G04 ================== begin FILE IDENTIFICATION RECORD ==================*
G04 Layout Name:  15126-1b.brd*
G04 Film Name:    SE_REF_L3*
G04 File Format:  Gerber RS274X*
G04 File Origin:  Cadence Allegro 16.6-2015-S079*
G04 Origin Date:  Fri Feb 10 17:23:33 2017*
G04 *
G04 Layer:  BOARD GEOMETRY/PANEL_OUTLINE*
G04 Layer:  BOARD GEOMETRY/SE_REF_L3_TBL*
G04 Layer:  BOARD GEOMETRY/SE_REF_L3_L3*
G04 *
G04 Offset:    (0.00 0.00)*
G04 Mirror:    No*
G04 Mode:      Positive*
G04 Rotation:  0*
G04 FullContactRelief:  No*
G04 UndefLineWidth:     6.00*
G04 ================== end FILE IDENTIFICATION RECORD ====================*
%FSLAX35Y35*MOIN*%
%IR0*IPPOS*OFA0.00000B0.00000*MIA0B0*SFA1.00000B1.00000*%
%ADD10C,.02*%
%ADD11C,.006*%
%ADD12C,.0035*%
%ADD13C,.00352*%
%ADD14C,.0056*%
G75*
%LPD*%
G75*
G54D10*
G01X2026678Y631398D02*
Y527448D01*
G01D02*
X2761678D01*
G01X2026678Y562098D02*
X2761678D01*
G01X2026678Y596748D02*
X2761678D01*
G01X2026678Y631398D02*
X2761678D01*
G01X2201678D02*
Y527448D01*
G01X2446678Y631398D02*
Y527448D01*
G01X2551678Y631398D02*
Y527448D01*
G01X2761678Y631398D02*
Y527448D01*
G54D11*
G01X-17372Y-95792D02*
Y-113292D01*
G01X-22394Y-95792D02*
X-12350D01*
G01X-3584Y-113292D02*
Y-95792D01*
G01Y-104250D02*
X-2492Y-102792D01*
X-1400Y-101917D01*
X346Y-101626D01*
X1656Y-101917D01*
X3185Y-103084D01*
X3840Y-104834D01*
Y-113292D01*
G01X17628Y-101626D02*
Y-113292D01*
G01Y-96959D02*
X17191Y-96667D01*
Y-96084D01*
X17628Y-95792D01*
X18065Y-96084D01*
Y-96667D01*
X17628Y-96959D01*
G01X31853Y-111251D02*
X32945Y-112417D01*
X34473Y-113292D01*
X35783D01*
X37093Y-112709D01*
X37966Y-111834D01*
X38403Y-110668D01*
X38185Y-108917D01*
X37311Y-108042D01*
X33381Y-106292D01*
X32508Y-104250D01*
X32945Y-102792D01*
X33818Y-101917D01*
X35128Y-101626D01*
X36438Y-101917D01*
X37748Y-102792D01*
G01X67071Y-117667D02*
X68600Y-118834D01*
X70346Y-119125D01*
X71874Y-118834D01*
X73185Y-117376D01*
X74058Y-115334D01*
Y-101626D01*
G01Y-103959D02*
X73185Y-102792D01*
X71874Y-101917D01*
X70346Y-101626D01*
X68600Y-102209D01*
X67508Y-103375D01*
X66634Y-105417D01*
X66198Y-107459D01*
X66416Y-109209D01*
X67290Y-111251D01*
X68600Y-112709D01*
X70346Y-113292D01*
X71656Y-113000D01*
X73185Y-111834D01*
X74058Y-110668D01*
G01X84353Y-105417D02*
X91340D01*
X90685Y-103375D01*
X89593Y-102209D01*
X88065Y-101626D01*
X86536Y-101917D01*
X85226Y-102792D01*
X84353Y-104834D01*
X83916Y-106584D01*
Y-108334D01*
X84353Y-110084D01*
X85445Y-111834D01*
X86755Y-113000D01*
X88283Y-113292D01*
X89811Y-112709D01*
X91340Y-110959D01*
G01X102071Y-113292D02*
Y-101626D01*
G01Y-103959D02*
X103163Y-102792D01*
X104255Y-101917D01*
X105783Y-101626D01*
X106874Y-101917D01*
X108185Y-102792D01*
G01X118698Y-113292D02*
Y-95792D01*
G01Y-104542D02*
X119790Y-102792D01*
X121100Y-101917D01*
X122410Y-101626D01*
X124374Y-102209D01*
X125685Y-103375D01*
X126558Y-105417D01*
Y-107750D01*
X126121Y-110084D01*
X125248Y-111834D01*
X123720Y-113000D01*
X122410Y-113292D01*
X121100Y-113000D01*
X119790Y-112126D01*
X118698Y-110668D01*
G01X136853Y-105417D02*
X143840D01*
X143185Y-103375D01*
X142093Y-102209D01*
X140565Y-101626D01*
X139036Y-101917D01*
X137726Y-102792D01*
X136853Y-104834D01*
X136416Y-106584D01*
Y-108334D01*
X136853Y-110084D01*
X137945Y-111834D01*
X139255Y-113000D01*
X140783Y-113292D01*
X142311Y-112709D01*
X143840Y-110959D01*
G01X154571Y-113292D02*
Y-101626D01*
G01Y-103959D02*
X155663Y-102792D01*
X156755Y-101917D01*
X158283Y-101626D01*
X159374Y-101917D01*
X160685Y-102792D01*
G01X192628Y-101626D02*
Y-113292D01*
G01Y-96959D02*
X192191Y-96667D01*
Y-96084D01*
X192628Y-95792D01*
X193065Y-96084D01*
Y-96667D01*
X192628Y-96959D01*
G01X206853Y-111251D02*
X207945Y-112417D01*
X209473Y-113292D01*
X210783D01*
X212093Y-112709D01*
X212966Y-111834D01*
X213403Y-110668D01*
X213185Y-108917D01*
X212311Y-108042D01*
X208381Y-106292D01*
X207508Y-104250D01*
X207945Y-102792D01*
X208818Y-101917D01*
X210128Y-101626D01*
X211438Y-101917D01*
X212748Y-102792D01*
G01X241634Y-117667D02*
X243163Y-118834D01*
X244473Y-119125D01*
X246220Y-118542D01*
X247530Y-117084D01*
X248185Y-114458D01*
Y-101626D01*
G01Y-96959D02*
X247748Y-96667D01*
Y-96084D01*
X248185Y-95792D01*
X248621Y-96084D01*
Y-96667D01*
X248185Y-96959D01*
G01X258916Y-101626D02*
Y-109792D01*
X259790Y-111834D01*
X261100Y-113000D01*
X262628Y-113292D01*
X264156Y-113000D01*
X265466Y-111834D01*
X266340Y-109792D01*
G01Y-113292D02*
Y-101626D01*
G01X276853Y-111251D02*
X277945Y-112417D01*
X279473Y-113292D01*
X280783D01*
X282093Y-112709D01*
X282966Y-111834D01*
X283403Y-110668D01*
X283185Y-108917D01*
X282311Y-108042D01*
X278381Y-106292D01*
X277508Y-104250D01*
X277945Y-102792D01*
X278818Y-101917D01*
X280128Y-101626D01*
X281438Y-101917D01*
X282748Y-102792D01*
G01X297628Y-95792D02*
Y-113292D01*
G01X294571Y-101626D02*
X300685D01*
G01X331318Y-113292D02*
Y-98417D01*
X331755Y-96959D01*
X332628Y-96084D01*
X333938Y-95792D01*
X335248Y-96375D01*
X335903Y-97834D01*
G01X333283Y-102792D02*
X328916D01*
G01X350128Y-113292D02*
X348818Y-113000D01*
X347508Y-111834D01*
X346634Y-109792D01*
X346198Y-107459D01*
X346634Y-105125D01*
X347508Y-103084D01*
X348818Y-101917D01*
X350128Y-101626D01*
X351438Y-101917D01*
X352748Y-103084D01*
X353621Y-105125D01*
X353840Y-107459D01*
X353621Y-109792D01*
X352748Y-111834D01*
X351438Y-113000D01*
X350128Y-113292D01*
G01X364571D02*
Y-101626D01*
G01Y-103959D02*
X365663Y-102792D01*
X366755Y-101917D01*
X368283Y-101626D01*
X369374Y-101917D01*
X370685Y-102792D01*
G01X398043Y-118542D02*
X399353Y-119125D01*
X401100Y-118542D01*
X402191Y-117376D01*
X403065Y-115917D01*
X404374Y-111251D01*
X407213Y-101626D01*
G01X400226D02*
X404374Y-111251D01*
G01X420128Y-113292D02*
X418818Y-113000D01*
X417508Y-111834D01*
X416634Y-109792D01*
X416198Y-107459D01*
X416634Y-105125D01*
X417508Y-103084D01*
X418818Y-101917D01*
X420128Y-101626D01*
X421438Y-101917D01*
X422748Y-103084D01*
X423621Y-105125D01*
X423840Y-107459D01*
X423621Y-109792D01*
X422748Y-111834D01*
X421438Y-113000D01*
X420128Y-113292D01*
G01X433916Y-101626D02*
Y-109792D01*
X434790Y-111834D01*
X436100Y-113000D01*
X437628Y-113292D01*
X439156Y-113000D01*
X440466Y-111834D01*
X441340Y-109792D01*
G01Y-113292D02*
Y-101626D01*
G01X452071Y-113292D02*
Y-101626D01*
G01Y-103959D02*
X453163Y-102792D01*
X454255Y-101917D01*
X455783Y-101626D01*
X456874Y-101917D01*
X458185Y-102792D01*
G01X487071Y-113292D02*
Y-101626D01*
G01Y-103959D02*
X488163Y-102792D01*
X489255Y-101917D01*
X490783Y-101626D01*
X491874Y-101917D01*
X493185Y-102792D01*
G01X504353Y-105417D02*
X511340D01*
X510685Y-103375D01*
X509593Y-102209D01*
X508065Y-101626D01*
X506536Y-101917D01*
X505226Y-102792D01*
X504353Y-104834D01*
X503916Y-106584D01*
Y-108334D01*
X504353Y-110084D01*
X505445Y-111834D01*
X506755Y-113000D01*
X508283Y-113292D01*
X509811Y-112709D01*
X511340Y-110959D01*
G01X523818Y-113292D02*
Y-98417D01*
X524255Y-96959D01*
X525128Y-96084D01*
X526438Y-95792D01*
X527748Y-96375D01*
X528403Y-97834D01*
G01X525783Y-102792D02*
X521416D01*
G01X539353Y-105417D02*
X546340D01*
X545685Y-103375D01*
X544593Y-102209D01*
X543065Y-101626D01*
X541536Y-101917D01*
X540226Y-102792D01*
X539353Y-104834D01*
X538916Y-106584D01*
Y-108334D01*
X539353Y-110084D01*
X540445Y-111834D01*
X541755Y-113000D01*
X543283Y-113292D01*
X544811Y-112709D01*
X546340Y-110959D01*
G01X557071Y-113292D02*
Y-101626D01*
G01Y-103959D02*
X558163Y-102792D01*
X559255Y-101917D01*
X560783Y-101626D01*
X561874Y-101917D01*
X563185Y-102792D01*
G01X574353Y-105417D02*
X581340D01*
X580685Y-103375D01*
X579593Y-102209D01*
X578065Y-101626D01*
X576536Y-101917D01*
X575226Y-102792D01*
X574353Y-104834D01*
X573916Y-106584D01*
Y-108334D01*
X574353Y-110084D01*
X575445Y-111834D01*
X576755Y-113000D01*
X578283Y-113292D01*
X579811Y-112709D01*
X581340Y-110959D01*
G01X591416Y-113292D02*
Y-101626D01*
G01Y-104542D02*
X592290Y-103084D01*
X593600Y-101917D01*
X595346Y-101626D01*
X596874Y-101917D01*
X598185Y-103084D01*
X598840Y-105125D01*
Y-113292D01*
G01X616121Y-103084D02*
X614593Y-101917D01*
X613283Y-101626D01*
X611536Y-102209D01*
X610226Y-103375D01*
X609353Y-105417D01*
X609134Y-107459D01*
X609353Y-109501D01*
X610226Y-111251D01*
X611536Y-112709D01*
X613283Y-113292D01*
X614811Y-112709D01*
X616121Y-111542D01*
G01X626853Y-105417D02*
X633840D01*
X633185Y-103375D01*
X632093Y-102209D01*
X630565Y-101626D01*
X629036Y-101917D01*
X627726Y-102792D01*
X626853Y-104834D01*
X626416Y-106584D01*
Y-108334D01*
X626853Y-110084D01*
X627945Y-111834D01*
X629255Y-113000D01*
X630783Y-113292D01*
X632311Y-112709D01*
X633840Y-110959D01*
G01X665128Y-95792D02*
Y-113292D01*
G01X662071Y-101626D02*
X668185D01*
G01X682628Y-113292D02*
X681318Y-113000D01*
X680008Y-111834D01*
X679134Y-109792D01*
X678698Y-107459D01*
X679134Y-105125D01*
X680008Y-103084D01*
X681318Y-101917D01*
X682628Y-101626D01*
X683938Y-101917D01*
X685248Y-103084D01*
X686121Y-105125D01*
X686340Y-107459D01*
X686121Y-109792D01*
X685248Y-111834D01*
X683938Y-113000D01*
X682628Y-113292D01*
G01X716318D02*
Y-98417D01*
X716755Y-96959D01*
X717628Y-96084D01*
X718938Y-95792D01*
X720248Y-96375D01*
X720903Y-97834D01*
G01X718283Y-102792D02*
X713916D01*
G01X735128Y-101626D02*
Y-113292D01*
G01Y-96959D02*
X734691Y-96667D01*
Y-96084D01*
X735128Y-95792D01*
X735565Y-96084D01*
Y-96667D01*
X735128Y-96959D01*
G01X748916Y-113292D02*
Y-101626D01*
G01Y-104542D02*
X749790Y-103084D01*
X751100Y-101917D01*
X752846Y-101626D01*
X754374Y-101917D01*
X755685Y-103084D01*
X756340Y-105125D01*
Y-113292D01*
G01X774058Y-95792D02*
Y-113292D01*
G01Y-110668D02*
X773185Y-112126D01*
X771874Y-113000D01*
X770346Y-113292D01*
X768600Y-112709D01*
X767290Y-111251D01*
X766416Y-109501D01*
X766198Y-107459D01*
X766416Y-105417D01*
X767290Y-103667D01*
X768600Y-102209D01*
X770346Y-101626D01*
X771874Y-101917D01*
X772966Y-102501D01*
X774058Y-103667D01*
G01X805128Y-95792D02*
Y-113292D01*
G01X802071Y-101626D02*
X808185D01*
G01X818916Y-113292D02*
Y-95792D01*
G01Y-104250D02*
X820008Y-102792D01*
X821100Y-101917D01*
X822846Y-101626D01*
X824156Y-101917D01*
X825685Y-103084D01*
X826340Y-104834D01*
Y-113292D01*
G01X836853Y-105417D02*
X843840D01*
X843185Y-103375D01*
X842093Y-102209D01*
X840565Y-101626D01*
X839036Y-101917D01*
X837726Y-102792D01*
X836853Y-104834D01*
X836416Y-106584D01*
Y-108334D01*
X836853Y-110084D01*
X837945Y-111834D01*
X839255Y-113000D01*
X840783Y-113292D01*
X842311Y-112709D01*
X843840Y-110959D01*
G01X870543D02*
X872290Y-112417D01*
X874255Y-113292D01*
X876001D01*
X877748Y-112417D01*
X879058Y-110959D01*
X879713Y-108917D01*
X879276Y-106876D01*
X878185Y-105125D01*
X876220Y-103959D01*
X873600Y-103375D01*
X872071Y-102209D01*
X871416Y-100167D01*
X871853Y-98125D01*
X872945Y-96667D01*
X874473Y-95792D01*
X876001D01*
X877530Y-96375D01*
X878840Y-97834D01*
G01X896995Y-113292D02*
X888261D01*
Y-95792D01*
X896995D01*
G01X893501Y-104250D02*
X888261D01*
G01X927628Y-101626D02*
Y-113292D01*
G01Y-96959D02*
X927191Y-96667D01*
Y-96084D01*
X927628Y-95792D01*
X928065Y-96084D01*
Y-96667D01*
X927628Y-96959D01*
G01X938578Y-113292D02*
Y-101626D01*
G01Y-104834D02*
X939233Y-103375D01*
X940325Y-102209D01*
X941853Y-101626D01*
X943381Y-102209D01*
X944473Y-103375D01*
X945128Y-104834D01*
Y-113292D01*
G01Y-104834D02*
X945783Y-103375D01*
X946874Y-102209D01*
X948403Y-101626D01*
X949931Y-102209D01*
X951023Y-103375D01*
X951678Y-105125D01*
Y-113292D01*
G01X958698Y-119125D02*
Y-101626D01*
G01Y-104250D02*
X959790Y-102792D01*
X960881Y-101917D01*
X962628Y-101626D01*
X964156Y-101917D01*
X965685Y-103375D01*
X966340Y-105417D01*
X966558Y-107459D01*
X966340Y-109501D01*
X965685Y-111542D01*
X964374Y-112709D01*
X962628Y-113292D01*
X961100Y-113000D01*
X959571Y-112126D01*
X958698Y-110959D01*
G01X976853Y-105417D02*
X983840D01*
X983185Y-103375D01*
X982093Y-102209D01*
X980565Y-101626D01*
X979036Y-101917D01*
X977726Y-102792D01*
X976853Y-104834D01*
X976416Y-106584D01*
Y-108334D01*
X976853Y-110084D01*
X977945Y-111834D01*
X979255Y-113000D01*
X980783Y-113292D01*
X982311Y-112709D01*
X983840Y-110959D01*
G01X1001558Y-95792D02*
Y-113292D01*
G01Y-110668D02*
X1000685Y-112126D01*
X999374Y-113000D01*
X997846Y-113292D01*
X996100Y-112709D01*
X994790Y-111251D01*
X993916Y-109501D01*
X993698Y-107459D01*
X993916Y-105417D01*
X994790Y-103667D01*
X996100Y-102209D01*
X997846Y-101626D01*
X999374Y-101917D01*
X1000466Y-102501D01*
X1001558Y-103667D01*
G01X1019058Y-113292D02*
Y-101626D01*
G01Y-103667D02*
X1018185Y-102501D01*
X1016874Y-101917D01*
X1015346Y-101626D01*
X1013818Y-102209D01*
X1012508Y-103375D01*
X1011634Y-105125D01*
X1011198Y-107459D01*
X1011634Y-109792D01*
X1012508Y-111542D01*
X1013818Y-112709D01*
X1015346Y-113292D01*
X1016874Y-113000D01*
X1018185Y-112126D01*
X1019058Y-110959D01*
G01X1028916Y-113292D02*
Y-101626D01*
G01Y-104542D02*
X1029790Y-103084D01*
X1031100Y-101917D01*
X1032846Y-101626D01*
X1034374Y-101917D01*
X1035685Y-103084D01*
X1036340Y-105125D01*
Y-113292D01*
G01X1053621Y-103084D02*
X1052093Y-101917D01*
X1050783Y-101626D01*
X1049036Y-102209D01*
X1047726Y-103375D01*
X1046853Y-105417D01*
X1046634Y-107459D01*
X1046853Y-109501D01*
X1047726Y-111251D01*
X1049036Y-112709D01*
X1050783Y-113292D01*
X1052311Y-112709D01*
X1053621Y-111542D01*
G01X1064353Y-105417D02*
X1071340D01*
X1070685Y-103375D01*
X1069593Y-102209D01*
X1068065Y-101626D01*
X1066536Y-101917D01*
X1065226Y-102792D01*
X1064353Y-104834D01*
X1063916Y-106584D01*
Y-108334D01*
X1064353Y-110084D01*
X1065445Y-111834D01*
X1066755Y-113000D01*
X1068283Y-113292D01*
X1069811Y-112709D01*
X1071340Y-110959D01*
G01X1102628Y-95792D02*
Y-113292D01*
G01X1099571Y-101626D02*
X1105685D01*
G01X1117071Y-113292D02*
Y-101626D01*
G01Y-103959D02*
X1118163Y-102792D01*
X1119255Y-101917D01*
X1120783Y-101626D01*
X1121874Y-101917D01*
X1123185Y-102792D01*
G01X1141558Y-113292D02*
Y-101626D01*
G01Y-103667D02*
X1140685Y-102501D01*
X1139374Y-101917D01*
X1137846Y-101626D01*
X1136318Y-102209D01*
X1135008Y-103375D01*
X1134134Y-105125D01*
X1133698Y-107459D01*
X1134134Y-109792D01*
X1135008Y-111542D01*
X1136318Y-112709D01*
X1137846Y-113292D01*
X1139374Y-113000D01*
X1140685Y-112126D01*
X1141558Y-110959D01*
G01X1158621Y-103084D02*
X1157093Y-101917D01*
X1155783Y-101626D01*
X1154036Y-102209D01*
X1152726Y-103375D01*
X1151853Y-105417D01*
X1151634Y-107459D01*
X1151853Y-109501D01*
X1152726Y-111251D01*
X1154036Y-112709D01*
X1155783Y-113292D01*
X1157311Y-112709D01*
X1158621Y-111542D01*
G01X1169353Y-105417D02*
X1176340D01*
X1175685Y-103375D01*
X1174593Y-102209D01*
X1173065Y-101626D01*
X1171536Y-101917D01*
X1170226Y-102792D01*
X1169353Y-104834D01*
X1168916Y-106584D01*
Y-108334D01*
X1169353Y-110084D01*
X1170445Y-111834D01*
X1171755Y-113000D01*
X1173283Y-113292D01*
X1174811Y-112709D01*
X1176340Y-110959D01*
G01X1186853Y-111251D02*
X1187945Y-112417D01*
X1189473Y-113292D01*
X1190783D01*
X1192093Y-112709D01*
X1192966Y-111834D01*
X1193403Y-110668D01*
X1193185Y-108917D01*
X1192311Y-108042D01*
X1188381Y-106292D01*
X1187508Y-104250D01*
X1187945Y-102792D01*
X1188818Y-101917D01*
X1190128Y-101626D01*
X1191438Y-101917D01*
X1192748Y-102792D01*
G01X1225128Y-101626D02*
Y-113292D01*
G01Y-96959D02*
X1224691Y-96667D01*
Y-96084D01*
X1225128Y-95792D01*
X1225565Y-96084D01*
Y-96667D01*
X1225128Y-96959D01*
G01X1238916Y-113292D02*
Y-101626D01*
G01Y-104542D02*
X1239790Y-103084D01*
X1241100Y-101917D01*
X1242846Y-101626D01*
X1244374Y-101917D01*
X1245685Y-103084D01*
X1246340Y-105125D01*
Y-113292D01*
G01X1277628D02*
Y-95792D01*
G01X1299058Y-113292D02*
Y-101626D01*
G01Y-103667D02*
X1298185Y-102501D01*
X1296874Y-101917D01*
X1295346Y-101626D01*
X1293818Y-102209D01*
X1292508Y-103375D01*
X1291634Y-105125D01*
X1291198Y-107459D01*
X1291634Y-109792D01*
X1292508Y-111542D01*
X1293818Y-112709D01*
X1295346Y-113292D01*
X1296874Y-113000D01*
X1298185Y-112126D01*
X1299058Y-110959D01*
G01X1308043Y-118542D02*
X1309353Y-119125D01*
X1311100Y-118542D01*
X1312191Y-117376D01*
X1313065Y-115917D01*
X1314374Y-111251D01*
X1317213Y-101626D01*
G01X1310226D02*
X1314374Y-111251D01*
G01X1326853Y-105417D02*
X1333840D01*
X1333185Y-103375D01*
X1332093Y-102209D01*
X1330565Y-101626D01*
X1329036Y-101917D01*
X1327726Y-102792D01*
X1326853Y-104834D01*
X1326416Y-106584D01*
Y-108334D01*
X1326853Y-110084D01*
X1327945Y-111834D01*
X1329255Y-113000D01*
X1330783Y-113292D01*
X1332311Y-112709D01*
X1333840Y-110959D01*
G01X1344571Y-113292D02*
Y-101626D01*
G01Y-103959D02*
X1345663Y-102792D01*
X1346755Y-101917D01*
X1348283Y-101626D01*
X1349374Y-101917D01*
X1350685Y-102792D01*
G01X1378261Y-95792D02*
Y-113292D01*
X1386995D01*
G01X1395325Y-109792D02*
X1396634Y-111834D01*
X1398381Y-113000D01*
X1400346Y-113292D01*
X1402093Y-113000D01*
X1403840Y-111542D01*
X1404931Y-109792D01*
X1405150Y-108042D01*
X1404713Y-106001D01*
X1403185Y-104542D01*
X1401656Y-103959D01*
X1399691D01*
G01X1401656D02*
X1402966Y-103084D01*
X1404058Y-101626D01*
X1404495Y-99876D01*
X1404058Y-98125D01*
X1402966Y-96667D01*
X1401001Y-95792D01*
X1399036Y-96084D01*
X1397071Y-97251D01*
G01X1417628Y-113875D02*
X1417191Y-113584D01*
Y-113000D01*
X1417628Y-112709D01*
X1418065Y-113000D01*
Y-113584D01*
X1417628Y-113875D01*
G01X2083125Y539822D02*
X2084434Y538364D01*
X2085963Y537490D01*
X2087928Y537198D01*
X2089893Y537781D01*
X2091421Y538948D01*
X2092513Y540989D01*
X2092731Y543323D01*
X2092295Y545656D01*
X2091203Y547115D01*
X2089674Y548281D01*
X2088146Y548573D01*
X2086618Y548281D01*
X2084653Y547115D01*
X2085308Y554698D01*
X2091203D01*
G01X2105428D02*
X2103681Y554115D01*
X2102371Y552656D01*
X2101498Y550907D01*
X2100843Y548573D01*
X2100625Y545948D01*
X2100843Y543323D01*
X2101498Y540989D01*
X2102371Y539239D01*
X2103681Y537781D01*
X2105428Y537198D01*
X2107174Y537781D01*
X2108485Y539239D01*
X2109358Y540989D01*
X2110013Y543323D01*
X2110231Y545948D01*
X2110013Y548573D01*
X2109358Y550907D01*
X2108485Y552656D01*
X2107174Y554115D01*
X2105428Y554698D01*
G01X2122928Y536615D02*
X2122491Y536906D01*
Y537490D01*
X2122928Y537781D01*
X2123365Y537490D01*
Y536906D01*
X2122928Y536615D01*
G01X2140428Y554698D02*
X2138681Y554115D01*
X2137371Y552656D01*
X2136498Y550907D01*
X2135843Y548573D01*
X2135625Y545948D01*
X2135843Y543323D01*
X2136498Y540989D01*
X2137371Y539239D01*
X2138681Y537781D01*
X2140428Y537198D01*
X2142174Y537781D01*
X2143485Y539239D01*
X2144358Y540989D01*
X2145013Y543323D01*
X2145231Y545948D01*
X2145013Y548573D01*
X2144358Y550907D01*
X2143485Y552656D01*
X2142174Y554115D01*
X2140428Y554698D01*
G01X2090548Y571848D02*
Y589348D01*
X2082469Y576806D01*
X2093387D01*
G01X2105428Y589348D02*
X2103681Y588765D01*
X2102371Y587306D01*
X2101498Y585557D01*
X2100843Y583223D01*
X2100625Y580598D01*
X2100843Y577973D01*
X2101498Y575639D01*
X2102371Y573889D01*
X2103681Y572431D01*
X2105428Y571848D01*
X2107174Y572431D01*
X2108485Y573889D01*
X2109358Y575639D01*
X2110013Y577973D01*
X2110231Y580598D01*
X2110013Y583223D01*
X2109358Y585557D01*
X2108485Y587306D01*
X2107174Y588765D01*
X2105428Y589348D01*
G01X2122928Y571265D02*
X2122491Y571556D01*
Y572140D01*
X2122928Y572431D01*
X2123365Y572140D01*
Y571556D01*
X2122928Y571265D01*
G01X2140428Y589348D02*
X2138681Y588765D01*
X2137371Y587306D01*
X2136498Y585557D01*
X2135843Y583223D01*
X2135625Y580598D01*
X2135843Y577973D01*
X2136498Y575639D01*
X2137371Y573889D01*
X2138681Y572431D01*
X2140428Y571848D01*
X2142174Y572431D01*
X2143485Y573889D01*
X2144358Y575639D01*
X2145013Y577973D01*
X2145231Y580598D01*
X2145013Y583223D01*
X2144358Y585557D01*
X2143485Y587306D01*
X2142174Y588765D01*
X2140428Y589348D01*
G01X2050308Y623998D02*
X2055548D01*
G01X2052928D02*
Y606498D01*
G01X2050308D02*
X2055548D01*
G01X2064751D02*
Y623998D01*
X2070428Y609415D01*
X2076105Y623998D01*
Y606498D01*
G01X2083561D02*
Y623998D01*
X2088801D01*
X2090548Y623123D01*
X2091858Y621081D01*
X2092295Y618748D01*
X2091858Y616415D01*
X2090766Y614665D01*
X2088801Y613789D01*
X2083561D01*
G01X2104336Y600665D02*
X2102153Y603581D01*
X2101061Y606498D01*
Y618164D01*
X2102153Y621081D01*
X2104336Y623998D01*
G01X2122928Y606498D02*
X2121181Y606790D01*
X2119653Y607956D01*
X2118343Y609706D01*
X2117469Y611748D01*
X2117033Y614081D01*
Y616415D01*
X2117469Y618748D01*
X2118343Y620790D01*
X2119653Y622539D01*
X2121181Y623706D01*
X2122928Y623998D01*
X2124674Y623706D01*
X2126203Y622539D01*
X2127513Y620790D01*
X2128387Y618748D01*
X2128823Y616415D01*
Y614081D01*
X2128387Y611748D01*
X2127513Y609706D01*
X2126203Y607956D01*
X2124674Y606790D01*
X2122928Y606498D01*
G01X2136716D02*
Y623998D01*
G01Y615540D02*
X2137808Y616998D01*
X2138900Y617873D01*
X2140646Y618164D01*
X2141956Y617873D01*
X2143485Y616706D01*
X2144140Y614956D01*
Y606498D01*
G01X2151378D02*
Y618164D01*
G01Y614956D02*
X2152033Y616415D01*
X2153125Y617581D01*
X2154653Y618164D01*
X2156181Y617581D01*
X2157273Y616415D01*
X2157928Y614956D01*
Y606498D01*
G01Y614956D02*
X2158583Y616415D01*
X2159674Y617581D01*
X2161203Y618164D01*
X2162731Y617581D01*
X2163823Y616415D01*
X2164478Y614665D01*
Y606498D01*
G01X2176520Y600665D02*
X2178703Y603581D01*
X2179795Y606498D01*
Y618164D01*
X2178703Y621081D01*
X2176520Y623998D01*
G01X2028643Y643481D02*
X2030390Y642023D01*
X2032355Y641148D01*
X2034101D01*
X2035848Y642023D01*
X2037158Y643481D01*
X2037813Y645523D01*
X2037376Y647564D01*
X2036285Y649315D01*
X2034320Y650481D01*
X2031700Y651065D01*
X2030171Y652231D01*
X2029516Y654273D01*
X2029953Y656315D01*
X2031045Y657773D01*
X2032573Y658648D01*
X2034101D01*
X2035630Y658065D01*
X2036940Y656606D01*
G01X2055095Y641148D02*
X2046361D01*
Y658648D01*
X2055095D01*
G01X2051601Y650190D02*
X2046361D01*
G01X2083108Y658648D02*
X2088348D01*
G01X2085728D02*
Y641148D01*
G01X2083108D02*
X2088348D01*
G01X2097551D02*
Y658648D01*
X2103228Y644065D01*
X2108905Y658648D01*
Y641148D01*
G01X2116361D02*
Y658648D01*
X2121601D01*
X2123348Y657773D01*
X2124658Y655731D01*
X2125095Y653398D01*
X2124658Y651065D01*
X2123566Y649315D01*
X2121601Y648439D01*
X2116361D01*
G01X2142595Y641148D02*
X2133861D01*
Y658648D01*
X2142595D01*
G01X2139101Y650190D02*
X2133861D01*
G01X2150925Y641148D02*
Y658648D01*
X2155291D01*
X2157038Y657773D01*
X2158348Y656606D01*
X2159440Y654857D01*
X2160313Y652814D01*
X2160531Y649898D01*
X2160313Y646981D01*
X2159440Y644939D01*
X2158348Y643189D01*
X2157038Y642023D01*
X2155291Y641148D01*
X2150925D01*
G01X2167769D02*
X2173228Y658648D01*
X2178687Y641148D01*
G01X2176721Y647273D02*
X2169734D01*
G01X2185706Y641148D02*
Y658648D01*
X2195750Y641148D01*
Y658648D01*
G01X2213031Y657189D02*
X2211721Y658065D01*
X2210193Y658648D01*
X2208446D01*
X2206481Y657773D01*
X2204953Y656315D01*
X2203861Y654564D01*
X2202988Y651648D01*
X2202769Y649023D01*
X2203206Y646398D01*
X2203861Y644648D01*
X2205171Y642898D01*
X2206700Y641731D01*
X2208228Y641148D01*
X2209756D01*
X2211285Y641731D01*
X2212595Y642606D01*
X2213687Y643772D01*
G01X2230095Y641148D02*
X2221361D01*
Y658648D01*
X2230095D01*
G01X2226601Y650190D02*
X2221361D01*
G01X2260728Y658648D02*
Y641148D01*
G01X2255706Y658648D02*
X2265750D01*
G01X2272769Y641148D02*
X2278228Y658648D01*
X2283687Y641148D01*
G01X2281721Y647273D02*
X2274734D01*
G01X2297474Y650481D02*
X2298348Y651356D01*
X2299003Y652814D01*
X2299440Y654857D01*
X2299003Y656606D01*
X2298130Y657773D01*
X2296601Y658648D01*
X2290706D01*
Y641148D01*
X2297911D01*
X2299440Y642314D01*
X2300313Y644065D01*
X2300750Y646106D01*
X2300313Y648148D01*
X2299003Y649898D01*
X2297474Y650481D01*
X2290706D01*
G01X2308861Y658648D02*
Y641148D01*
X2317595D01*
G01X2335095D02*
X2326361D01*
Y658648D01*
X2335095D01*
G01X2331601Y650190D02*
X2326361D01*
G01X2348228Y640565D02*
X2347791Y640856D01*
Y641440D01*
X2348228Y641731D01*
X2348665Y641440D01*
Y640856D01*
X2348228Y640565D01*
G01Y648439D02*
X2347791Y648731D01*
Y649315D01*
X2348228Y649606D01*
X2348665Y649315D01*
Y648731D01*
X2348228Y648439D01*
G01X2378861Y658648D02*
Y641148D01*
X2387595D01*
G01X2395925Y644648D02*
X2397234Y642606D01*
X2398981Y641440D01*
X2400946Y641148D01*
X2402693Y641440D01*
X2404440Y642898D01*
X2405531Y644648D01*
X2405750Y646398D01*
X2405313Y648439D01*
X2403785Y649898D01*
X2402256Y650481D01*
X2400291D01*
G01X2402256D02*
X2403566Y651356D01*
X2404658Y652814D01*
X2405095Y654564D01*
X2404658Y656315D01*
X2403566Y657773D01*
X2401601Y658648D01*
X2399636Y658356D01*
X2397671Y657189D01*
G01X2230128Y623998D02*
X2233184Y606498D01*
X2236678Y623998D01*
X2240171Y606498D01*
X2243228Y623998D01*
G01X2251558D02*
X2256798D01*
G01X2254178D02*
Y606498D01*
G01X2251558D02*
X2256798D01*
G01X2266875D02*
Y623998D01*
X2271241D01*
X2272988Y623123D01*
X2274298Y621956D01*
X2275390Y620207D01*
X2276263Y618164D01*
X2276481Y615248D01*
X2276263Y612331D01*
X2275390Y610289D01*
X2274298Y608539D01*
X2272988Y607373D01*
X2271241Y606498D01*
X2266875D01*
G01X2289178Y623998D02*
Y606498D01*
G01X2284156Y623998D02*
X2294200D01*
G01X2302093Y606498D02*
Y623998D01*
G01X2311263D02*
Y606498D01*
G01Y615248D02*
X2302093D01*
G01X2323086Y600665D02*
X2320903Y603581D01*
X2319811Y606498D01*
Y618164D01*
X2320903Y621081D01*
X2323086Y623998D01*
G01X2335128Y606498D02*
Y618164D01*
G01Y614956D02*
X2335783Y616415D01*
X2336875Y617581D01*
X2338403Y618164D01*
X2339931Y617581D01*
X2341023Y616415D01*
X2341678Y614956D01*
Y606498D01*
G01Y614956D02*
X2342333Y616415D01*
X2343424Y617581D01*
X2344953Y618164D01*
X2346481Y617581D01*
X2347573Y616415D01*
X2348228Y614665D01*
Y606498D01*
G01X2359178Y618164D02*
Y606498D01*
G01Y622831D02*
X2358741Y623123D01*
Y623706D01*
X2359178Y623998D01*
X2359615Y623706D01*
Y623123D01*
X2359178Y622831D01*
G01X2376678Y606498D02*
Y623998D01*
G01X2390903Y608539D02*
X2391995Y607373D01*
X2393523Y606498D01*
X2394833D01*
X2396143Y607081D01*
X2397016Y607956D01*
X2397453Y609122D01*
X2397235Y610873D01*
X2396361Y611748D01*
X2392431Y613498D01*
X2391558Y615540D01*
X2391995Y616998D01*
X2392868Y617873D01*
X2394178Y618164D01*
X2395488Y617873D01*
X2396798Y616998D01*
G01X2412770Y600665D02*
X2414953Y603581D01*
X2416045Y606498D01*
Y618164D01*
X2414953Y621081D01*
X2412770Y623998D01*
G01X2293125Y540698D02*
X2294434Y538656D01*
X2296181Y537490D01*
X2298146Y537198D01*
X2299893Y537490D01*
X2301640Y538948D01*
X2302731Y540698D01*
X2302950Y542448D01*
X2302513Y544489D01*
X2300985Y545948D01*
X2299456Y546531D01*
X2297491D01*
G01X2299456D02*
X2300766Y547406D01*
X2301858Y548864D01*
X2302295Y550614D01*
X2301858Y552365D01*
X2300766Y553823D01*
X2298801Y554698D01*
X2296836Y554406D01*
X2294871Y553239D01*
G01X2315428Y536615D02*
X2314991Y536906D01*
Y537490D01*
X2315428Y537781D01*
X2315865Y537490D01*
Y536906D01*
X2315428Y536615D01*
G01X2328125Y539822D02*
X2329434Y538364D01*
X2330963Y537490D01*
X2332928Y537198D01*
X2334893Y537781D01*
X2336421Y538948D01*
X2337513Y540989D01*
X2337731Y543323D01*
X2337295Y545656D01*
X2336203Y547115D01*
X2334674Y548281D01*
X2333146Y548573D01*
X2331618Y548281D01*
X2329653Y547115D01*
X2330308Y554698D01*
X2336203D01*
G01X2346280Y551781D02*
X2347590Y553531D01*
X2349118Y554406D01*
X2350865Y554698D01*
X2353048Y554115D01*
X2354576Y552656D01*
X2355013Y550907D01*
X2354795Y549156D01*
X2353921Y547698D01*
X2349555Y544781D01*
X2347590Y542740D01*
X2346280Y539822D01*
X2345843Y537198D01*
X2355013D01*
G01X2301875Y574472D02*
X2303184Y573014D01*
X2304713Y572140D01*
X2306678Y571848D01*
X2308643Y572431D01*
X2310171Y573598D01*
X2311263Y575639D01*
X2311481Y577973D01*
X2311045Y580306D01*
X2309953Y581765D01*
X2308424Y582931D01*
X2306896Y583223D01*
X2305368Y582931D01*
X2303403Y581765D01*
X2304058Y589348D01*
X2309953D01*
G01X2324178Y571265D02*
X2323741Y571556D01*
Y572140D01*
X2324178Y572431D01*
X2324615Y572140D01*
Y571556D01*
X2324178Y571265D01*
G01X2337530Y579139D02*
X2339058Y581181D01*
X2340368Y582348D01*
X2342115Y582931D01*
X2343643Y582348D01*
X2344735Y581181D01*
X2345608Y579431D01*
X2345826Y577390D01*
X2345608Y575639D01*
X2344735Y573889D01*
X2343424Y572431D01*
X2341896Y571848D01*
X2340150Y572431D01*
X2338621Y574181D01*
X2337748Y576806D01*
X2337530Y579723D01*
X2337966Y583514D01*
X2338621Y585557D01*
X2339713Y587598D01*
X2341241Y589056D01*
X2342770Y589348D01*
X2344298Y588765D01*
X2345390Y587306D01*
G01X2485843Y539531D02*
X2487590Y538073D01*
X2489555Y537198D01*
X2491301D01*
X2493048Y538073D01*
X2494358Y539531D01*
X2495013Y541573D01*
X2494576Y543614D01*
X2493485Y545365D01*
X2491520Y546531D01*
X2488900Y547115D01*
X2487371Y548281D01*
X2486716Y550323D01*
X2487153Y552365D01*
X2488245Y553823D01*
X2489773Y554698D01*
X2491301D01*
X2492830Y554115D01*
X2494140Y552656D01*
G01X2512295Y537198D02*
X2503561D01*
Y554698D01*
X2512295D01*
G01X2508801Y546240D02*
X2503561D01*
G01X2485843Y574181D02*
X2487590Y572723D01*
X2489555Y571848D01*
X2491301D01*
X2493048Y572723D01*
X2494358Y574181D01*
X2495013Y576223D01*
X2494576Y578264D01*
X2493485Y580015D01*
X2491520Y581181D01*
X2488900Y581765D01*
X2487371Y582931D01*
X2486716Y584973D01*
X2487153Y587015D01*
X2488245Y588473D01*
X2489773Y589348D01*
X2491301D01*
X2492830Y588765D01*
X2494140Y587306D01*
G01X2512295Y571848D02*
X2503561D01*
Y589348D01*
X2512295D01*
G01X2508801Y580890D02*
X2503561D01*
G01X2472928Y623998D02*
Y606498D01*
G01X2467906Y623998D02*
X2477950D01*
G01X2490428Y606498D02*
Y614373D01*
X2486061Y623998D01*
G01X2494795D02*
X2490428Y614373D01*
G01X2503561Y606498D02*
Y623998D01*
X2508801D01*
X2510548Y623123D01*
X2511858Y621081D01*
X2512295Y618748D01*
X2511858Y616415D01*
X2510766Y614665D01*
X2508801Y613789D01*
X2503561D01*
G01X2529795Y606498D02*
X2521061D01*
Y623998D01*
X2529795D01*
G01X2526301Y615540D02*
X2521061D01*
G01X2573561Y606498D02*
Y623998D01*
X2579020D01*
X2580766Y623123D01*
X2581858Y621956D01*
X2582295Y619623D01*
X2581858Y617289D01*
X2580548Y615831D01*
X2579020Y614956D01*
X2573561D01*
G01X2579020D02*
X2582295Y606498D01*
G01X2592153Y614373D02*
X2599140D01*
X2598485Y616415D01*
X2597393Y617581D01*
X2595865Y618164D01*
X2594336Y617873D01*
X2593026Y616998D01*
X2592153Y614956D01*
X2591716Y613206D01*
Y611456D01*
X2592153Y609706D01*
X2593245Y607956D01*
X2594555Y606790D01*
X2596083Y606498D01*
X2597611Y607081D01*
X2599140Y608831D01*
G01X2611618Y606498D02*
Y621373D01*
X2612055Y622831D01*
X2612928Y623706D01*
X2614238Y623998D01*
X2615548Y623415D01*
X2616203Y621956D01*
G01X2613583Y616998D02*
X2609216D01*
G01X2630428Y605915D02*
X2629991Y606206D01*
Y606790D01*
X2630428Y607081D01*
X2630865Y606790D01*
Y606206D01*
X2630428Y605915D01*
G01X2661061Y606498D02*
Y623998D01*
X2666301D01*
X2668048Y623123D01*
X2669358Y621081D01*
X2669795Y618748D01*
X2669358Y616415D01*
X2668266Y614665D01*
X2666301Y613789D01*
X2661061D01*
G01X2682928Y606498D02*
Y623998D01*
G01X2704358Y606498D02*
Y618164D01*
G01Y616123D02*
X2703485Y617289D01*
X2702174Y617873D01*
X2700646Y618164D01*
X2699118Y617581D01*
X2697808Y616415D01*
X2696934Y614665D01*
X2696498Y612331D01*
X2696934Y609998D01*
X2697808Y608248D01*
X2699118Y607081D01*
X2700646Y606498D01*
X2702174Y606790D01*
X2703485Y607664D01*
X2704358Y608831D01*
G01X2714216Y606498D02*
Y618164D01*
G01Y615248D02*
X2715090Y616706D01*
X2716400Y617873D01*
X2718146Y618164D01*
X2719674Y617873D01*
X2720985Y616706D01*
X2721640Y614665D01*
Y606498D01*
G01X2732153Y614373D02*
X2739140D01*
X2738485Y616415D01*
X2737393Y617581D01*
X2735865Y618164D01*
X2734336Y617873D01*
X2733026Y616998D01*
X2732153Y614956D01*
X2731716Y613206D01*
Y611456D01*
X2732153Y609706D01*
X2733245Y607956D01*
X2734555Y606790D01*
X2736083Y606498D01*
X2737611Y607081D01*
X2739140Y608831D01*
G01X2617311Y554698D02*
Y537198D01*
X2626045D01*
G01X2635030Y551781D02*
X2636340Y553531D01*
X2637868Y554406D01*
X2639615Y554698D01*
X2641798Y554115D01*
X2643326Y552656D01*
X2643763Y550907D01*
X2643545Y549156D01*
X2642671Y547698D01*
X2638305Y544781D01*
X2636340Y542740D01*
X2635030Y539822D01*
X2634593Y537198D01*
X2643763D01*
G01X2652748Y536615D02*
X2660608Y554698D01*
G01X2669811D02*
Y537198D01*
X2678545D01*
G01X2694298D02*
Y554698D01*
X2686219Y542156D01*
X2697137D01*
G01X2617311Y589348D02*
Y571848D01*
X2626045D01*
G01X2635030Y586431D02*
X2636340Y588181D01*
X2637868Y589056D01*
X2639615Y589348D01*
X2641798Y588765D01*
X2643326Y587306D01*
X2643763Y585557D01*
X2643545Y583806D01*
X2642671Y582348D01*
X2638305Y579431D01*
X2636340Y577390D01*
X2635030Y574472D01*
X2634593Y571848D01*
X2643763D01*
G01X2652748Y571265D02*
X2660608Y589348D01*
G01X2669811D02*
Y571848D01*
X2678545D01*
G01X2694298D02*
Y589348D01*
X2686219Y576806D01*
X2697137D01*
G01X2853228Y548864D02*
Y537198D01*
G01Y553531D02*
X2852791Y553823D01*
Y554406D01*
X2853228Y554698D01*
X2853665Y554406D01*
Y553823D01*
X2853228Y553531D01*
G01X2867016Y537198D02*
Y548864D01*
G01Y545948D02*
X2867890Y547406D01*
X2869200Y548573D01*
X2870946Y548864D01*
X2872474Y548573D01*
X2873785Y547406D01*
X2874440Y545365D01*
Y537198D01*
G01X2884953Y539239D02*
X2886045Y538073D01*
X2887573Y537198D01*
X2888883D01*
X2890193Y537781D01*
X2891066Y538656D01*
X2891503Y539822D01*
X2891285Y541573D01*
X2890411Y542448D01*
X2886481Y544198D01*
X2885608Y546240D01*
X2886045Y547698D01*
X2886918Y548573D01*
X2888228Y548864D01*
X2889538Y548573D01*
X2890848Y547698D01*
G01X2905728Y548864D02*
Y537198D01*
G01Y553531D02*
X2905291Y553823D01*
Y554406D01*
X2905728Y554698D01*
X2906165Y554406D01*
Y553823D01*
X2905728Y553531D01*
G01X2927158Y554698D02*
Y537198D01*
G01Y539822D02*
X2926285Y538364D01*
X2924974Y537490D01*
X2923446Y537198D01*
X2921700Y537781D01*
X2920390Y539239D01*
X2919516Y540989D01*
X2919298Y543031D01*
X2919516Y545073D01*
X2920390Y546823D01*
X2921700Y548281D01*
X2923446Y548864D01*
X2924974Y548573D01*
X2926066Y547989D01*
X2927158Y546823D01*
G01X2937453Y545073D02*
X2944440D01*
X2943785Y547115D01*
X2942693Y548281D01*
X2941165Y548864D01*
X2939636Y548573D01*
X2938326Y547698D01*
X2937453Y545656D01*
X2937016Y543906D01*
Y542156D01*
X2937453Y540406D01*
X2938545Y538656D01*
X2939855Y537490D01*
X2941383Y537198D01*
X2942911Y537781D01*
X2944440Y539531D01*
G01X2971798Y537198D02*
Y554698D01*
G01Y545948D02*
X2972890Y547698D01*
X2974200Y548573D01*
X2975510Y548864D01*
X2977474Y548281D01*
X2978785Y547115D01*
X2979658Y545073D01*
Y542740D01*
X2979221Y540406D01*
X2978348Y538656D01*
X2976820Y537490D01*
X2975510Y537198D01*
X2974200Y537490D01*
X2972890Y538364D01*
X2971798Y539822D01*
G01X2993228Y537198D02*
X2991918Y537490D01*
X2990608Y538656D01*
X2989734Y540698D01*
X2989298Y543031D01*
X2989734Y545365D01*
X2990608Y547406D01*
X2991918Y548573D01*
X2993228Y548864D01*
X2994538Y548573D01*
X2995848Y547406D01*
X2996721Y545365D01*
X2996940Y543031D01*
X2996721Y540698D01*
X2995848Y538656D01*
X2994538Y537490D01*
X2993228Y537198D01*
G01X3014658D02*
Y548864D01*
G01Y546823D02*
X3013785Y547989D01*
X3012474Y548573D01*
X3010946Y548864D01*
X3009418Y548281D01*
X3008108Y547115D01*
X3007234Y545365D01*
X3006798Y543031D01*
X3007234Y540698D01*
X3008108Y538948D01*
X3009418Y537781D01*
X3010946Y537198D01*
X3012474Y537490D01*
X3013785Y538364D01*
X3014658Y539531D01*
G01X3025171Y537198D02*
Y548864D01*
G01Y546531D02*
X3026263Y547698D01*
X3027355Y548573D01*
X3028883Y548864D01*
X3029974Y548573D01*
X3031285Y547698D01*
G01X3049658Y554698D02*
Y537198D01*
G01Y539822D02*
X3048785Y538364D01*
X3047474Y537490D01*
X3045946Y537198D01*
X3044200Y537781D01*
X3042890Y539239D01*
X3042016Y540989D01*
X3041798Y543031D01*
X3042016Y545073D01*
X3042890Y546823D01*
X3044200Y548281D01*
X3045946Y548864D01*
X3047474Y548573D01*
X3048566Y547989D01*
X3049658Y546823D01*
G01X3080728Y537198D02*
X3079418Y537490D01*
X3078108Y538656D01*
X3077234Y540698D01*
X3076798Y543031D01*
X3077234Y545365D01*
X3078108Y547406D01*
X3079418Y548573D01*
X3080728Y548864D01*
X3082038Y548573D01*
X3083348Y547406D01*
X3084221Y545365D01*
X3084440Y543031D01*
X3084221Y540698D01*
X3083348Y538656D01*
X3082038Y537490D01*
X3080728Y537198D01*
G01X3094516Y548864D02*
Y540698D01*
X3095390Y538656D01*
X3096700Y537490D01*
X3098228Y537198D01*
X3099756Y537490D01*
X3101066Y538656D01*
X3101940Y540698D01*
G01Y537198D02*
Y548864D01*
G01X3115728Y554698D02*
Y537198D01*
G01X3112671Y548864D02*
X3118785D01*
G01X3133228Y537198D02*
Y554698D01*
G01X3150728Y548864D02*
Y537198D01*
G01Y553531D02*
X3150291Y553823D01*
Y554406D01*
X3150728Y554698D01*
X3151165Y554406D01*
Y553823D01*
X3150728Y553531D01*
G01X3164516Y537198D02*
Y548864D01*
G01Y545948D02*
X3165390Y547406D01*
X3166700Y548573D01*
X3168446Y548864D01*
X3169974Y548573D01*
X3171285Y547406D01*
X3171940Y545365D01*
Y537198D01*
G01X3182453Y545073D02*
X3189440D01*
X3188785Y547115D01*
X3187693Y548281D01*
X3186165Y548864D01*
X3184636Y548573D01*
X3183326Y547698D01*
X3182453Y545656D01*
X3182016Y543906D01*
Y542156D01*
X3182453Y540406D01*
X3183545Y538656D01*
X3184855Y537490D01*
X3186383Y537198D01*
X3187911Y537781D01*
X3189440Y539531D01*
G01X3203228Y536615D02*
X3202791Y536906D01*
Y537490D01*
X3203228Y537781D01*
X3203665Y537490D01*
Y536906D01*
X3203228Y536615D01*
G01X2853228Y583514D02*
Y571848D01*
G01Y588181D02*
X2852791Y588473D01*
Y589056D01*
X2853228Y589348D01*
X2853665Y589056D01*
Y588473D01*
X2853228Y588181D01*
G01X2867453Y573889D02*
X2868545Y572723D01*
X2870073Y571848D01*
X2871383D01*
X2872693Y572431D01*
X2873566Y573306D01*
X2874003Y574472D01*
X2873785Y576223D01*
X2872911Y577098D01*
X2868981Y578848D01*
X2868108Y580890D01*
X2868545Y582348D01*
X2869418Y583223D01*
X2870728Y583514D01*
X2872038Y583223D01*
X2873348Y582348D01*
G01X2900706Y571848D02*
Y589348D01*
X2910750Y571848D01*
Y589348D01*
G01X2923228Y571848D02*
X2921481Y572140D01*
X2919953Y573306D01*
X2918643Y575056D01*
X2917769Y577098D01*
X2917333Y579431D01*
Y581765D01*
X2917769Y584098D01*
X2918643Y586140D01*
X2919953Y587889D01*
X2921481Y589056D01*
X2923228Y589348D01*
X2924974Y589056D01*
X2926503Y587889D01*
X2927813Y586140D01*
X2928687Y584098D01*
X2929123Y581765D01*
Y579431D01*
X2928687Y577098D01*
X2927813Y575056D01*
X2926503Y573306D01*
X2924974Y572140D01*
X2923228Y571848D01*
G01X2940728Y589348D02*
Y571848D01*
G01X2935706Y589348D02*
X2945750D01*
G01X2972016Y583514D02*
Y575348D01*
X2972890Y573306D01*
X2974200Y572140D01*
X2975728Y571848D01*
X2977256Y572140D01*
X2978566Y573306D01*
X2979440Y575348D01*
G01Y571848D02*
Y583514D01*
G01X2989953Y573889D02*
X2991045Y572723D01*
X2992573Y571848D01*
X2993883D01*
X2995193Y572431D01*
X2996066Y573306D01*
X2996503Y574472D01*
X2996285Y576223D01*
X2995411Y577098D01*
X2991481Y578848D01*
X2990608Y580890D01*
X2991045Y582348D01*
X2991918Y583223D01*
X2993228Y583514D01*
X2994538Y583223D01*
X2995848Y582348D01*
G01X3007453Y579723D02*
X3014440D01*
X3013785Y581765D01*
X3012693Y582931D01*
X3011165Y583514D01*
X3009636Y583223D01*
X3008326Y582348D01*
X3007453Y580306D01*
X3007016Y578556D01*
Y576806D01*
X3007453Y575056D01*
X3008545Y573306D01*
X3009855Y572140D01*
X3011383Y571848D01*
X3012911Y572431D01*
X3014440Y574181D01*
G01X3032158Y589348D02*
Y571848D01*
G01Y574472D02*
X3031285Y573014D01*
X3029974Y572140D01*
X3028446Y571848D01*
X3026700Y572431D01*
X3025390Y573889D01*
X3024516Y575639D01*
X3024298Y577681D01*
X3024516Y579723D01*
X3025390Y581473D01*
X3026700Y582931D01*
X3028446Y583514D01*
X3029974Y583223D01*
X3031066Y582639D01*
X3032158Y581473D01*
G01X3063228Y583514D02*
Y571848D01*
G01Y588181D02*
X3062791Y588473D01*
Y589056D01*
X3063228Y589348D01*
X3063665Y589056D01*
Y588473D01*
X3063228Y588181D01*
G01X3077016Y571848D02*
Y583514D01*
G01Y580598D02*
X3077890Y582056D01*
X3079200Y583223D01*
X3080946Y583514D01*
X3082474Y583223D01*
X3083785Y582056D01*
X3084440Y580015D01*
Y571848D01*
G01X3115728Y589348D02*
Y571848D01*
G01X3112671Y583514D02*
X3118785D01*
G01X3129516Y571848D02*
Y589348D01*
G01Y580890D02*
X3130608Y582348D01*
X3131700Y583223D01*
X3133446Y583514D01*
X3134756Y583223D01*
X3136285Y582056D01*
X3136940Y580306D01*
Y571848D01*
G01X3150728Y583514D02*
Y571848D01*
G01Y588181D02*
X3150291Y588473D01*
Y589056D01*
X3150728Y589348D01*
X3151165Y589056D01*
Y588473D01*
X3150728Y588181D01*
G01X3164953Y573889D02*
X3166045Y572723D01*
X3167573Y571848D01*
X3168883D01*
X3170193Y572431D01*
X3171066Y573306D01*
X3171503Y574472D01*
X3171285Y576223D01*
X3170411Y577098D01*
X3166481Y578848D01*
X3165608Y580890D01*
X3166045Y582348D01*
X3166918Y583223D01*
X3168228Y583514D01*
X3169538Y583223D01*
X3170848Y582348D01*
G01X3203228Y571848D02*
Y589348D01*
G01X3224658Y571848D02*
Y583514D01*
G01Y581473D02*
X3223785Y582639D01*
X3222474Y583223D01*
X3220946Y583514D01*
X3219418Y582931D01*
X3218108Y581765D01*
X3217234Y580015D01*
X3216798Y577681D01*
X3217234Y575348D01*
X3218108Y573598D01*
X3219418Y572431D01*
X3220946Y571848D01*
X3222474Y572140D01*
X3223785Y573014D01*
X3224658Y574181D01*
G01X3233643Y566598D02*
X3234953Y566015D01*
X3236700Y566598D01*
X3237791Y567764D01*
X3238665Y569223D01*
X3239974Y573889D01*
X3242813Y583514D01*
G01X3235826D02*
X3239974Y573889D01*
G01X3252453Y579723D02*
X3259440D01*
X3258785Y581765D01*
X3257693Y582931D01*
X3256165Y583514D01*
X3254636Y583223D01*
X3253326Y582348D01*
X3252453Y580306D01*
X3252016Y578556D01*
Y576806D01*
X3252453Y575056D01*
X3253545Y573306D01*
X3254855Y572140D01*
X3256383Y571848D01*
X3257911Y572431D01*
X3259440Y574181D01*
G01X3270171Y571848D02*
Y583514D01*
G01Y581181D02*
X3271263Y582348D01*
X3272355Y583223D01*
X3273883Y583514D01*
X3274974Y583223D01*
X3276285Y582348D01*
G01X2778425Y605915D02*
X2788031Y618748D01*
G01X2783228Y621081D02*
Y603581D01*
G01X2788031Y605915D02*
X2778425Y618748D01*
G01X2776678Y612331D02*
X2789778D01*
G01X2815390D02*
X2821066D01*
G01X2848425Y606498D02*
Y623998D01*
X2852791D01*
X2854538Y623123D01*
X2855848Y621956D01*
X2856940Y620207D01*
X2857813Y618164D01*
X2858031Y615248D01*
X2857813Y612331D01*
X2856940Y610289D01*
X2855848Y608539D01*
X2854538Y607373D01*
X2852791Y606498D01*
X2848425D01*
G01X2867453Y614373D02*
X2874440D01*
X2873785Y616415D01*
X2872693Y617581D01*
X2871165Y618164D01*
X2869636Y617873D01*
X2868326Y616998D01*
X2867453Y614956D01*
X2867016Y613206D01*
Y611456D01*
X2867453Y609706D01*
X2868545Y607956D01*
X2869855Y606790D01*
X2871383Y606498D01*
X2872911Y607081D01*
X2874440Y608831D01*
G01X2884516Y606498D02*
Y618164D01*
G01Y615248D02*
X2885390Y616706D01*
X2886700Y617873D01*
X2888446Y618164D01*
X2889974Y617873D01*
X2891285Y616706D01*
X2891940Y614665D01*
Y606498D01*
G01X2905728D02*
X2904418Y606790D01*
X2903108Y607956D01*
X2902234Y609998D01*
X2901798Y612331D01*
X2902234Y614665D01*
X2903108Y616706D01*
X2904418Y617873D01*
X2905728Y618164D01*
X2907038Y617873D01*
X2908348Y616706D01*
X2909221Y614665D01*
X2909440Y612331D01*
X2909221Y609998D01*
X2908348Y607956D01*
X2907038Y606790D01*
X2905728Y606498D01*
G01X2923228Y623998D02*
Y606498D01*
G01X2920171Y618164D02*
X2926285D01*
G01X2937453Y614373D02*
X2944440D01*
X2943785Y616415D01*
X2942693Y617581D01*
X2941165Y618164D01*
X2939636Y617873D01*
X2938326Y616998D01*
X2937453Y614956D01*
X2937016Y613206D01*
Y611456D01*
X2937453Y609706D01*
X2938545Y607956D01*
X2939855Y606790D01*
X2941383Y606498D01*
X2942911Y607081D01*
X2944440Y608831D01*
G01X2954953Y608539D02*
X2956045Y607373D01*
X2957573Y606498D01*
X2958883D01*
X2960193Y607081D01*
X2961066Y607956D01*
X2961503Y609122D01*
X2961285Y610873D01*
X2960411Y611748D01*
X2956481Y613498D01*
X2955608Y615540D01*
X2956045Y616998D01*
X2956918Y617873D01*
X2958228Y618164D01*
X2959538Y617873D01*
X2960848Y616998D01*
G01X2993228Y623998D02*
Y606498D01*
G01X2990171Y618164D02*
X2996285D01*
G01X3007016Y606498D02*
Y623998D01*
G01Y615540D02*
X3008108Y616998D01*
X3009200Y617873D01*
X3010946Y618164D01*
X3012256Y617873D01*
X3013785Y616706D01*
X3014440Y614956D01*
Y606498D01*
G01X3032158D02*
Y618164D01*
G01Y616123D02*
X3031285Y617289D01*
X3029974Y617873D01*
X3028446Y618164D01*
X3026918Y617581D01*
X3025608Y616415D01*
X3024734Y614665D01*
X3024298Y612331D01*
X3024734Y609998D01*
X3025608Y608248D01*
X3026918Y607081D01*
X3028446Y606498D01*
X3029974Y606790D01*
X3031285Y607664D01*
X3032158Y608831D01*
G01X3045728Y623998D02*
Y606498D01*
G01X3042671Y618164D02*
X3048785D01*
G01X3074178Y623998D02*
X3077234Y606498D01*
X3080728Y623998D01*
X3084221Y606498D01*
X3087278Y623998D01*
G01X3095608D02*
X3100848D01*
G01X3098228D02*
Y606498D01*
G01X3095608D02*
X3100848D01*
G01X3110925D02*
Y623998D01*
X3115291D01*
X3117038Y623123D01*
X3118348Y621956D01*
X3119440Y620207D01*
X3120313Y618164D01*
X3120531Y615248D01*
X3120313Y612331D01*
X3119440Y610289D01*
X3118348Y608539D01*
X3117038Y607373D01*
X3115291Y606498D01*
X3110925D01*
G01X3133228Y623998D02*
Y606498D01*
G01X3128206Y623998D02*
X3138250D01*
G01X3146143Y606498D02*
Y623998D01*
G01X3155313D02*
Y606498D01*
G01Y615248D02*
X3146143D01*
G01X-7874Y-31496D02*
X-19685D01*
G01X-7874D02*
X-19685D01*
G01D02*
G03X-23622Y-35433I0J-3937D01*
G01D02*
Y-59055D01*
G01Y-35433D02*
Y-59055D01*
G01X-19685Y-31496D02*
G03X-23622Y-35433I0J-3937D01*
G01Y-59055D02*
G03X-19685Y-62992I3937J0D01*
G01D02*
X1972441D01*
G01X-19685D02*
X1972441D01*
G01X-23622Y-59055D02*
G03X-19685Y-62992I3937J0D01*
G01Y-23622D02*
X1972441D01*
G01X-19685D02*
X1972441D01*
G01X-19685D02*
X1972441D01*
G01X-19685D02*
X1972441D01*
G01X-23622Y622441D02*
Y-19685D01*
G01Y622441D02*
Y-19685D01*
G01Y622441D02*
Y-19685D01*
G01Y622441D02*
Y-19685D01*
G01D02*
G03X-19685Y-23622I3937J0D01*
G01X-23622Y-19685D02*
G03X-19685Y-23622I3937J0D01*
G01X-23622Y-19685D02*
G03X-19685Y-23622I3937J0D01*
G01X-23622Y-19685D02*
G03X-19685Y-23622I3937J0D01*
G01X1972441Y626378D02*
X-19685D01*
G01X1972441D02*
X-19685D01*
G01X1972441D02*
X-19685D01*
G01X1972441D02*
X-19685D01*
G01D02*
G03X-23622Y622441I0J-3937D01*
G01X-19685Y626378D02*
G03X-23622Y622441I0J-3937D01*
G01X-19685Y626378D02*
G03X-23622Y622441I0J-3937D01*
G01X-19685Y626378D02*
G03X-23622Y622441I0J-3937D01*
G01X-19685Y634252D02*
X-7874D01*
G01X-19685D02*
X-7874D01*
G01X-23622Y661811D02*
Y638189D01*
G01Y661811D02*
Y638189D01*
G01D02*
G03X-19685Y634252I3937J0D01*
G01X-23622Y638189D02*
G03X-19685Y634252I3937J0D01*
G01X1972441Y665748D02*
X-19685D01*
G01X1972441D02*
X-19685D01*
G01D02*
G03X-23622Y661811I0J-3937D01*
G01X-19685Y665748D02*
G03X-23622Y661811I0J-3937D01*
G01X-7874Y-31496D02*
G03Y-23622I0J3937D01*
G01Y-31496D02*
G03Y-23622I0J3937D01*
G01X22835D02*
G03Y-31496I0J-3937D01*
G01X137795D02*
X22835D01*
G01X137795D02*
X22835D01*
G01Y-23622D02*
G03Y-31496I0J-3937D01*
G01X0Y616535D02*
G03Y604724I0J-5905D01*
G01Y616535D02*
G03Y604724I0J-5905D01*
G01Y616535D02*
X2646D01*
G01X2644D02*
X0D01*
G01Y604724D02*
X2644D01*
G01X2646D02*
X0D01*
G01X2646D02*
X0D01*
G01D02*
X2644D01*
G01Y616535D02*
X0D01*
G01D02*
X2646D01*
G01X0D02*
G03Y604724I0J-5905D01*
G01Y616535D02*
G03Y604724I0J-5905D01*
G01X2646Y616535D02*
G03X7595Y618285I0J7874D01*
G01X2644Y616535D02*
G03X7593Y618285I0J7874D01*
G01X2644Y616535D02*
G03X7593Y618285I0J7874D01*
G01X7595Y602975D02*
G03X2646Y604724I-4948J-6125D01*
G01X7593Y602975D02*
G03X2644Y604724I-4948J-6125D01*
G01X7593Y602975D02*
G03X2644Y604724I-4948J-6125D01*
G01X7593Y602975D02*
G03X2644Y604724I-4948J-6125D01*
G01X7593Y602975D02*
G03X2644Y604724I-4948J-6125D01*
G01X7595Y602975D02*
G03X2646Y604724I-4948J-6125D01*
G01X2644Y616535D02*
G03X7593Y618285I0J7874D01*
G01X2644Y616535D02*
G03X7593Y618285I0J7874D01*
G01X2646Y616535D02*
G03X7595Y618285I0J7874D01*
G01Y602975D02*
G03Y618285I6186J7655D01*
G01X7593Y602975D02*
G03Y618285I6187J7655D01*
G01Y602975D02*
G03Y618285I6187J7655D01*
G01Y602975D02*
G03Y618285I6187J7655D01*
G01Y602975D02*
G03Y618285I6187J7655D01*
G01X7595Y602975D02*
G03Y618285I6186J7655D01*
G01X-7874Y626378D02*
G03Y634252I0J3937D01*
G01Y626378D02*
G03Y634252I0J3937D01*
G01X22835D02*
G03Y626378I0J-3937D01*
G01Y634252D02*
X137795D01*
G01X22835D02*
X137795D01*
G01X22835D02*
G03Y626378I0J-3937D01*
G01X168504Y-23622D02*
G03Y-31496I0J-3937D01*
G01X137795D02*
G03Y-23622I0J3937D01*
G01X341732Y-31496D02*
X168504D01*
G01X341732D02*
X168504D01*
G01X137795D02*
G03Y-23622I0J3937D01*
G01X168504D02*
G03Y-31496I0J-3937D01*
G01Y634252D02*
G03Y626378I0J-3937D01*
G01X137795D02*
G03Y634252I0J3937D01*
G01X168504D02*
X341732D01*
G01X168504D02*
X341732D01*
G01X137795Y626378D02*
G03Y634252I0J3937D01*
G01X168504D02*
G03Y626378I0J-3937D01*
G01X341732Y-31496D02*
G03Y-23622I0J3937D01*
G01Y-31496D02*
G03Y-23622I0J3937D01*
G01Y626378D02*
G03Y634252I0J3937D01*
G01Y626378D02*
G03Y634252I0J3937D01*
G01X372441Y-23622D02*
G03Y-31496I0J-3937D01*
G01X529921D02*
X372441D01*
G01X529921D02*
X372441D01*
G01Y-23622D02*
G03Y-31496I0J-3937D01*
G01Y634252D02*
G03Y626378I0J-3937D01*
G01Y634252D02*
X529921D01*
G01X372441D02*
X529921D01*
G01X372441D02*
G03Y626378I0J-3937D01*
G01X529921Y-31496D02*
G03Y-23622I0J3937D01*
G01Y-31496D02*
G03Y-23622I0J3937D01*
G01Y626378D02*
G03Y634252I0J3937D01*
G01Y626378D02*
G03Y634252I0J3937D01*
G01X560630Y-23622D02*
G03Y-31496I0J-3937D01*
G01X788976D02*
X560630D01*
G01X788976D02*
X560630D01*
G01Y-23622D02*
G03Y-31496I0J-3937D01*
G01Y634252D02*
G03Y626378I0J-3937D01*
G01Y634252D02*
X788976D01*
G01X560630D02*
X788976D01*
G01X560630D02*
G03Y626378I0J-3937D01*
G01X684760Y-15529D02*
G03Y-219I6187J7655D01*
G01X684759Y-15529D02*
G03X679809Y-13780I-4948J-6125D01*
G01X679811Y-1969D02*
G03X684760Y-219I0J7874D01*
G01X677165Y-1969D02*
X679811D01*
G01X677165D02*
G03Y-13780I0J-5906D01*
G01D02*
X679809D01*
G01X684760Y602975D02*
G03Y618285I6187J7655D01*
G01X684759Y602975D02*
G03Y618285I6186J7655D01*
G01Y602975D02*
G03Y618285I6186J7655D01*
G01Y602975D02*
G03Y618285I6186J7655D01*
G01Y602975D02*
G03Y618285I6186J7655D01*
G01X684760Y602975D02*
G03Y618285I6187J7655D01*
G01X679811Y616535D02*
G03X684760Y618285I0J7874D01*
G01X679809Y616535D02*
G03X684759Y618285I0J7874D01*
G01X679809Y616535D02*
G03X684759Y618285I0J7874D01*
G01X684760Y602975D02*
G03X679811Y604724I-4948J-6125D01*
G01X684759Y602975D02*
G03X679809Y604724I-4948J-6125D01*
G01X684759Y602975D02*
G03X679809Y604724I-4948J-6125D01*
G01X684759Y602975D02*
G03X679809Y604724I-4948J-6125D01*
G01X684759Y602975D02*
G03X679809Y604724I-4948J-6125D01*
G01X684760Y602975D02*
G03X679811Y604724I-4948J-6125D01*
G01X679809Y616535D02*
G03X684759Y618285I0J7874D01*
G01X679809Y616535D02*
G03X684759Y618285I0J7874D01*
G01X679811Y616535D02*
G03X684760Y618285I0J7874D01*
G01X677165Y616535D02*
X679811D01*
G01X677165D02*
G03Y604724I0J-5905D01*
G01D02*
X679809D01*
G01X788976Y-31496D02*
G03Y-23622I0J3937D01*
G01Y-31496D02*
G03Y-23622I0J3937D01*
G01X819685D02*
G03Y-31496I0J-3937D01*
G01X975591D02*
X819685D01*
G01X975591D02*
X819685D01*
G01Y-23622D02*
G03Y-31496I0J-3937D01*
G01X788976Y626378D02*
G03Y634252I0J3937D01*
G01Y626378D02*
G03Y634252I0J3937D01*
G01X819685D02*
G03Y626378I0J-3937D01*
G01Y634252D02*
X975591D01*
G01X819685D02*
X975591D01*
G01X819685D02*
G03Y626378I0J-3937D01*
G01X975591Y-31496D02*
G03Y-23622I0J3937D01*
G01Y-31496D02*
G03Y-23622I0J3937D01*
G01X1006299D02*
G03Y-31496I0J-3937D01*
G01X1162205D02*
X1006299D01*
G01X1162205D02*
X1006299D01*
G01Y-23622D02*
G03Y-31496I0J-3937D01*
G01Y634252D02*
X1162205D01*
G01X1006299D02*
X1162205D01*
G01X975591Y626378D02*
G03Y634252I0J3937D01*
G01Y626378D02*
G03Y634252I0J3937D01*
G01X1006299D02*
G03Y626378I0J-3937D01*
G01Y634252D02*
G03Y626378I0J-3937D01*
G01X1162205Y-31496D02*
G03Y-23622I0J3937D01*
G01Y-31496D02*
G03Y-23622I0J3937D01*
G01X1192913D02*
G03Y-31496I0J-3937D01*
G01X1398425D02*
X1192913D01*
G01X1398425D02*
X1192913D01*
G01Y-23622D02*
G03Y-31496I0J-3937D01*
G01Y634252D02*
X1394488D01*
G01X1192913D02*
X1394488D01*
G01X1162205Y626378D02*
G03Y634252I0J3937D01*
G01Y626378D02*
G03Y634252I0J3937D01*
G01X1192913D02*
G03Y626378I0J-3937D01*
G01Y634252D02*
G03Y626378I0J-3937D01*
G01X1398425Y-31496D02*
G03Y-23622I0J3937D01*
G01Y-31496D02*
G03Y-23622I0J3937D01*
G01X1405512Y-1968D02*
G03Y-13779I0J-5906D01*
G01Y-1968D02*
G03Y-13779I0J-5906D01*
G01Y-1968D02*
G03Y-13779I0J-5906D01*
G01Y-1968D02*
G03Y-13779I0J-5906D01*
G01X1394488Y626378D02*
G03Y634252I0J3937D01*
G01Y626378D02*
G03Y634252I0J3937D01*
G01X1405512Y616535D02*
G03Y604724I0J-5905D01*
G01Y616535D02*
G03Y604724I0J-5905D01*
G01Y616535D02*
G03Y604724I0J-5905D01*
G01Y616535D02*
G03Y604724I0J-5905D01*
G01X1429134Y-23622D02*
G03Y-31496I0J-3937D01*
G01X1851181D02*
X1429134D01*
G01X1851181D02*
X1429134D01*
G01Y-23622D02*
G03Y-31496I0J-3937D01*
G01X1413107Y-15529D02*
G03Y-218I6186J7655D01*
G01X1413105Y-15529D02*
G03Y-218I6186J7655D01*
G01Y-15529D02*
G03Y-218I6186J7655D01*
G01Y-15529D02*
G03Y-218I6186J7655D01*
G01Y-15529D02*
G03Y-218I6186J7655D01*
G01X1413107Y-15529D02*
G03Y-218I6186J7655D01*
G01X1408157Y-1968D02*
G03X1413107Y-218I1J7874D01*
G01X1408156Y-1968D02*
G03X1413105Y-218I0J7874D01*
G01X1408156Y-1968D02*
G03X1413105Y-218I0J7874D01*
G01X1408156Y-1968D02*
G03X1413105Y-218I0J7874D01*
G01X1408156Y-1968D02*
G03X1413105Y-218I0J7874D01*
G01X1408157Y-1968D02*
G03X1413107Y-218I1J7874D01*
G01Y-15529D02*
G03X1408157Y-13779I-4949J-6124D01*
G01X1413105Y-15529D02*
G03X1408156Y-13779I-4949J-6124D01*
G01X1413105Y-15529D02*
G03X1408156Y-13779I-4949J-6124D01*
G01X1413105Y-15529D02*
G03X1408156Y-13779I-4949J-6124D01*
G01X1413105Y-15529D02*
G03X1408156Y-13779I-4949J-6124D01*
G01X1413107Y-15529D02*
G03X1408157Y-13779I-4949J-6124D01*
G01X1405512D02*
X1408156D01*
G01X1408157D02*
X1405512D01*
G01X1408157D02*
X1405512D01*
G01D02*
X1408156D01*
G01X1405512Y-1968D02*
X1408157D01*
G01X1408156D02*
X1405512D01*
G01X1408156D02*
X1405512D01*
G01D02*
X1408157D01*
G01X1425197Y634252D02*
X1851181D01*
G01X1425197D02*
X1851181D01*
G01X1425197D02*
G03Y626378I0J-3937D01*
G01Y634252D02*
G03Y626378I0J-3937D01*
G01X1408157Y616535D02*
G03X1413107Y618285I1J7874D01*
G01X1408156Y616535D02*
G03X1413105Y618285I0J7874D01*
G01X1408156Y616535D02*
G03X1413105Y618285I0J7874D01*
G01X1413107Y602975D02*
G03Y618285I6186J7655D01*
G01X1413105Y602975D02*
G03Y618285I6187J7655D01*
G01Y602975D02*
G03Y618285I6187J7655D01*
G01X1413107Y602975D02*
G03X1408157Y604724I-4948J-6125D01*
G01X1413105Y602975D02*
G03X1408156Y604724I-4948J-6125D01*
G01X1413105Y602975D02*
G03X1408156Y604724I-4948J-6125D01*
G01X1413105Y602975D02*
G03X1408156Y604724I-4948J-6125D01*
G01X1413105Y602975D02*
G03X1408156Y604724I-4948J-6125D01*
G01X1413107Y602975D02*
G03X1408157Y604724I-4948J-6125D01*
G01X1413105Y602975D02*
G03Y618285I6187J7655D01*
G01Y602975D02*
G03Y618285I6187J7655D01*
G01X1413107Y602975D02*
G03Y618285I6186J7655D01*
G01X1408156Y616535D02*
G03X1413105Y618285I0J7874D01*
G01X1408156Y616535D02*
G03X1413105Y618285I0J7874D01*
G01X1408157Y616535D02*
G03X1413107Y618285I1J7874D01*
G01X1405512Y616535D02*
X1408157D01*
G01X1408156D02*
X1405512D01*
G01Y604724D02*
X1408156D01*
G01X1408157D02*
X1405512D01*
G01X1408157D02*
X1405512D01*
G01D02*
X1408156D01*
G01Y616535D02*
X1405512D01*
G01D02*
X1408157D01*
G01X1685866Y267244D02*
X1883780D01*
G01X1685866D02*
X1883780D01*
G01X1685866D02*
X1883780D01*
G01X1685866D02*
X1883780D01*
G01X1681929Y271181D02*
G03X1685866Y267244I3937J0D01*
G01X1681929Y271181D02*
G03X1685866Y267244I3937J0D01*
G01X1681929Y271181D02*
G03X1685866Y267244I3937J0D01*
G01X1681929Y271181D02*
G03X1685866Y267244I3937J0D01*
G01X1681929Y428661D02*
Y271181D01*
G01Y428661D02*
Y271181D01*
G01Y428661D02*
Y271181D01*
G01Y428661D02*
Y271181D01*
G01X1685866Y432598D02*
G03X1681929Y428661I0J-3937D01*
G01X1685866Y432598D02*
G03X1681929Y428661I0J-3937D01*
G01X1972441Y432598D02*
X1685866D01*
G01X1972441D02*
X1685866D01*
G01X1972441D02*
X1685866D01*
G01X1972441D02*
X1685866D01*
G01D02*
G03X1681929Y428661I0J-3937D01*
G01X1685866Y432598D02*
G03X1681929Y428661I0J-3937D01*
G01X1851181Y-31496D02*
G03Y-23622I0J3937D01*
G01Y-31496D02*
G03Y-23622I0J3937D01*
G01X1881890D02*
G03Y-31496I0J-3937D01*
G01X1972441D02*
X1881890D01*
G01X1972441D02*
X1881890D01*
G01Y-23622D02*
G03Y-31496I0J-3937D01*
G01X1861926Y-15529D02*
G03X1856976Y-13780I-4948J-6125D01*
G01X1861924Y-15529D02*
G03X1856975Y-13780I-4948J-6125D01*
G01X1861924Y-15529D02*
G03X1856975Y-13780I-4948J-6125D01*
G01X1861924Y-15529D02*
G03X1856975Y-13780I-4948J-6125D01*
G01X1861924Y-15529D02*
G03X1856975Y-13780I-4948J-6125D01*
G01X1861926Y-15529D02*
G03X1856976Y-13780I-4948J-6125D01*
G01Y-1969D02*
G03X1861926Y-219I0J7874D01*
G01X1856975Y-1969D02*
G03X1861924Y-219I0J7874D01*
G01X1856975Y-1969D02*
G03X1861924Y-219I0J7874D01*
G01X1861926Y-15529D02*
G03Y-219I6186J7655D01*
G01X1861924Y-15529D02*
G03Y-219I6186J7655D01*
G01Y-15529D02*
G03Y-219I6186J7655D01*
G01Y-15529D02*
G03Y-219I6186J7655D01*
G01Y-15529D02*
G03Y-219I6186J7655D01*
G01X1861926Y-15529D02*
G03Y-219I6186J7655D01*
G01X1856975Y-1969D02*
G03X1861924Y-219I0J7874D01*
G01X1856975Y-1969D02*
G03X1861924Y-219I0J7874D01*
G01X1856976Y-1969D02*
G03X1861926Y-219I0J7874D01*
G01X1854331Y-1969D02*
G03Y-13780I0J-5906D01*
G01Y-1969D02*
G03Y-13780I0J-5906D01*
G01D02*
X1856975D01*
G01X1856976D02*
X1854331D01*
G01X1856976D02*
X1854331D01*
G01D02*
X1856975D01*
G01X1854331Y-1969D02*
G03Y-13780I0J-5906D01*
G01Y-1969D02*
G03Y-13780I0J-5906D01*
G01Y-1969D02*
X1856976D01*
G01X1856975D02*
X1854331D01*
G01X1856975D02*
X1854331D01*
G01D02*
X1856976D01*
G01X1891654Y246772D02*
X1972441D01*
G01X1891654D02*
X1972441D01*
G01X1891654D02*
X1972441D01*
G01X1891654D02*
X1972441D01*
G01X1887717Y250709D02*
G03X1891654Y246772I3937J0D01*
G01X1887717Y250709D02*
G03X1891654Y246772I3937J0D01*
G01X1887717Y263307D02*
Y250709D01*
G01Y263307D02*
Y250709D01*
G01Y263307D02*
Y250709D01*
G01Y263307D02*
Y250709D01*
G01D02*
G03X1891654Y246772I3937J0D01*
G01X1887717Y250709D02*
G03X1891654Y246772I3937J0D01*
G01X1887717Y263307D02*
G03X1883780Y267244I-3937J0D01*
G01X1887717Y263307D02*
G03X1883780Y267244I-3937J0D01*
G01X1887717Y263307D02*
G03X1883780Y267244I-3937J0D01*
G01X1887717Y263307D02*
G03X1883780Y267244I-3937J0D01*
G01X1881890Y634252D02*
G03Y626378I0J-3937D01*
G01Y634252D02*
X1972441D01*
G01X1881890D02*
X1972441D01*
G01X1881890D02*
G03Y626378I0J-3937D01*
G01X1851181D02*
G03Y634252I0J3937D01*
G01Y626378D02*
G03Y634252I0J3937D01*
G01X1856976Y616535D02*
G03X1861926Y618285I0J7874D01*
G01X1856975Y616535D02*
G03X1861924Y618285I0J7874D01*
G01X1856975Y616535D02*
G03X1861924Y618285I0J7874D01*
G01X1861926Y602975D02*
G03Y618285I6186J7655D01*
G01X1861924Y602975D02*
G03Y618285I6186J7655D01*
G01Y602975D02*
G03Y618285I6186J7655D01*
G01Y602975D02*
G03Y618285I6186J7655D01*
G01Y602975D02*
G03Y618285I6186J7655D01*
G01X1861926Y602975D02*
G03Y618285I6186J7655D01*
G01X1856975Y616535D02*
G03X1861924Y618285I0J7874D01*
G01X1856975Y616535D02*
G03X1861924Y618285I0J7874D01*
G01X1856976Y616535D02*
G03X1861926Y618285I0J7874D01*
G01Y602975D02*
G03X1856976Y604724I-4948J-6125D01*
G01X1861924Y602975D02*
G03X1856975Y604724I-4948J-6125D01*
G01X1861924Y602975D02*
G03X1856975Y604724I-4948J-6125D01*
G01X1861924Y602975D02*
G03X1856975Y604724I-4948J-6125D01*
G01X1861924Y602975D02*
G03X1856975Y604724I-4948J-6125D01*
G01X1861926Y602975D02*
G03X1856976Y604724I-4948J-6125D01*
G01X1854331Y616535D02*
G03Y604724I0J-5905D01*
G01Y616535D02*
G03Y604724I0J-5905D01*
G01D02*
X1856975D01*
G01X1856976D02*
X1854331D01*
G01X1856976D02*
X1854331D01*
G01D02*
X1856975D01*
G01X1854331Y616535D02*
G03Y604724I0J-5905D01*
G01Y616535D02*
G03Y604724I0J-5905D01*
G01Y616535D02*
X1856976D01*
G01X1856975D02*
X1854331D01*
G01X1856975D02*
X1854331D01*
G01D02*
X1856976D01*
G01X1972441Y-11811D02*
X1906890D01*
G01X1904921Y-9843D02*
G03X1906890Y-11811I1969J1D01*
G01X1904921Y53150D02*
Y-9843D01*
G01X1972441Y-11811D02*
X1906890D01*
G01X1904921Y-9843D02*
G03X1906890Y-11811I1969J1D01*
G01X1904921Y53150D02*
Y-9843D01*
G01X1923071Y53150D02*
Y-9843D01*
G01X1940787Y-3937D02*
X1972441D01*
G01X1940787D02*
G03X1938819Y-5906I0J-1968D01*
G01Y-9843D02*
Y-5906D01*
G01Y-9843D02*
G03X1940787Y-11811I1968J0D01*
G01X1921102D02*
G03X1923071Y-9843I0J1969D01*
G01X1906890Y55118D02*
G03X1904921Y53150I0J-1969D01*
G01X1972441Y55118D02*
X1906890D01*
G01X1972441D02*
X1906890D01*
G01X1972441D02*
X1906890D01*
G01X1972441D02*
X1906890D01*
G01D02*
G03X1904921Y53150I0J-1969D01*
G01X1923071D02*
G03X1921102Y55118I-1969J-1D01*
G01X1940787D02*
G03X1938819Y53150I0J-1968D01*
G01Y49213D02*
Y53150D01*
G01Y49213D02*
G03X1940787Y47244I1968J-1D01*
G01X1972441D02*
X1940787D01*
G01X1976378Y-35433D02*
G03X1972441Y-31496I-3937J0D01*
G01X1976378Y-59055D02*
Y-35433D01*
G01Y-59055D02*
Y-35433D01*
G01D02*
G03X1972441Y-31496I-3937J0D01*
G01Y-62992D02*
G03X1976378Y-59055I0J3937D01*
G01X1972441Y-62992D02*
G03X1976378Y-59055I0J3937D01*
G01X1972441Y-23622D02*
G03X1976378Y-19685I0J3937D01*
G01X1972441Y-23622D02*
G03X1976378Y-19685I0J3937D01*
G01X1972441Y-23622D02*
G03X1976378Y-19685I0J3937D01*
G01X1972441Y-23622D02*
G03X1976378Y-19685I0J3937D01*
G01D02*
Y-15748D01*
G01Y-19685D02*
Y-15748D01*
G01Y-19685D02*
Y-15748D01*
G01Y-19685D02*
Y-15748D01*
G01D02*
G03X1972441Y-11811I-3937J0D01*
G01X1976378Y-15748D02*
G03X1972441Y-11811I-3937J0D01*
G01X1976378Y-15748D02*
G03X1972441Y-11811I-3937J0D01*
G01X1976378Y-15748D02*
G03X1972441Y-11811I-3937J0D01*
G01X1976378Y0D02*
Y43307D01*
G01X1972441Y-3937D02*
G03X1976378Y0I0J3937D01*
G01X1972441Y55118D02*
G03X1976378Y59055I0J3937D01*
G01X1972441Y55118D02*
G03X1976378Y59055I0J3937D01*
G01X1972441Y55118D02*
G03X1976378Y59055I0J3937D01*
G01X1972441Y55118D02*
G03X1976378Y59055I0J3937D01*
G01D02*
Y242835D01*
G01Y59055D02*
Y242835D01*
G01Y59055D02*
Y242835D01*
G01Y59055D02*
Y242835D01*
G01Y43307D02*
G03X1972441Y47244I-3937J0D01*
G01X1976378Y242835D02*
G03X1972441Y246772I-3937J0D01*
G01X1976378Y242835D02*
G03X1972441Y246772I-3937J0D01*
G01X1976378Y242835D02*
G03X1972441Y246772I-3937J0D01*
G01X1976378Y242835D02*
G03X1972441Y246772I-3937J0D01*
G01Y432598D02*
G03X1976378Y436535I0J3937D01*
G01X1972441Y432598D02*
G03X1976378Y436535I0J3937D01*
G01X1972441Y432598D02*
G03X1976378Y436535I0J3937D01*
G01X1972441Y432598D02*
G03X1976378Y436535I0J3937D01*
G01D02*
Y622441D01*
G01Y436535D02*
Y622441D01*
G01Y436535D02*
Y622441D01*
G01Y436535D02*
Y622441D01*
G01D02*
G03X1972441Y626378I-3937J0D01*
G01X1976378Y622441D02*
G03X1972441Y626378I-3937J0D01*
G01X1976378Y622441D02*
G03X1972441Y626378I-3937J0D01*
G01X1976378Y622441D02*
G03X1972441Y626378I-3937J0D01*
G01Y634252D02*
G03X1976378Y638189I0J3937D01*
G01X1972441Y634252D02*
G03X1976378Y638189I0J3937D01*
G01D02*
Y661811D01*
G01Y638189D02*
Y661811D01*
G01D02*
G03X1972441Y665748I-3937J0D01*
G01X1976378Y661811D02*
G03X1972441Y665748I-3937J0D01*
G54D12*
G01X53425Y283198D02*
X54600Y284373D01*
G01X51700Y283200D02*
X50151Y281651D01*
G01X278058Y217285D02*
G03X279236Y217884I-60J1575D01*
G01X277929Y217285D02*
X278058D01*
G01X275984Y213797D02*
G02X277929Y217285I2015J1163D01*
G01X274663Y211434D02*
G03X275984Y213797I-44J1575D01*
G01X274534Y211434D02*
X274663D01*
G01X272604Y210272D02*
G02X274534Y211434I2015J-1163D01*
G01X271298Y209485D02*
G03X272604Y210272I-59J1575D01*
G01X271188Y209485D02*
X271298D01*
G01X269224Y208322D02*
G02X271188Y209485I2015J-1163D01*
G01X269092Y208117D02*
X269224Y208322D01*
G01X268756Y207596D02*
X269092Y208117D01*
G01X267448Y205756D02*
X268756Y207596D01*
G01X291604Y212635D02*
G03X293534Y213797I-85J2325D01*
G01X291475Y212635D02*
X291604D01*
G01X290154Y211847D02*
G02X291475Y212635I1365J-787D01*
G01X288209Y210684D02*
G03X290154Y211847I-70J2325D01*
G01X288080Y210684D02*
X288209D01*
G01X286774Y209897D02*
G02X288080Y210684I1365J-788D01*
G01X284810Y208734D02*
G03X286774Y209897I-51J2326D01*
G01X284715Y208734D02*
X284810D01*
G01X283394Y207946D02*
G02X284715Y208734I1365J-787D01*
G01X281464Y206784D02*
G03X283394Y207946I-85J2325D01*
G01X281308Y206784D02*
X281464D01*
G01X280014Y205997D02*
G02X281308Y206784I1365J-787D01*
G01X278069Y204834D02*
G03X280014Y205997I-70J2325D01*
G01X277928Y204834D02*
X278069D01*
G01X276634Y204047D02*
G02X277928Y204834I1365J-787D01*
G01X274670Y202884D02*
G03X276634Y204047I-51J2326D01*
G01X274560Y202884D02*
X274670D01*
G01X273254Y202097D02*
G02X274560Y202884I1365J-788D01*
G01X272828Y201351D02*
X273254Y202097D01*
G01X272828Y198477D02*
Y201351D01*
G01X271755Y197404D02*
X272828Y198477D01*
G01X280225Y217575D02*
X281379Y216909D01*
G01X279873Y217480D02*
X280225Y217575D01*
G01X278084Y216535D02*
G03X279873Y217480I-84J2325D01*
G01X277955Y216535D02*
X278084D01*
G01X276634Y214172D02*
G02X277955Y216535I1365J788D01*
G01X274689Y210684D02*
G03X276634Y214172I-70J2325D01*
G01X274560Y210684D02*
X274689D01*
G01X273254Y209897D02*
G02X274560Y210684I1365J-788D01*
G01X271290Y208734D02*
G03X273254Y209897I-51J2326D01*
G01X271195Y208734D02*
X271290D01*
G01X269874Y207946D02*
G02X271195Y208734I1365J-787D01*
G01X269692Y207596D02*
X269874Y207946D01*
G01X269403Y207040D02*
X269692Y207596D01*
G01X269403Y204104D02*
Y207040D01*
G01X268612Y203313D02*
X269403Y204104D01*
G01X290726Y194041D02*
X290537Y193852D01*
G01X291748Y194041D02*
X290726D01*
G01X292048Y194341D02*
X291748Y194041D01*
G01X292048Y197123D02*
Y194341D01*
G01X292884Y198572D02*
X292048Y197123D01*
G01X294814Y199734D02*
G03X292884Y198572I85J-2325D01*
G01X266304Y210841D02*
X273947Y218484D01*
G01X265747Y210841D02*
X266304D01*
G01X264736Y209830D02*
X265747Y210841D01*
G01X292884Y210272D02*
G02X294814Y211434I2015J-1163D01*
G01X291578Y209485D02*
G03X292884Y210272I-59J1575D01*
G01X291468Y209485D02*
X291578D01*
G01X289504Y208322D02*
G02X291468Y209485I2015J-1163D01*
G01X288210Y207535D02*
G03X289504Y208322I-71J1574D01*
G01X288069Y207535D02*
X288210D01*
G01X286124Y206372D02*
G02X288069Y207535I2015J-1162D01*
G01X284830Y205585D02*
G03X286124Y206372I-71J1574D01*
G01X284674Y205585D02*
X284830D01*
G01X282744Y204423D02*
G02X284674Y205585I2015J-1163D01*
G01X281423Y203635D02*
G03X282744Y204423I-44J1575D01*
G01X281328Y203635D02*
X281423D01*
G01X279364Y202472D02*
G02X281328Y203635I2015J-1163D01*
G01X278420Y201741D02*
G03X279364Y202472I-421J1519D01*
G01X275913Y199919D02*
G02X278420Y201741I3688J-2439D01*
G01X275452Y199116D02*
X275913Y199919D01*
G01X275452Y197494D02*
Y199116D01*
G01X275061Y197103D02*
X275452Y197494D01*
G01X265399Y211589D02*
X264608Y212380D01*
G01X265994Y211589D02*
X265399D01*
G01X273639Y219234D02*
X265994Y211589D01*
G01X292798Y196921D02*
X293534Y198197D01*
G01X292798Y193991D02*
Y196921D01*
G01X292548Y193741D02*
X292798Y193991D01*
G01X292548Y192255D02*
Y193741D01*
G01X292291Y191998D02*
X292548Y192255D01*
G01X292950Y214288D02*
X294899Y216909D01*
G01X292884Y214172D02*
X292950Y214288D01*
G01X291578Y213385D02*
G03X292884Y214172I-59J1575D01*
G01X291449Y213385D02*
X291578D01*
G01X289504Y212222D02*
G02X291449Y213385I2015J-1162D01*
G01X288183Y211434D02*
G03X289504Y212222I-44J1575D01*
G01X288054Y211434D02*
X288183D01*
G01X286124Y210272D02*
G02X288054Y211434I2015J-1163D01*
G01X284818Y209485D02*
G03X286124Y210272I-59J1575D01*
G01X284708Y209485D02*
X284818D01*
G01X282744Y208322D02*
G02X284708Y209485I2015J-1163D01*
G01X281450Y207535D02*
G03X282744Y208322I-71J1574D01*
G01X281309Y207535D02*
X281450D01*
G01X279364Y206372D02*
G02X281309Y207535I2015J-1162D01*
G01X278070Y205585D02*
G03X279364Y206372I-71J1574D01*
G01X277914Y205585D02*
X278070D01*
G01X275984Y204423D02*
G02X277914Y205585I2015J-1163D01*
G01X274663Y203635D02*
G03X275984Y204423I-44J1575D01*
G01X274568Y203635D02*
X274663D01*
G01X272604Y202472D02*
G02X274568Y203635I2015J-1163D01*
G01X271618Y200871D02*
X272604Y202472D01*
G01X271441Y200697D02*
X271618Y200871D01*
G01X270723Y199979D02*
X271441Y200697D01*
G01X291570Y208734D02*
G03X293534Y209897I-51J2326D01*
G01X291475Y208734D02*
X291570D01*
G01X290154Y207946D02*
G02X291475Y208734I1365J-787D01*
G01X288224Y206784D02*
G03X290154Y207946I-85J2325D01*
G01X288068Y206784D02*
X288224D01*
G01X286774Y205997D02*
G02X288068Y206784I1365J-787D01*
G01X284829Y204834D02*
G03X286774Y205997I-70J2325D01*
G01X284688Y204834D02*
X284829D01*
G01X283394Y204047D02*
G02X284688Y204834I1365J-787D01*
G01X281430Y202884D02*
G03X283394Y204047I-51J2326D01*
G01X281320Y202884D02*
X281430D01*
G01X280014Y202097D02*
G02X281320Y202884I1365J-788D01*
G01X279624Y201346D02*
X280014Y202097D01*
G01X279624Y198059D02*
Y201346D01*
G01X278366Y196801D02*
X279624Y198059D01*
G01X279153Y218194D02*
X277999Y218860D01*
G01X279236Y217884D02*
X279153Y218194D01*
G01X267163Y261760D02*
X271239D01*
G01X265259Y259856D02*
X267163Y261760D01*
G01X263537Y259856D02*
X265259D01*
G01X260530Y262863D02*
X263537Y259856D01*
G01X257892Y262863D02*
X260530D01*
G01X283534Y233385D02*
X284759Y230559D01*
G01X283394Y233672D02*
G02X283534Y233385I-2016J-1161D01*
G01X281464Y234834D02*
G02X283394Y233672I-85J-2325D01*
G01X281335Y234834D02*
X281464D01*
G01X280014Y235622D02*
G03X281335Y234834I1365J787D01*
G01X278069Y236785D02*
G02X280014Y235622I-70J-2325D01*
G01X277929Y236785D02*
X278069D01*
G01X275984Y235622D02*
G02X277929Y236785I2015J-1162D01*
G01X274663Y234834D02*
G03X275984Y235622I-44J1575D01*
G01X268483Y234834D02*
X274663D01*
G01X266187Y232538D02*
X268483Y234834D01*
G01X261850Y232538D02*
X266187D01*
G01X261436Y232952D02*
X261850Y232538D01*
G01X261045Y232952D02*
X261436D01*
G01X260576Y265363D02*
X264179Y261760D01*
G01X257892Y265363D02*
X260576D01*
G01X281013Y218860D02*
X284759D01*
G01X279553Y219948D02*
X281013Y218860D01*
G01X278084Y220435D02*
G02X279553Y219948I0J-2459D01*
G01X277955Y220435D02*
X278084D01*
G01X276634Y219647D02*
G02X277955Y220435I1365J-787D01*
G01X274689Y218484D02*
G03X276634Y219647I-70J2325D01*
G01X273947Y218484D02*
X274689D01*
G01X279429Y231232D02*
X281379Y228610D01*
G01X279364Y231346D02*
X279429Y231232D01*
G01X276634Y231346D02*
G02X279364I1365J-787D01*
G01X276129Y230841D02*
X276634Y231346D01*
G01X275277Y230841D02*
X276129D01*
G01X274689Y230935D02*
G02X275277Y230841I-70J-2326D01*
G01X274049Y230935D02*
X274689D01*
G01X274048Y230934D02*
X274049Y230935D01*
G01X269083Y230934D02*
X274048D01*
G01X267490Y229341D02*
X269083Y230934D01*
G01X263174Y229341D02*
X267490D01*
G01X261685Y227852D02*
X263174Y229341D01*
G01X260840Y227852D02*
X261685D01*
G01X263281Y257860D02*
X264179D01*
G01X260778Y260363D02*
X263281Y257860D01*
G01X258392Y260363D02*
X260778D01*
G01X260080Y242260D02*
X264092D01*
G01X259681Y242659D02*
X260080Y242260D01*
G01X258392Y242659D02*
X259681D01*
G01X267087Y246160D02*
X271239D01*
G01X265183Y244256D02*
X267087Y246160D01*
G01X260885Y244256D02*
X265183D01*
G01X259982Y245159D02*
X260885Y244256D01*
G01X258392Y245159D02*
X259982D01*
G01X274663Y219234D02*
X273639D01*
G01X275984Y220022D02*
G02X274663Y219234I-1365J787D01*
G01X277929Y221185D02*
G03X275984Y220022I70J-2325D01*
G01X278058Y221185D02*
X277929D01*
G01X279236Y221784D02*
G02X278058Y221185I-1238J976D01*
G01X279153Y222094D02*
X279236Y221784D01*
G01X277999Y222760D02*
X279153Y222094D01*
G01X286189Y227334D02*
X288139Y224709D01*
G01X286124Y227447D02*
X286189Y227334D01*
G01X284830Y228234D02*
G02X286124Y227447I-71J-1574D01*
G01X284688Y228234D02*
X284830D01*
G01X283946Y228010D02*
G02X284688Y228234I812J-1350D01*
G01X282991Y227436D02*
X283946Y228010D01*
G01X281430Y227035D02*
G03X282991Y227436I108J2818D01*
G01X281335Y227035D02*
X281430D01*
G01X280014Y227823D02*
G03X281335Y227035I1365J787D01*
G01X278084Y228985D02*
G02X280014Y227823I-85J-2325D01*
G01X276396Y228985D02*
X278084D01*
G01X275984Y229397D02*
X276396Y228985D01*
G01X274690Y230184D02*
G02X275984Y229397I-71J-1574D01*
G01X269391Y230184D02*
X274690D01*
G01X267798Y228591D02*
X269391Y230184D01*
G01X263498Y228591D02*
X267798D01*
G01X260209Y225302D02*
X263498Y228591D01*
G01X284903Y228985D02*
X288139Y228610D01*
G01X284688Y228985D02*
X284903D01*
G01X283394Y229772D02*
G03X284688Y228985I1365J787D01*
G01X283209Y230093D02*
X283394Y229772D01*
G01X282939Y232733D02*
X283209Y230093D01*
G01X282744Y233297D02*
G02X282939Y232733I-1365J-788D01*
G01X281438Y234084D02*
G02X282744Y233297I-59J-1575D01*
G01X281309Y234084D02*
X281438D01*
G01X279364Y235247D02*
G03X281309Y234084I2015J1162D01*
G01X278043Y236035D02*
G02X279364Y235247I-44J-1575D01*
G01X276634D02*
G02X278043Y236035I1365J-787D01*
G01X274689Y234084D02*
G03X276634Y235247I-70J2325D01*
G01X268791Y234084D02*
X274689D01*
G01X266495Y231788D02*
X268791Y234084D01*
G01X262594Y231788D02*
X266495D01*
G01X261208Y230402D02*
X262594Y231788D01*
G01X260898Y230402D02*
X261208D01*
G01X267088Y257860D02*
X271239D01*
G01X265191Y255963D02*
X267088Y257860D01*
G01X262778Y255963D02*
X265191D01*
G01X260878Y257863D02*
X262778Y255963D01*
G01X258392Y257863D02*
X260878D01*
G01X267063Y242260D02*
X271239D01*
G01X264962Y240159D02*
X267063Y242260D01*
G01X257892Y240159D02*
X264962D01*
G01X261680Y246160D02*
X264179D01*
G01X260181Y247659D02*
X261680Y246160D01*
G01X258392Y247659D02*
X260181D01*
G01X262056Y334836D02*
X259291D01*
G01X262977Y333915D02*
X262056Y334836D01*
G01X264605Y333913D02*
X262977Y333915D01*
G01X265251Y333913D02*
X264605D01*
G01X267198Y335860D02*
X265251Y333913D01*
G01X271239Y335860D02*
X267198D01*
G01X264949Y330247D02*
X259124D01*
G01X265685Y330983D02*
X264949Y330247D01*
G01X268043Y331960D02*
X265685Y330983D01*
G01X271239Y331960D02*
X268043D01*
G01X262703Y337336D02*
X259306D01*
G01X264179Y335860D02*
X262703Y337336D01*
G01X261647Y332336D02*
X259233D01*
G01X262023Y331960D02*
X261647Y332336D01*
G01X264179Y331960D02*
X262023D01*
G01X264096Y358691D02*
X263236Y357831D01*
G01X273848Y358691D02*
X264096D01*
G01X274041Y358884D02*
X273848Y358691D01*
G01X274689Y358884D02*
X274041D01*
G01X276634Y360047D02*
G02X274689Y358884I-2015J1162D01*
G01X277955Y360835D02*
G03X276634Y360047I44J-1575D01*
G01X278084Y360835D02*
X277955D01*
G01X280014Y361997D02*
G02X278084Y360835I-2015J1163D01*
G01X281320Y362784D02*
G03X280014Y361997I59J-1575D01*
G01X281449Y362784D02*
X281320D01*
G01X283394Y363947D02*
G02X281449Y362784I-2015J1162D01*
G01X284715Y364735D02*
G03X283394Y363947I44J-1575D01*
G01X284844Y364735D02*
X284715D01*
G01X286774Y365897D02*
G02X284844Y364735I-2015J1163D01*
G01X288139Y369010D02*
X286774Y365897D01*
G01X293174Y400044D02*
X289939Y403279D01*
G01X261108Y399581D02*
X257180Y403509D01*
G01X262288Y399581D02*
X261108D01*
G01X267647Y394221D02*
X262288Y399581D01*
G01X268509Y394221D02*
X267647D01*
G01X268803Y393927D02*
X268509Y394221D01*
G01X269224Y393197D02*
X268803Y393927D01*
G01X271169Y392034D02*
G02X269224Y393197I70J2325D01*
G01X271310Y392034D02*
X271169D01*
G01X272604Y391247D02*
G03X271310Y392034I-1365J-787D01*
G01X274534Y390085D02*
G02X272604Y391247I85J2325D01*
G01X274663Y390085D02*
X274534D01*
G01X275984Y389297D02*
G03X274663Y390085I-1365J-787D01*
G01X277914Y388135D02*
G02X275984Y389297I85J2325D01*
G01X278043Y388135D02*
X277914D01*
G01X279364Y387347D02*
G03X278043Y388135I-1365J-787D01*
G01X281309Y386184D02*
G02X279364Y387347I70J2325D01*
G01X281438Y386184D02*
X281309D01*
G01X282744Y385397D02*
G03X281438Y386184I-1365J-788D01*
G01X284674Y384235D02*
G02X282744Y385397I85J2325D01*
G01X284803Y384235D02*
X284674D01*
G01X286124Y383447D02*
G03X284803Y384235I-1365J-787D01*
G01X288069Y382284D02*
G02X286124Y383447I70J2325D01*
G01X288198Y382284D02*
X288069D01*
G01X289504Y381497D02*
G03X288198Y382284I-1365J-788D01*
G01X291434Y380335D02*
G02X289504Y381497I85J2325D01*
G01X291563Y380335D02*
X291434D01*
G01X292884Y379547D02*
G03X291563Y380335I-1365J-787D01*
G01X294642Y378397D02*
G02X292884Y379547I257J2312D01*
G01X261418Y400329D02*
X257553Y404194D01*
G01X262598Y400329D02*
X261418D01*
G01X267957Y394969D02*
X262598Y400329D01*
G01X268819Y394969D02*
X267957D01*
G01X269402Y394386D02*
X268819Y394969D01*
G01X269872Y393571D02*
X269402Y394386D01*
G01X269874Y393572D02*
X269872Y393571D01*
G01X271168Y392785D02*
G02X269874Y393572I71J1574D01*
G01X271324Y392785D02*
X271168D01*
G01X273254Y391623D02*
G03X271324Y392785I-2015J-1163D01*
G01X274575Y390835D02*
G02X273254Y391623I44J1575D01*
G01X274704Y390835D02*
X274575D01*
G01X276634Y389673D02*
G03X274704Y390835I-2015J-1163D01*
G01X277955Y388885D02*
G02X276634Y389673I44J1575D01*
G01X278069Y388885D02*
X277955D01*
G01X280014Y387722D02*
G03X278069Y388885I-2015J-1162D01*
G01X281335Y386934D02*
G02X280014Y387722I44J1575D01*
G01X281464Y386934D02*
X281335D01*
G01X283394Y385772D02*
G03X281464Y386934I-2015J-1163D01*
G01X284700Y384985D02*
G02X283394Y385772I59J1575D01*
G01X284829Y384985D02*
X284700D01*
G01X286774Y383822D02*
G03X284829Y384985I-2015J-1162D01*
G01X288095Y383034D02*
G02X286774Y383822I44J1575D01*
G01X288224Y383034D02*
X288095D01*
G01X290154Y381872D02*
G03X288224Y383034I-2015J-1163D01*
G01X291460Y381085D02*
G02X290154Y381872I59J1575D01*
G01X291589Y381085D02*
X291460D01*
G01X293534Y379922D02*
G03X291589Y381085I-2015J-1162D01*
G01X264179Y351460D02*
X259422D01*
G01X264206Y359439D02*
X263264Y360381D01*
G01X273538Y359439D02*
X264206D01*
G01X273733Y359634D02*
X273538Y359439D01*
G01X274663Y359634D02*
X273733D01*
G01X275984Y360422D02*
G02X274663Y359634I-1365J787D01*
G01X277929Y361585D02*
G03X275984Y360422I70J-2325D01*
G01X278058Y361585D02*
X277929D01*
G01X279364Y362372D02*
G02X278058Y361585I-1365J788D01*
G01X281294Y363534D02*
G03X279364Y362372I85J-2325D01*
G01X281423Y363534D02*
X281294D01*
G01X282744Y364322D02*
G02X281423Y363534I-1365J787D01*
G01X282810Y364437D02*
X282744Y364322D01*
G01X284759Y367060D02*
X282810Y364437D01*
G01X263613Y364513D02*
X262499Y365627D01*
G01X263976Y364513D02*
X263613D01*
G01X264955Y363534D02*
X263976Y364513D01*
G01X274663Y363534D02*
X264955D01*
G01X275984Y364322D02*
G02X274663Y363534I-1365J787D01*
G01X277929Y365485D02*
G03X275984Y364322I70J-2325D01*
G01X278058Y365485D02*
X277929D01*
G01X279364Y366272D02*
G02X278058Y365485I-1365J788D01*
G01X279430Y366387D02*
X279364Y366272D01*
G01X281379Y369010D02*
X279430Y366387D01*
G01X263188Y363765D02*
X262499Y363076D01*
G01X263666Y363765D02*
X263188D01*
G01X264647Y362784D02*
X263666Y363765D01*
G01X274689Y362784D02*
X264647D01*
G01X276634Y363947D02*
G02X274689Y362784I-2015J1162D01*
G01X277955Y364735D02*
G03X276634Y363947I44J-1575D01*
G01X278084Y364735D02*
X277955D01*
G01X280014Y365897D02*
G02X278084Y364735I-2015J1163D01*
G01X281320Y366684D02*
G03X280014Y365897I59J-1575D01*
G01X281430Y366684D02*
X281320D01*
G01X283394Y367847D02*
G02X281430Y366684I-2015J1163D01*
G01X284688Y368634D02*
G03X283394Y367847I71J-1574D01*
G01X284829Y368634D02*
X284688D01*
G01X286774Y369797D02*
G02X284829Y368634I-2015J1162D01*
G01X286841Y369912D02*
X286774Y369797D01*
G01X288139Y372909D02*
X286841Y369912D01*
G01X268778Y398991D02*
X261053Y406716D01*
G01X268778Y397357D02*
Y398991D01*
G01X270203Y395932D02*
X268778Y397357D01*
G01X271244Y395932D02*
X270203D01*
G01X272604Y395146D02*
G03X271244Y395932I-1360J-784D01*
G01X274534Y393984D02*
G02X272604Y395146I85J2325D01*
G01X274690Y393984D02*
X274534D01*
G01X275984Y393197D02*
G03X274690Y393984I-1365J-787D01*
G01X277929Y392034D02*
G02X275984Y393197I70J2325D01*
G01X278070Y392034D02*
X277929D01*
G01X279364Y391247D02*
G03X278070Y392034I-1365J-787D01*
G01X281328Y390084D02*
G02X279364Y391247I51J2326D01*
G01X281438Y390084D02*
X281328D01*
G01X282744Y389297D02*
G03X281438Y390084I-1365J-788D01*
G01X284674Y388135D02*
G02X282744Y389297I85J2325D01*
G01X284803Y388135D02*
X284674D01*
G01X286124Y387347D02*
G03X284803Y388135I-1365J-787D01*
G01X288069Y386184D02*
G02X286124Y387347I70J2325D01*
G01X288198Y386184D02*
X288069D01*
G01X289504Y385397D02*
G03X288198Y386184I-1365J-788D01*
G01X291434Y384235D02*
G02X289504Y385397I85J2325D01*
G01X291563Y384235D02*
X291434D01*
G01X292884Y383447D02*
G03X291563Y384235I-1365J-787D01*
G01X294829Y382284D02*
G02X292884Y383447I70J2325D01*
G01X286409Y400053D02*
X275946Y410516D01*
G01X286774Y399421D02*
X286409Y400053D01*
G01X288095Y398634D02*
G02X286774Y399421I44J1576D01*
G01X288224Y398634D02*
X288095D01*
G01X290154Y397472D02*
G03X288224Y398634I-2015J-1163D01*
G01X291460Y396685D02*
G02X290154Y397472I59J1575D01*
G01X291570Y396685D02*
X291460D01*
G01X293534Y395522D02*
G03X291570Y396685I-2015J-1163D01*
G01X256248Y391041D02*
X254978D01*
G01X262048Y385241D02*
X256248Y391041D01*
G01X262048Y380615D02*
Y385241D01*
G01X264722Y377941D02*
X262048Y380615D01*
G01X272048Y377941D02*
X264722D01*
G01X272491Y378384D02*
X272048Y377941D01*
G01X275704Y378384D02*
X272491D01*
G01X277097Y376991D02*
X275704Y378384D01*
G01X279198Y376991D02*
X277097D01*
G01X281379Y379172D02*
X279198Y376991D01*
G01X281379Y380709D02*
Y379172D01*
G01X256748Y391599D02*
Y392878D01*
G01X262796Y385551D02*
X256748Y391599D01*
G01X262796Y380925D02*
Y385551D01*
G01X265032Y378689D02*
X262796Y380925D01*
G01X271735Y378689D02*
X265032D01*
G01X272180Y379134D02*
X271735Y378689D01*
G01X276144Y379134D02*
X272180D01*
G01X276518Y378760D02*
X276144Y379134D01*
G01X277999Y378760D02*
X276518D01*
G01X262901Y354000D02*
X259480D01*
G01X263355Y353546D02*
X262901Y354000D01*
G01X264941Y353546D02*
X263355D01*
G01X267027Y351460D02*
X264941Y353546D01*
G01X271239Y351460D02*
X267027D01*
G01X287430Y402529D02*
X285238Y404721D01*
G01X289627Y402529D02*
X287430D01*
G01X292573Y399583D02*
X289627Y402529D01*
G01X292884Y399045D02*
X292573Y399583D01*
G01X294814Y397883D02*
G02X292884Y399045I85J2325D01*
G01X285804Y399600D02*
X275243Y410161D01*
G01X286123Y399047D02*
X285804Y399600D01*
G01X288075Y397884D02*
G02X286123Y399047I63J2325D01*
G01X288085Y397884D02*
G02X288075I-5J2326D01*
G01X288198D02*
X288085D01*
G01X289504Y397097D02*
G03X288198Y397884I-1365J-788D01*
G01X291468Y395934D02*
G02X289504Y397097I51J2326D01*
G01X291563Y395934D02*
X291468D01*
G01X292884Y395146D02*
G03X291563Y395934I-1365J-787D01*
G01X294814Y393984D02*
G02X292884Y395146I85J2325D01*
G01X265013Y349616D02*
X259334D01*
G01X267069Y347560D02*
X265013Y349616D01*
G01X271239Y347560D02*
X267069D01*
G01X257684Y382405D02*
X256400D01*
G01X258241Y381848D02*
X257684Y382405D01*
G01X258241Y379648D02*
Y381848D01*
G01X262948Y374941D02*
X258241Y379648D01*
G01X272948Y374941D02*
X262948D01*
G01X273405Y374484D02*
X272948Y374941D01*
G01X275304Y374484D02*
X273405D01*
G01X276634Y374072D02*
X275304Y374484D01*
G01X277940Y373285D02*
G02X276634Y374072I59J1575D01*
G01X278058Y373285D02*
X277940D01*
G01X279364Y374072D02*
G02X278058Y373285I-1365J788D01*
G01X281294Y375234D02*
G03X279364Y374072I85J-2325D01*
G01X281423Y375234D02*
X281294D01*
G01X282744Y376022D02*
G02X281423Y375234I-1365J787D01*
G01X282810Y376138D02*
X282744Y376022D01*
G01X284759Y378760D02*
X282810Y376138D01*
G01X269526Y399301D02*
X261660Y407167D01*
G01X269526Y397667D02*
Y399301D01*
G01X270508Y396685D02*
X269526Y397667D01*
G01X271290Y396685D02*
X270508D01*
G01X273254Y395522D02*
G03X271290Y396685I-2015J-1163D01*
G01X274548Y394735D02*
G02X273254Y395522I71J1574D01*
G01X274689Y394735D02*
X274548D01*
G01X276634Y393572D02*
G03X274689Y394735I-2015J-1162D01*
G01X277928Y392785D02*
G02X276634Y393572I71J1574D01*
G01X278084Y392785D02*
X277928D01*
G01X280014Y391623D02*
G03X278084Y392785I-2015J-1163D01*
G01X281335Y390835D02*
G02X280014Y391623I44J1575D01*
G01X281430Y390835D02*
X281335D01*
G01X283394Y389672D02*
G03X281430Y390835I-2015J-1163D01*
G01X284700Y388885D02*
G02X283394Y389672I59J1575D01*
G01X284829Y388885D02*
X284700D01*
G01X286774Y387722D02*
G03X284829Y388885I-2015J-1162D01*
G01X288095Y386934D02*
G02X286774Y387722I44J1575D01*
G01X288224Y386934D02*
X288095D01*
G01X290154Y385772D02*
G03X288224Y386934I-2015J-1163D01*
G01X291460Y384985D02*
G02X290154Y385772I59J1575D01*
G01X291589Y384985D02*
X291460D01*
G01X293534Y383822D02*
G03X291589Y384985I-2015J-1162D01*
G01X258104Y383043D02*
Y384308D01*
G01X258989Y382158D02*
X258104Y383043D01*
G01X258989Y379958D02*
Y382158D01*
G01X263258Y375689D02*
X258989Y379958D01*
G01X273261Y375689D02*
X263258D01*
G01X273716Y375234D02*
X273261Y375689D01*
G01X276305Y375234D02*
X273716D01*
G01X276679Y374860D02*
X276305Y375234D01*
G01X277999Y374860D02*
X276679D01*
G01X264179Y347560D02*
X259334D01*
G01X280841Y412856D02*
Y414135D01*
G01X285986Y407711D02*
X280841Y412856D01*
G01X285986Y405031D02*
Y407711D01*
G01X287738Y403279D02*
X285986Y405031D01*
G01X289939Y403279D02*
X287738D01*
G01X257180Y403509D02*
X255750D01*
G01X257553Y404194D02*
Y405313D01*
G01X259857Y406716D02*
X259808Y406667D01*
G01X261053Y406716D02*
X259857D01*
G01X275946Y411866D02*
X275722Y412090D01*
G01X275946Y410516D02*
Y411866D01*
G01X279088Y412331D02*
X279063Y412356D01*
G01X280308Y412331D02*
X279088D01*
G01X285238Y407401D02*
X280308Y412331D01*
G01X285238Y404721D02*
Y407401D01*
G01X275243Y410161D02*
X274044D01*
G01X261660Y407167D02*
Y408422D01*
G01X296198Y217810D02*
X294899Y220809D01*
G01X296264Y217697D02*
X296198Y217810D01*
G01X296283Y216156D02*
G03X296264Y217697I-1384J754D01*
G01Y216122D02*
X296283Y216156D01*
G01X295616Y214998D02*
X296264Y216122D01*
G01X294899Y214584D02*
G03X295616Y214998I0J828D01*
G01X294840Y214584D02*
X294899D01*
G01X293534Y213797D02*
G02X294840Y214584I1365J-788D01*
G01X317623Y217383D02*
X317193Y218073D01*
G01X317623Y207937D02*
Y217383D01*
G01X318086Y207474D02*
X317623Y207937D01*
G01X318086Y203341D02*
Y207474D01*
G01X310926Y196181D02*
X318086Y203341D01*
G01X310926Y194933D02*
Y196181D01*
G01X311868Y193991D02*
X310926Y194933D01*
G01X349298Y201759D02*
Y200994D01*
G01X347613Y204423D02*
X349298Y201759D01*
G01X347613Y205997D02*
G03Y204423I1365J-787D01*
G01X347638Y206039D02*
X347613Y205997D01*
G01Y208322D02*
G02X347638Y206039I-2015J-1164D01*
G01X347594Y208356D02*
X347613Y208322D01*
G01Y209897D02*
G03X347594Y208356I1365J-787D01*
G01X347638Y212180D02*
G02X347613Y209897I-2040J-1119D01*
G01Y212222D02*
X347638Y212180D01*
G01X347594Y212256D02*
X347613Y212222D01*
G01Y213797D02*
G03X347594Y212256I1365J-787D01*
G01X347638Y216080D02*
G02X347613Y213797I-2040J-1119D01*
G01Y216122D02*
X347638Y216080D01*
G01X347594Y216156D02*
X347613Y216122D01*
G01Y217697D02*
G03X347594Y216156I1365J-787D01*
G01X347638Y219980D02*
G02X347613Y217697I-2040J-1119D01*
G01X347298Y203468D02*
Y201105D01*
G01X346963Y204047D02*
X347298Y203468D01*
G01X346938Y206330D02*
G03X346963Y204047I2040J-1119D01*
G01Y206372D02*
X346938Y206330D01*
G01X346963Y207946D02*
G02Y206372I-1365J-787D01*
G01Y210272D02*
G03Y207946I2015J-1163D01*
G01X346982Y211813D02*
G02X346963Y210272I-1384J-754D01*
G01Y211847D02*
X346982Y211813D01*
G01X346938Y211889D02*
X346963Y211847D01*
G01Y214172D02*
G03X346938Y211889I2015J-1164D01*
G01X346982Y215713D02*
G02X346963Y214172I-1384J-754D01*
G01Y215747D02*
X346982Y215713D01*
G01X346938Y215789D02*
X346963Y215747D01*
G01Y218072D02*
G03X346938Y215789I2015J-1164D01*
G01X344258D02*
G03X344233Y218072I-2040J1119D01*
G01Y215747D02*
X344258Y215789D01*
G01X344214Y215713D02*
X344233Y215747D01*
G01Y214172D02*
G02X344214Y215713I1365J787D01*
G01X344258Y211889D02*
G03X344233Y214172I-2040J1119D01*
G01Y211847D02*
X344258Y211889D01*
G01X344214Y211813D02*
X344233Y211847D01*
G01Y210272D02*
G02X344214Y211813I1365J787D01*
G01X344233Y207946D02*
G03Y210272I-2015J1163D01*
G01Y206372D02*
G02Y207946I1365J787D01*
G01X344258Y206330D02*
X344233Y206372D01*
G01Y204047D02*
G03X344258Y206330I-2015J1164D01*
G01X344023Y203672D02*
X344233Y204047D01*
G01X344023Y202594D02*
Y203672D01*
G01X345298Y201319D02*
X344023Y202594D01*
G01X345298Y200336D02*
Y201319D01*
G01X332376Y215186D02*
X330713Y218073D01*
G01X332376Y203254D02*
Y215186D01*
G01X333286Y202344D02*
X332376Y203254D01*
G01X333286Y200293D02*
Y202344D01*
G01X331286Y198293D02*
X333286Y200293D01*
G01X331286Y194689D02*
Y198293D01*
G01X331789Y194186D02*
X331286Y194689D01*
G01X294943Y199734D02*
X294814D01*
G01X296264Y200522D02*
G02X294943Y199734I-1365J787D01*
G01X298209Y201685D02*
G03X296264Y200522I70J-2325D01*
G01X300410Y201685D02*
X298209D01*
G01X306616Y207891D02*
X300410Y201685D01*
G01X306616Y209151D02*
Y207891D01*
G01X306615Y209152D02*
X306616Y209151D01*
G01X306614Y211060D02*
X306615Y209152D01*
G01X306403Y211847D02*
G02X306614Y211060I-1365J-788D01*
G01X306241Y212188D02*
G03X306403Y211847I2176J825D01*
G01X305039Y214960D02*
X306241Y212188D01*
G01X343273Y203868D02*
Y200681D01*
G01X343583Y204422D02*
X343273Y203868D01*
G01X343583Y205997D02*
G02Y204422I-1365J-787D01*
G01X343558Y206039D02*
X343583Y205997D01*
G01Y208322D02*
G03X343558Y206039I2015J-1164D01*
G01X343602Y208356D02*
X343583Y208322D01*
G01Y209897D02*
G02X343602Y208356I-1365J-787D01*
G01X343558Y212180D02*
G03X343583Y209897I2040J-1119D01*
G01Y212222D02*
X343558Y212180D01*
G01X343602Y212256D02*
X343583Y212222D01*
G01Y213797D02*
G02X343602Y212256I-1365J-787D01*
G01X343558Y216080D02*
G03X343583Y213797I2040J-1119D01*
G01Y216122D02*
X343558Y216080D01*
G01X343602Y216156D02*
X343583Y216122D01*
G01Y217697D02*
G02X343602Y216156I-1365J-787D01*
G01X343558Y219980D02*
G03X343583Y217697I2040J-1119D01*
G01X353290Y203902D02*
X355298Y201894D01*
G01X353290Y209525D02*
Y203902D01*
G01X353722Y210273D02*
X353290Y209525D01*
G01X353741Y211813D02*
G02X353722Y210273I-1384J-753D01*
G01Y211847D02*
X353741Y211813D01*
G01X353697Y211889D02*
X353722Y211847D01*
G01Y214172D02*
G03X353697Y211889I2015J-1164D01*
G01X353741Y215713D02*
G02X353722Y214172I-1384J-754D01*
G01Y215747D02*
X353741Y215713D01*
G01X353697Y215789D02*
X353722Y215747D01*
G01Y218072D02*
G03X353697Y215789I2015J-1164D01*
G01X330063Y217698D02*
G02Y220022I2015J1162D01*
G01X331626Y214987D02*
X330063Y217698D01*
G01X331626Y202943D02*
Y214987D01*
G01X332538Y202031D02*
X331626Y202943D01*
G01X332538Y200615D02*
Y202031D01*
G01X330538Y198615D02*
X332538Y200615D01*
G01X330538Y195504D02*
Y198615D01*
G01X329220Y194186D02*
X330538Y195504D01*
G01X328198Y214322D02*
Y218522D01*
G01X329356Y213164D02*
X328198Y214322D01*
G01X329356Y200881D02*
Y213164D01*
G01X328550Y200075D02*
X329356Y200881D01*
G01X328550Y197312D02*
Y200075D01*
G01X325788Y194550D02*
X328550Y197312D01*
G01X325788Y192931D02*
Y194550D01*
G01X326578Y192141D02*
X325788Y192931D01*
G01X296330Y212338D02*
X298279Y214960D01*
G01X296264Y212222D02*
X296330Y212338D01*
G01X294943Y211434D02*
G03X296264Y212222I-44J1575D01*
G01X294814Y211434D02*
X294943D01*
G01X327448Y214011D02*
Y218323D01*
G01X328608Y212851D02*
X327448Y214011D01*
G01X328608Y201191D02*
Y212851D01*
G01X327800Y200383D02*
X328608Y201191D01*
G01X327800Y197623D02*
Y200383D01*
G01X325038Y194861D02*
X327800Y197623D01*
G01X325038Y193141D02*
Y194861D01*
G01X324028Y192131D02*
X325038Y193141D01*
G01X354092Y204400D02*
X356398Y202094D01*
G01X354092Y209412D02*
Y204400D01*
G01X354372Y209897D02*
X354092Y209412D01*
G01X354397Y212180D02*
G02X354372Y209897I-2040J-1119D01*
G01Y212222D02*
X354397Y212180D01*
G01X354353Y212256D02*
X354372Y212222D01*
G01Y213797D02*
G03X354353Y212256I1365J-787D01*
G01X354397Y216080D02*
G02X354372Y213797I-2040J-1119D01*
G01Y216122D02*
X354397Y216080D01*
G01X354353Y216156D02*
X354372Y216122D01*
G01Y217697D02*
G03X354353Y216156I1365J-787D01*
G01X354397Y219980D02*
G02X354372Y217697I-2040J-1119D01*
G01X337273Y192612D02*
Y190678D01*
G01X338503Y193842D02*
X337273Y192612D01*
G01X338503Y201089D02*
Y193842D01*
G01X337262Y202330D02*
X338503Y201089D01*
G01X337262Y211047D02*
Y202330D01*
G01X337473Y211848D02*
G03X337262Y211047I1365J-788D01*
G01X337473Y214174D02*
G02Y211848I-2015J-1163D01*
G01Y215748D02*
G03Y214174I1365J-787D01*
G01Y218074D02*
G02Y215748I-2015J-1163D01*
G01X295898Y193746D02*
Y192029D01*
G01X299837Y197685D02*
X295898Y193746D01*
G01X300687Y197685D02*
X299837D01*
G01X309470Y206468D02*
X300687Y197685D01*
G01X309470Y211056D02*
Y206468D01*
G01X309758Y212179D02*
G03X309470Y211056I2047J-1123D01*
G01X309783Y212221D02*
X309758Y212179D01*
G01X309783Y213795D02*
G02Y212221I-1365J-787D01*
G01X309116Y214947D02*
X309783Y213795D01*
G01X308418Y216909D02*
X309116Y214947D01*
G01X295898Y190692D02*
Y192029D01*
G01X295147Y189941D02*
X295898Y190692D01*
G01X293841Y189941D02*
X295147D01*
G01X353298Y202494D02*
Y200493D01*
G01X352192Y203600D02*
X353298Y202494D01*
G01X352192Y206284D02*
Y203600D01*
G01X351242Y209837D02*
G02X352192Y206284I-6168J-3553D01*
G01X350991Y210272D02*
X351242Y209837D01*
G01X350963Y211796D02*
G03X350991Y210272I1394J-737D01*
G01X350992Y211847D02*
G02X350963Y211796I-2033J1122D01*
G01X350993Y211847D02*
X350992D01*
G01X351028Y211907D02*
X350993Y211847D01*
G01X351024Y214117D02*
G02X351028Y211907I-2046J-1109D01*
G01X351023Y214122D02*
X351024Y214117D01*
G01X350993Y214174D02*
X351023Y214122D01*
G01X350993Y215748D02*
G03Y214174I1364J-787D01*
G01Y218074D02*
G02Y215748I-2015J-1163D01*
G01X307053Y216123D02*
G02X306590Y218590I3278J1892D01*
G01X307053Y213797D02*
G03Y216123I-2015J1163D01*
G01Y212223D02*
G02Y213797I1365J787D01*
G01X307365Y211060D02*
G03X307053Y212223I-2327J-1D01*
G01X307365Y207581D02*
Y211060D01*
G01X307366Y207580D02*
X307365Y207581D01*
G01X300721Y200935D02*
X307366Y207580D01*
G01X298235Y200935D02*
X300721D01*
G01X296914Y200147D02*
G02X298235Y200935I1365J-787D01*
G01X294969Y198984D02*
G03X296914Y200147I-70J2325D01*
G01X294840Y198984D02*
X294969D01*
G01X293534Y198197D02*
G02X294840Y198984I1365J-788D01*
G01X313813Y217697D02*
G03X313838Y219980I-2015J1164D01*
G01X313794Y216156D02*
G02X313813Y217697I1384J754D01*
G01Y216122D02*
X313794Y216156D01*
G01X313838Y216080D02*
X313813Y216122D01*
G01Y213797D02*
G03X313838Y216080I-2015J1164D01*
G01X313794Y212256D02*
G02X313813Y213797I1384J754D01*
G01Y212222D02*
X313794Y212256D01*
G01X313838Y212180D02*
X313813Y212222D01*
G01Y209897D02*
G03X313838Y212180I-2015J1164D01*
G01X313329Y209058D02*
X313813Y209897D01*
G01X313329Y207350D02*
Y209058D01*
G01X314498Y206181D02*
X313329Y207350D01*
G01X314498Y204062D02*
Y206181D01*
G01X305824Y195388D02*
X314498Y204062D01*
G01X305824Y194455D02*
Y195388D01*
G01X306768Y193511D02*
X305824Y194455D01*
G01X351298Y201374D02*
Y200173D01*
G01X351092Y201580D02*
X351298Y201374D01*
G01X351092Y207099D02*
Y201580D01*
G01X350342Y209896D02*
G02X351092Y207099I-4842J-2797D01*
G01X350307Y212162D02*
G03X350342Y209896I2050J-1102D01*
G01Y212222D02*
X350307Y212162D01*
G01X350342Y213796D02*
G02Y212222I-1364J-787D01*
G01X350307Y216062D02*
G03X350342Y213796I2050J-1102D01*
G01Y216122D02*
X350307Y216062D01*
G01X350342Y217696D02*
G02Y216122I-1364J-787D01*
G01X350307Y219962D02*
G03X350342Y217696I2050J-1102D01*
G01X339273Y192357D02*
Y191212D01*
G01X339746Y192830D02*
X339273Y192357D01*
G01X339746Y201699D02*
Y192830D01*
G01X340423Y202376D02*
X339746Y201699D01*
G01X340423Y203666D02*
Y202376D01*
G01X340203Y204048D02*
X340423Y203666D01*
G01X340203Y206372D02*
G03Y204048I2015J-1162D01*
G01Y207946D02*
G02Y206372I-1365J-787D01*
G01Y210272D02*
G03Y207946I2015J-1163D01*
G01X340222Y211813D02*
G02X340203Y210272I-1384J-754D01*
G01Y211847D02*
X340222Y211813D01*
G01X340178Y211889D02*
X340203Y211847D01*
G01Y214172D02*
G03X340178Y211889I2015J-1164D01*
G01X340222Y215713D02*
G02X340203Y214172I-1384J-754D01*
G01Y215747D02*
X340222Y215713D01*
G01X340178Y215789D02*
X340203Y215747D01*
G01Y218072D02*
G03X340178Y215789I2015J-1164D01*
G01X310000Y214947D02*
Y220549D01*
G01X310433Y214171D02*
X310000Y214947D01*
G01X310458Y211888D02*
G03X310433Y214171I-2040J1119D01*
G01Y211846D02*
X310458Y211888D01*
G01X310222Y211060D02*
G02X310433Y211846I1576J-2D01*
G01X310220Y209161D02*
X310222Y211060D01*
G01X310220Y206157D02*
Y209161D01*
G01X300998Y196935D02*
X310220Y206157D01*
G01X300148Y196935D02*
X300998D01*
G01X296648Y193435D02*
X300148Y196935D01*
G01X296648Y192029D02*
Y193435D01*
G01Y190241D02*
Y192029D01*
G01X295748Y189341D02*
X296648Y190241D01*
G01X295748Y188241D02*
Y189341D01*
G01X341273Y203694D02*
Y200481D01*
G01X340853Y204423D02*
X341273Y203694D01*
G01X340853Y205997D02*
G03Y204423I1365J-787D01*
G01X340878Y206039D02*
X340853Y205997D01*
G01Y208322D02*
G02X340878Y206039I-2015J-1164D01*
G01X340834Y208356D02*
X340853Y208322D01*
G01Y209897D02*
G03X340834Y208356I1365J-787D01*
G01X340878Y212180D02*
G02X340853Y209897I-2040J-1119D01*
G01Y212222D02*
X340878Y212180D01*
G01X340834Y212256D02*
X340853Y212222D01*
G01Y213797D02*
G03X340834Y212256I1365J-787D01*
G01X340878Y216080D02*
G02X340853Y213797I-2040J-1119D01*
G01Y216122D02*
X340878Y216080D01*
G01X340834Y216156D02*
X340853Y216122D01*
G01Y217697D02*
G03X340834Y216156I1365J-787D01*
G01X340878Y219980D02*
G02X340853Y217697I-2040J-1119D01*
G01X310178Y194851D02*
X309592Y194265D01*
G01X310178Y196491D02*
Y194851D01*
G01X317338Y203651D02*
X310178Y196491D01*
G01X317338Y207161D02*
Y203651D01*
G01X316873Y207626D02*
X317338Y207161D01*
G01X316873Y217073D02*
Y207626D01*
G01X316543Y217698D02*
X316873Y217073D01*
G01X316543Y220022D02*
G03Y217698I2015J-1162D01*
G01X297159Y217752D02*
G02X296895Y219613I1120J1108D01*
G01X298966Y216378D02*
G02X297159Y217752I2504J5168D01*
G01X299644Y214172D02*
G03X298966Y216378I-1365J788D01*
G01X298448Y213041D02*
G03X299644Y214172I-1299J2571D01*
G01X297320Y212309D02*
G02X298448Y213041I5343J-6998D01*
G01X296914Y211847D02*
G02X297320Y212309I1355J-781D01*
G01X294969Y210684D02*
G03X296914Y211847I-70J2325D01*
G01X294840Y210684D02*
X294969D01*
G01X293534Y209897D02*
G02X294840Y210684I1365J-788D01*
G01X313138Y215789D02*
G02X313163Y218072I2040J1119D01*
G01Y215747D02*
X313138Y215789D01*
G01X313182Y215713D02*
X313163Y215747D01*
G01Y214172D02*
G03X313182Y215713I-1365J787D01*
G01X313138Y211889D02*
G02X313163Y214172I2040J1119D01*
G01Y211847D02*
X313138Y211889D01*
G01X313182Y211813D02*
X313163Y211847D01*
G01Y210272D02*
G03X313182Y211813I-1365J787D01*
G01X312579Y209259D02*
X313163Y210272D01*
G01X312579Y207172D02*
Y209259D01*
G01X311308Y205901D02*
X312579Y207172D01*
G01X311308Y203841D02*
Y205901D01*
G01X311748Y203401D02*
X311308Y203841D01*
G01X311748Y202382D02*
Y203401D01*
G01X305068Y195702D02*
X311748Y202382D01*
G01X305068Y194461D02*
Y195702D01*
G01X304218Y193611D02*
X305068Y194461D01*
G01X325318Y247961D02*
Y246160D01*
G01X324818Y248461D02*
X325318Y247961D01*
G01X323948Y248461D02*
X324818D01*
G01X323743Y248256D02*
X323948Y248461D01*
G01X323743Y245096D02*
Y248256D01*
G01X324338Y244501D02*
X323743Y245096D01*
G01X324338Y243666D02*
Y244501D01*
G01X323743Y243071D02*
X324338Y243666D01*
G01X323743Y242279D02*
Y243071D01*
G01X324714Y240804D02*
G02X323743Y242279I604J1455D01*
G01X326568Y239318D02*
G03X324714Y240804I-3490J-2454D01*
G01X325892Y236892D02*
G03X326568Y239318I-574J1467D01*
G01X323953Y235246D02*
G02X325892Y236892I3267J-1884D01*
G01X322008Y234084D02*
G03X323953Y235246I-68J2323D01*
G01X321879Y234084D02*
X322008D01*
G01X320573Y233297D02*
G02X321879Y234084I1365J-788D01*
G01X318609Y232134D02*
G03X320573Y233297I-51J2326D01*
G01X318514Y232134D02*
X318609D01*
G01X317193Y229772D02*
G02X318514Y232134I1365J787D01*
G01X317218Y229730D02*
X317193Y229772D01*
G01Y227447D02*
G03X317218Y229730I-2015J1164D01*
G01X317174Y227413D02*
X317193Y227447D01*
G01Y225872D02*
G02X317174Y227413I1365J787D01*
G01X317218Y223589D02*
G03X317193Y225872I-2040J1119D01*
G01Y223547D02*
X317218Y223589D01*
G01X317174Y223513D02*
X317193Y223547D01*
G01Y221972D02*
G02X317174Y223513I1365J787D01*
G01X317218Y219689D02*
G03X317193Y221972I-2040J1119D01*
G01Y219647D02*
X317218Y219689D01*
G01X317193Y218073D02*
G02Y219647I1365J787D01*
G01X347613Y220022D02*
X347638Y219980D01*
G01X347594Y220056D02*
X347613Y220022D01*
G01Y221597D02*
G03X347594Y220056I1365J-787D01*
G01X347638Y223880D02*
G02X347613Y221597I-2040J-1119D01*
G01Y223922D02*
X347638Y223880D01*
G01X347594Y223956D02*
X347613Y223922D01*
G01Y225497D02*
G03X347594Y223956I1365J-787D01*
G01X347613Y227823D02*
G02Y225497I-2015J-1163D01*
G01Y229397D02*
G03Y227823I1365J-787D01*
G01X347775Y229678D02*
X347613Y229397D01*
G01X348813Y230516D02*
X347775Y229678D01*
G01X349800Y231166D02*
X348813Y230516D01*
G01X350342Y231722D02*
G02X349800Y231166I-1364J787D01*
G01X350405Y231832D02*
X350342Y231722D01*
G01X352357Y234460D02*
X350405Y231832D01*
G01X346982Y219613D02*
G02X346963Y218072I-1384J-754D01*
G01Y219647D02*
X346982Y219613D01*
G01X346938Y219689D02*
X346963Y219647D01*
G01Y221972D02*
G03X346938Y219689I2015J-1164D01*
G01X346982Y223513D02*
G02X346963Y221972I-1384J-754D01*
G01Y223547D02*
X346982Y223513D01*
G01X346938Y223589D02*
X346963Y223547D01*
G01Y225872D02*
G03X346938Y223589I2015J-1164D01*
G01X346982Y227413D02*
G02X346963Y225872I-1384J-754D01*
G01Y227447D02*
X346982Y227413D01*
G01X346938Y229730D02*
G03X346963Y227447I2040J-1119D01*
G01X347132Y230066D02*
X346938Y229730D01*
G01X347347Y231591D02*
X347132Y230066D01*
G01X347403Y232463D02*
X347347Y231591D01*
G01X348555Y234027D02*
G03X347403Y232463I423J-1518D01*
G01X349028Y234500D02*
X348555Y234027D01*
G01X349892Y234500D02*
X349028D01*
G01X350892Y235500D02*
X349892Y234500D01*
G01X350892Y237499D02*
Y235500D01*
G01X348978Y239413D02*
X350892Y237499D01*
G01X348978Y240309D02*
Y239413D01*
G01X347800Y236409D02*
X348978D01*
G01X347192Y235801D02*
X347800Y236409D01*
G01X347192Y234404D02*
Y235801D01*
G01X347029Y233788D02*
G03X347192Y234404I-1083J616D01*
G01X346963Y233672D02*
X347029Y233788D01*
G01X346427Y233120D02*
G03X346963Y233672I-828J1341D01*
G01X345888Y232803D02*
X346427Y233120D01*
G01X344398Y231632D02*
X345888Y232803D01*
G01X344233Y231346D02*
X344398Y231632D01*
G01X344233Y229772D02*
G02Y231346I1365J787D01*
G01X344258Y229730D02*
X344233Y229772D01*
G01Y227447D02*
G03X344258Y229730I-2015J1164D01*
G01X344214Y227413D02*
X344233Y227447D01*
G01Y225872D02*
G02X344214Y227413I1365J787D01*
G01X344258Y223589D02*
G03X344233Y225872I-2040J1119D01*
G01Y223547D02*
X344258Y223589D01*
G01X344214Y223513D02*
X344233Y223547D01*
G01Y221972D02*
G02X344214Y223513I1365J787D01*
G01X344258Y219689D02*
G03X344233Y221972I-2040J1119D01*
G01Y219647D02*
X344258Y219689D01*
G01X344214Y219613D02*
X344233Y219647D01*
G01Y218072D02*
G02X344214Y219613I1365J787D01*
G01X335458Y245820D02*
Y244209D01*
G01X335848Y246210D02*
X335458Y245820D01*
G01X336432Y246210D02*
X335848D01*
G01X337918Y244724D02*
X336432Y246210D01*
G01X337918Y243744D02*
Y244724D01*
G01X336972Y242798D02*
X337918Y243744D01*
G01X336972Y242076D02*
Y242798D01*
G01X337498Y239189D02*
G03X336972Y242076I-2040J1120D01*
G01X337473Y239147D02*
X337498Y239189D01*
G01X337454Y239113D02*
X337473Y239147D01*
G01Y237572D02*
G02X337454Y239113I1365J787D01*
G01X337498Y235289D02*
G03X337473Y237572I-2040J1119D01*
G01Y235247D02*
X337498Y235289D01*
G01X337454Y235213D02*
X337473Y235247D01*
G01Y233672D02*
G02X337454Y235213I1365J787D01*
G01X337473Y231346D02*
G03Y233672I-2015J1163D01*
G01Y229772D02*
G02Y231346I1365J787D01*
G01X337498Y229730D02*
X337473Y229772D01*
G01X335509Y226284D02*
G03X337498Y229730I-51J2326D01*
G01X335399Y226284D02*
X335509D01*
G01X334093Y225497D02*
G02X335399Y226284I1365J-788D01*
G01X332163Y224335D02*
G03X334093Y225497I-85J2325D01*
G01X332034Y224335D02*
X332163D01*
G01X330713Y221972D02*
G02X332034Y224335I1365J788D01*
G01X330738Y219689D02*
G03X330713Y221972I-2040J1119D01*
G01Y219647D02*
X330738Y219689D01*
G01X330713Y218073D02*
G02Y219647I1365J787D01*
G01X343583Y220022D02*
X343558Y219980D01*
G01X343602Y220056D02*
X343583Y220022D01*
G01Y221597D02*
G02X343602Y220056I-1365J-787D01*
G01X343558Y223880D02*
G03X343583Y221597I2040J-1119D01*
G01Y223922D02*
X343558Y223880D01*
G01X343602Y223956D02*
X343583Y223922D01*
G01Y225497D02*
G02X343602Y223956I-1365J-787D01*
G01X343583Y227823D02*
G03Y225497I2015J-1163D01*
G01Y229397D02*
G02Y227823I-1365J-787D01*
G01X343558Y229439D02*
X343583Y229397D01*
G01Y231722D02*
G03X343558Y229439I2015J-1164D01*
G01X343770Y232048D02*
X343583Y231722D01*
G01X345558Y234454D02*
X343770Y232048D01*
G01X345598Y234460D02*
X345558Y234454D01*
G01X353741Y219613D02*
G02X353722Y218072I-1384J-754D01*
G01Y219647D02*
X353741Y219613D01*
G01X353697Y219689D02*
X353722Y219647D01*
G01Y221972D02*
G03X353697Y219689I2015J-1164D01*
G01X353741Y223513D02*
G02X353722Y221972I-1384J-754D01*
G01Y223547D02*
X353741Y223513D01*
G01X353697Y223589D02*
X353722Y223547D01*
G01Y225872D02*
G03X353697Y223589I2015J-1164D01*
G01X353932Y226696D02*
G02X353722Y225872I-1575J-37D01*
G01X354102Y228047D02*
X353932Y226696D01*
G01X354162Y228648D02*
X354102Y228047D01*
G01X354372Y229397D02*
G03X354162Y228648I1365J-787D01*
G01X354534Y229678D02*
X354372Y229397D01*
G01X355210Y230293D02*
X354534Y229678D01*
G01X336602Y237718D02*
X335458Y240309D01*
G01X336823Y237197D02*
G02X336602Y237718I2016J1162D01*
G01X336842Y235656D02*
G03X336823Y237197I-1384J754D01*
G01Y235622D02*
X336842Y235656D01*
G01X336798Y235580D02*
X336823Y235622D01*
G01Y233297D02*
G02X336798Y235580I2015J1164D01*
G01X336842Y231756D02*
G03X336823Y233297I-1384J754D01*
G01Y231722D02*
X336842Y231756D01*
G01X336798Y229439D02*
G02X336823Y231722I2040J1119D01*
G01Y229397D02*
X336798Y229439D01*
G01X335502Y227035D02*
G03X336823Y229397I-44J1575D01*
G01X335407Y227035D02*
X335502D01*
G01X333443Y225872D02*
G02X335407Y227035I2015J-1163D01*
G01X332137Y225085D02*
G03X333443Y225872I-59J1575D01*
G01X332008Y225085D02*
X332137D01*
G01X330063Y221597D02*
G02X332008Y225085I2015J1163D01*
G01X330082Y220056D02*
G03X330063Y221597I-1384J754D01*
G01Y220022D02*
X330082Y220056D01*
G01X334057Y242153D02*
X332078Y246160D01*
G01X334093Y241097D02*
X334057Y242153D01*
G01X334074Y239556D02*
G02X334093Y241097I1384J754D01*
G01Y239522D02*
X334074Y239556D01*
G01X334118Y239480D02*
X334093Y239522D01*
G01Y237197D02*
G03X334118Y239480I-2015J1164D01*
G01X334074Y235656D02*
G02X334093Y237197I1384J754D01*
G01Y235622D02*
X334074Y235656D01*
G01X334118Y235580D02*
X334093Y235622D01*
G01Y233297D02*
G03X334118Y235580I-2015J1164D01*
G01X334074Y231756D02*
G02X334093Y233297I1384J754D01*
G01Y231722D02*
X334074Y231756D01*
G01X332148Y228234D02*
G03X334093Y231722I-70J2325D01*
G01X332007Y228234D02*
X332148D01*
G01X330713Y227447D02*
G02X332007Y228234I1365J-787D01*
G01X328749Y226284D02*
G03X330713Y227447I-51J2326D01*
G01X328639Y226284D02*
X328749D01*
G01X327314Y223956D02*
G02X328639Y226284I1384J753D01*
G01X327333Y223922D02*
X327314Y223956D01*
G01X327358Y223880D02*
X327333Y223922D01*
G01Y221597D02*
G03X327358Y223880I-2015J1164D01*
G01X327314Y220056D02*
G02X327333Y221597I1384J754D01*
G01X328198Y218522D02*
X327314Y220056D01*
G01X333375Y235364D02*
X332078Y238360D01*
G01X333462Y235213D02*
X333375Y235364D01*
G01X333443Y233672D02*
G03X333462Y235213I-1365J787D01*
G01X333443Y231346D02*
G02Y233672I2015J1163D01*
G01X332149Y228985D02*
G03X333443Y231346I-71J1574D01*
G01X331993Y228985D02*
X332149D01*
G01X330063Y227823D02*
G02X331993Y228985I2015J-1163D01*
G01X328742Y227035D02*
G03X330063Y227823I-44J1575D01*
G01X328647Y227035D02*
X328742D01*
G01X326658Y223589D02*
G02X328647Y227035I2040J1120D01*
G01X326683Y223547D02*
X326658Y223589D01*
G01X326702Y223513D02*
X326683Y223547D01*
G01Y221972D02*
G03X326702Y223513I-1365J787D01*
G01X326658Y219689D02*
G02X326683Y221972I2040J1119D01*
G01X327448Y218323D02*
X326658Y219689D01*
G01X354372Y220022D02*
X354397Y219980D01*
G01X354353Y220056D02*
X354372Y220022D01*
G01Y221597D02*
G03X354353Y220056I1365J-787D01*
G01X354397Y223880D02*
G02X354372Y221597I-2040J-1119D01*
G01Y223922D02*
X354397Y223880D01*
G01X354353Y223956D02*
X354372Y223922D01*
G01Y225497D02*
G03X354353Y223956I1365J-787D01*
G01X354938Y226475D02*
X354372Y225497D01*
G01X337473Y219648D02*
G03Y218074I1365J-787D01*
G01Y221974D02*
G02Y219648I-2015J-1163D01*
G01Y223548D02*
G03Y221974I1365J-787D01*
G01X337785Y224700D02*
G02X337473Y223548I-2327J12D01*
G01X337785Y225093D02*
Y224700D01*
G01X339592Y226900D02*
X337785Y225093D01*
G01X339592Y228712D02*
Y226900D01*
G01X340223Y229807D02*
X339592Y228712D01*
G01X340413Y230520D02*
G02X340223Y229807I-1576J38D01*
G01X340413Y230681D02*
Y230520D01*
G01X340409Y230685D02*
X340413Y230681D01*
G01X340203Y231346D02*
G02X340409Y230685I-1365J-788D01*
G01X340203Y233672D02*
G03Y231346I2015J-1163D01*
G01X340222Y235213D02*
G02X340203Y233672I-1384J-754D01*
G01Y235247D02*
X340222Y235213D01*
G01X340203Y236071D02*
G03Y235247I714J-412D01*
G01X340919Y237310D02*
X340203Y236071D01*
G01X342218Y240309D02*
X340919Y237310D01*
G01X350993Y219648D02*
G03Y218074I1364J-787D01*
G01Y221974D02*
G02Y219648I-2015J-1163D01*
G01Y223548D02*
G03Y221974I1364J-787D01*
G01Y225874D02*
G02Y223548I-2015J-1163D01*
G01Y227448D02*
G03Y225874I1364J-787D01*
G01X351528Y228035D02*
G03X350993Y227448I1069J-1512D01*
G01X353244Y229248D02*
X351528Y228035D01*
G01X353722Y229772D02*
G02X353244Y229248I-1430J825D01*
G01X353858Y230008D02*
X353722Y229772D01*
G01X353975Y230484D02*
X353858Y230008D01*
G01X354167Y232643D02*
X353975Y230484D01*
G01X354372Y233297D02*
G03X354167Y232643I1365J-787D01*
G01X354397Y235580D02*
G02X354372Y233297I-2040J-1119D01*
G01Y235622D02*
X354397Y235580D01*
G01X354353Y235656D02*
X354372Y235622D01*
G01Y237197D02*
G03X354353Y235656I1365J-787D01*
G01X354438Y237310D02*
X354372Y237197D01*
G01X355737Y240309D02*
X354438Y237310D01*
G01X306309Y222760D02*
X305039D01*
G01X306526Y222543D02*
X306309Y222760D01*
G01X306526Y219377D02*
Y222543D01*
G01X306590Y218590D02*
G03X306526Y219377I-1552J270D01*
G01X321938Y242710D02*
Y244209D01*
G01X323090Y241558D02*
X321938Y242710D01*
G01X323090Y241550D02*
Y241558D01*
G01X323237Y241210D02*
X323090Y241550D01*
G01X323303Y241097D02*
X323237Y241210D01*
G01X323314Y239517D02*
G03X323303Y241097I-1397J780D01*
G01X323125Y239189D02*
X323314Y239517D01*
G01X322265Y238510D02*
X323125Y239189D01*
G01X321097Y237742D02*
X322265Y238510D01*
G01X320573Y237197D02*
G02X321097Y237742I1365J-788D01*
G01X318643Y236035D02*
G03X320573Y237197I-85J2325D01*
G01X318514Y236035D02*
X318643D01*
G01X317193Y235247D02*
G02X318514Y236035I1365J-787D01*
G01X315248Y234084D02*
G03X317193Y235247I-70J2325D01*
G01X315119Y234084D02*
X315248D01*
G01X313794Y231756D02*
G02X315119Y234084I1384J753D01*
G01X313813Y231722D02*
X313794Y231756D01*
G01X313838Y229439D02*
G03X313813Y231722I-2040J1119D01*
G01Y229397D02*
X313838Y229439D01*
G01X313813Y227823D02*
G02Y229397I1365J787D01*
G01Y225497D02*
G03Y227823I-2015J1163D01*
G01X313794Y223956D02*
G02X313813Y225497I1384J754D01*
G01Y223922D02*
X313794Y223956D01*
G01X313838Y223880D02*
X313813Y223922D01*
G01Y221597D02*
G03X313838Y223880I-2015J1164D01*
G01X313794Y220056D02*
G02X313813Y221597I1384J754D01*
G01Y220022D02*
X313794Y220056D01*
G01X313838Y219980D02*
X313813Y220022D01*
G01X350342D02*
X350307Y219962D01*
G01X350342Y221596D02*
G02Y220022I-1364J-787D01*
G01X350307Y223862D02*
G03X350342Y221596I2050J-1102D01*
G01Y223922D02*
X350307Y223862D01*
G01X350342Y225496D02*
G02Y223922I-1364J-787D01*
G01X350317Y227781D02*
G03X350342Y225496I2040J-1120D01*
G01Y227823D02*
X350317Y227781D01*
G01X350455Y228063D02*
G02X350342Y227823I-1476J548D01*
G01X350564Y228364D02*
X350455Y228063D01*
G01X350782Y230566D02*
X350564Y228364D01*
G01X351781Y232025D02*
G03X350782Y230566I576J-1466D01*
G01X353543Y233362D02*
X351781Y232025D01*
G01X353722Y233672D02*
X353543Y233362D01*
G01X353741Y235213D02*
G02X353722Y233672I-1384J-754D01*
G01Y235247D02*
X353741Y235213D01*
G01X353697Y235289D02*
X353722Y235247D01*
G01Y237572D02*
G03X353697Y235289I2015J-1164D01*
G01X353741Y239113D02*
G02X353722Y237572I-1384J-754D01*
G01X353654Y239264D02*
X353741Y239113D01*
G01X352357Y242260D02*
X353654Y239264D01*
G01X340222Y219613D02*
G02X340203Y218072I-1384J-754D01*
G01Y219647D02*
X340222Y219613D01*
G01X340178Y219689D02*
X340203Y219647D01*
G01Y221972D02*
G03X340178Y219689I2015J-1164D01*
G01X340222Y223513D02*
G02X340203Y221972I-1384J-754D01*
G01Y223547D02*
X340222Y223513D01*
G01X340178Y223589D02*
X340203Y223547D01*
G01X339891Y224730D02*
G03X340178Y223589I2327J-21D01*
G01X339891Y225899D02*
Y224730D01*
G01X340453Y226461D02*
X339891Y225899D01*
G01X340453Y228703D02*
Y226461D01*
G01X340907Y229488D02*
X340453Y228703D01*
G01X340922Y231599D02*
G02X340907Y229488I-1865J-1042D01*
G01X340834Y231756D02*
X340922Y231599D01*
G01X340853Y233297D02*
G03X340834Y231756I1365J-787D01*
G01X340919Y233410D02*
X340853Y233297D01*
G01X342218Y236409D02*
X340919Y233410D01*
G01X309740Y220809D02*
X308418D01*
G01X310000Y220549D02*
X309740Y220809D01*
G01X340853Y220022D02*
X340878Y219980D01*
G01X340834Y220056D02*
X340853Y220022D01*
G01Y221597D02*
G03X340834Y220056I1365J-787D01*
G01X340878Y223880D02*
G02X340853Y221597I-2040J-1119D01*
G01Y223922D02*
X340878Y223880D01*
G01X340834Y223956D02*
X340853Y223922D01*
G01Y225497D02*
G03X340834Y223956I1365J-787D01*
G01X340919Y225611D02*
X340853Y225497D01*
G01X342218Y228610D02*
X340919Y225611D01*
G01X316562Y220056D02*
X316543Y220022D01*
G01Y221597D02*
G02X316562Y220056I-1365J-787D01*
G01X316518Y223880D02*
G03X316543Y221597I2040J-1119D01*
G01Y223922D02*
X316518Y223880D01*
G01X316562Y223956D02*
X316543Y223922D01*
G01Y225497D02*
G02X316562Y223956I-1365J-787D01*
G01X316543Y227823D02*
G03Y225497I2015J-1163D01*
G01Y229397D02*
G02Y227823I-1365J-787D01*
G01X316518Y229439D02*
X316543Y229397D01*
G01X318507Y232885D02*
G03X316518Y229439I51J-2326D01*
G01X318617Y232885D02*
X318507D01*
G01X319923Y233672D02*
G02X318617Y232885I-1365J788D01*
G01X321853Y234834D02*
G03X319923Y233672I85J-2325D01*
G01X321982Y234834D02*
X321853D01*
G01X323303Y235622D02*
G02X321982Y234834I-1359J776D01*
G01X323319Y235650D02*
X323303Y235622D01*
G01X323836Y236482D02*
G03X323319Y235650I12648J-8436D01*
G01X323937Y236812D02*
G02X323836Y236482I-599J3D01*
G01X323937Y237352D02*
Y236812D01*
G01X323715Y237574D02*
X323937Y237352D01*
G01X323715Y238068D02*
Y237574D01*
G01X324007Y238360D02*
X323715Y238068D01*
G01X325318Y238360D02*
X324007D01*
G01X296982Y219764D02*
X298279Y222760D01*
G01X296895Y219613D02*
X296982Y219764D01*
G01X320173Y237925D02*
X321938Y240309D01*
G01X319923Y237572D02*
G02X320173Y237925I2015J-1162D01*
G01X318617Y236785D02*
G03X319923Y237572I-59J1575D01*
G01X318488Y236785D02*
X318617D01*
G01X316543Y235622D02*
G02X318488Y236785I2015J-1162D01*
G01X315222Y234834D02*
G03X316543Y235622I-44J1575D01*
G01X315093Y234834D02*
X315222D01*
G01X313163Y231346D02*
G02X315093Y234834I2015J1163D01*
G01X313163Y229772D02*
G03Y231346I-1365J787D01*
G01X313138Y229730D02*
X313163Y229772D01*
G01Y227447D02*
G02X313138Y229730I2015J1164D01*
G01X313182Y227413D02*
X313163Y227447D01*
G01Y225872D02*
G03X313182Y227413I-1365J787D01*
G01X313138Y223589D02*
G02X313163Y225872I2040J1119D01*
G01Y223547D02*
X313138Y223589D01*
G01X313182Y223513D02*
X313163Y223547D01*
G01Y221972D02*
G03X313182Y223513I-1365J787D01*
G01X313138Y219689D02*
G02X313163Y221972I2040J1119D01*
G01Y219647D02*
X313138Y219689D01*
G01X313182Y219613D02*
X313163Y219647D01*
G01Y218072D02*
G03X313182Y219613I-1365J787D01*
G01X293534Y399421D02*
X293174Y400044D01*
G01X294828Y398634D02*
G02X293534Y399421I71J1574D01*
G01X294969Y398634D02*
X294828D01*
G01X296914Y397471D02*
G03X294969Y398634I-2015J-1162D01*
G01X298208Y396684D02*
G02X296914Y397471I71J1574D01*
G01X298364Y396684D02*
X298208D01*
G01X300294Y395522D02*
G03X298364Y396684I-2015J-1163D01*
G01X301615Y394734D02*
G02X300294Y395522I44J1575D01*
G01X301710Y394734D02*
X301615D01*
G01X303674Y393571D02*
G03X301710Y394734I-2015J-1163D01*
G01X304980Y392784D02*
G02X303674Y393571I59J1575D01*
G01X305039Y392785D02*
G03X304980Y392784I0J-1741D01*
G01X305109Y392785D02*
X305039D01*
G01X307054Y389296D02*
G03X305109Y392785I-2015J1163D01*
G01X307054Y387722D02*
G02Y389296I1364J787D01*
G01X307089Y387662D02*
X307054Y387722D01*
G01Y385396D02*
G03X307089Y387662I-2015J1164D01*
G01X307054Y383822D02*
G02Y385396I1364J787D01*
G01X307089Y383762D02*
X307054Y383822D01*
G01Y381496D02*
G03X307089Y383762I-2015J1164D01*
G01X308191Y379151D02*
G02X307054Y381496I227J1558D01*
G01X308418Y379378D02*
X308191Y379151D01*
G01X308418Y380709D02*
Y379378D01*
G01X294899Y378140D02*
X294642Y378397D01*
G01X294899Y376809D02*
Y378140D01*
G01X354118Y393330D02*
X354892Y394104D01*
G01X354118Y388694D02*
Y393330D01*
G01X354397Y387680D02*
G02X354118Y388694I1703J1014D01*
G01X354372Y385397D02*
G03X354397Y387680I-2015J1164D01*
G01X354353Y383856D02*
G02X354372Y385397I1384J754D01*
G01Y383822D02*
X354353Y383856D01*
G01X354397Y383780D02*
X354372Y383822D01*
G01Y381497D02*
G03X354397Y383780I-2015J1164D01*
G01X354353Y379956D02*
G02X354372Y381497I1384J754D01*
G01Y379922D02*
X354353Y379956D01*
G01X354397Y379880D02*
X354372Y379922D01*
G01Y377597D02*
G03X354397Y379880I-2015J1164D01*
G01X354353Y376056D02*
G02X354372Y377597I1384J754D01*
G01Y376022D02*
X354353Y376056D01*
G01X354397Y375980D02*
X354372Y376022D01*
G01Y373697D02*
G03X354397Y375980I-2015J1164D01*
G01X354353Y372156D02*
G02X354372Y373697I1384J754D01*
G01Y372122D02*
X354353Y372156D01*
G01X354397Y369839D02*
G03X354372Y372122I-2040J1119D01*
G01Y369797D02*
X354397Y369839D01*
G01X354372Y368223D02*
G02Y369797I1365J787D01*
G01Y365897D02*
G03Y368223I-2015J1163D01*
G01X354353Y364356D02*
G02X354372Y365897I1384J754D01*
G01Y364322D02*
X354353Y364356D01*
G01X354397Y364280D02*
X354372Y364322D01*
G01Y361997D02*
G03X354397Y364280I-2015J1164D01*
G01X354353Y360456D02*
G02X354372Y361997I1384J754D01*
G01X354440Y360305D02*
X354353Y360456D01*
G01X355737Y357309D02*
X354440Y360305D01*
G01X294671Y379150D02*
G02X293534Y379922I228J1559D01*
G01X294899Y379378D02*
X294671Y379150D01*
G01X294899Y380709D02*
Y379378D01*
G01X343792Y398760D02*
Y399647D01*
G01X344592Y397960D02*
X343792Y398760D01*
G01X344592Y391881D02*
Y397960D01*
G01X344214Y391213D02*
X344592Y391881D01*
G01X344233Y389672D02*
G02X344214Y391213I1365J787D01*
G01X344258Y387389D02*
G03X344233Y389672I-2040J1119D01*
G01Y387347D02*
X344258Y387389D01*
G01X344214Y387313D02*
X344233Y387347D01*
G01Y385772D02*
G02X344214Y387313I1365J787D01*
G01X344258Y383489D02*
G03X344233Y385772I-2040J1119D01*
G01Y383447D02*
X344258Y383489D01*
G01X344214Y383413D02*
X344233Y383447D01*
G01Y381872D02*
G02X344214Y383413I1365J787D01*
G01X344258Y379589D02*
G03X344233Y381872I-2040J1119D01*
G01Y379547D02*
X344258Y379589D01*
G01X344214Y379513D02*
X344233Y379547D01*
G01Y377972D02*
G02X344214Y379513I1365J787D01*
G01X344258Y375689D02*
G03X344233Y377972I-2040J1119D01*
G01Y375647D02*
X344258Y375689D01*
G01X344214Y375613D02*
X344233Y375647D01*
G01Y374072D02*
G02X344214Y375613I1365J787D01*
G01X344233Y371746D02*
G03Y374072I-2015J1163D01*
G01Y370172D02*
G02Y371746I1365J787D01*
G01X344258Y370130D02*
X344233Y370172D01*
G01Y367847D02*
G03X344258Y370130I-2015J1164D01*
G01X343892Y367506D02*
X344233Y367847D01*
G01X343892Y364866D02*
Y367506D01*
G01X345598Y363160D02*
X343892Y364866D01*
G01X294958Y382284D02*
X294829D01*
G01X296283Y379956D02*
G03X294958Y382284I-1384J753D01*
G01X296264Y379922D02*
X296283Y379956D01*
G01X296239Y379880D02*
X296264Y379922D01*
G01Y377597D02*
G02X296239Y379880I2015J1164D01*
G01X296330Y377481D02*
X296264Y377597D01*
G01X298279Y374860D02*
X296330Y377481D01*
G01X294828Y394735D02*
G02X293534Y395522I71J1574D01*
G01X294969Y394735D02*
X294828D01*
G01X296914Y393572D02*
G03X294969Y394735I-2015J-1162D01*
G01X298208Y392785D02*
G02X296914Y393572I71J1574D01*
G01X298349Y392785D02*
X298208D01*
G01X300294Y391622D02*
G03X298349Y392785I-2015J-1162D01*
G01X301615Y390836D02*
G02X300294Y391622I0J1503D01*
G01X301635Y390836D02*
X301615D01*
G01X301744Y390834D02*
G03X301635Y390836I-109J-2994D01*
G01X303986Y388509D02*
G03X301744Y390834I-2327J0D01*
G01X303986Y388131D02*
Y388509D01*
G01X304343Y386552D02*
G02X303986Y388131I3313J1579D01*
G01X304661Y385996D02*
G02X304343Y386552I3552J2400D01*
G01X305039Y384536D02*
G03X304661Y385996I-2247J197D01*
G01X305039Y382660D02*
Y384536D01*
G01X347792Y394360D02*
Y395781D01*
G01X347392Y393960D02*
X347792Y394360D01*
G01X347392Y392015D02*
Y393960D01*
G01X347613Y391623D02*
X347392Y392015D01*
G01X347613Y389297D02*
G03Y391623I-2015J1163D01*
G01X347594Y387756D02*
G02X347613Y389297I1384J754D01*
G01Y387722D02*
X347594Y387756D01*
G01X347613Y387723D02*
Y387722D01*
G01Y385397D02*
G03Y387723I-2015J1163D01*
G01X347594Y383856D02*
G02X347613Y385397I1384J754D01*
G01Y383822D02*
X347594Y383856D01*
G01X347638Y383780D02*
X347613Y383822D01*
G01Y381497D02*
G03X347638Y383780I-2015J1164D01*
G01X347594Y379956D02*
G02X347613Y381497I1384J754D01*
G01Y379922D02*
X347594Y379956D01*
G01X347638Y379880D02*
X347613Y379922D01*
G01Y377597D02*
G03X347638Y379880I-2015J1164D01*
G01X347594Y376056D02*
G02X347613Y377597I1384J754D01*
G01Y376022D02*
X347594Y376056D01*
G01X347638Y375980D02*
X347613Y376022D01*
G01Y373697D02*
G03X347638Y375980I-2015J1164D01*
G01X347594Y372156D02*
G02X347613Y373697I1384J754D01*
G01Y372122D02*
X347594Y372156D01*
G01X347638Y369839D02*
G03X347613Y372122I-2040J1119D01*
G01Y369797D02*
X347638Y369839D01*
G01X347613Y368223D02*
G02Y369797I1365J787D01*
G01Y365897D02*
G03Y368223I-2015J1163D01*
G01X347594Y364356D02*
G02X347613Y365897I1384J754D01*
G01Y364322D02*
X347594Y364356D01*
G01X347638Y364280D02*
X347613Y364322D01*
G01Y361997D02*
G03X347638Y364280I-2015J1164D01*
G01X347594Y360456D02*
G02X347613Y361997I1384J754D01*
G01Y360422D02*
X347594Y360456D01*
G01X347638Y360380D02*
X347613Y360422D01*
G01Y358097D02*
G03X347638Y360380I-2015J1164D01*
G01X347594Y356556D02*
G02X347613Y358097I1384J754D01*
G01Y356522D02*
X347594Y356556D01*
G01X347638Y356480D02*
X347613Y356522D01*
G01X347452Y353954D02*
G03X347638Y356480I-1854J1406D01*
G01X345598Y351460D02*
X347452Y353954D01*
G01X352792Y399001D02*
Y403600D01*
G01X351768Y397977D02*
X352792Y399001D01*
G01X351768Y388190D02*
Y397977D01*
G01X351486Y387908D02*
X351768Y388190D01*
G01X350993Y387347D02*
G02X351486Y387908I1652J-955D01*
G01X350993Y385773D02*
G02Y387347I1364J787D01*
G01X351028Y383507D02*
G03X350993Y385773I-2050J1102D01*
G01Y383447D02*
X351028Y383507D01*
G01X350993Y381873D02*
G02Y383447I1364J787D01*
G01X351028Y379607D02*
G03X350993Y381873I-2050J1102D01*
G01Y379547D02*
X351028Y379607D01*
G01X350993Y377973D02*
G02Y379547I1364J787D01*
G01X351028Y375707D02*
G03X350993Y377973I-2050J1102D01*
G01Y375647D02*
X351028Y375707D01*
G01X350993Y374073D02*
G02Y375647I1364J787D01*
G01X351018Y371788D02*
G03X350993Y374073I-2040J1120D01*
G01Y371746D02*
X351018Y371788D01*
G01X350993Y370172D02*
G02Y371746I1364J787D01*
G01X351018Y370130D02*
X350993Y370172D01*
G01Y367847D02*
G03X351018Y370130I-2015J1164D01*
G01X350993Y366273D02*
G02Y367847I1364J787D01*
G01X351028Y364007D02*
G03X350993Y366273I-2050J1102D01*
G01Y363947D02*
X351028Y364007D01*
G01X350782Y363179D02*
G02X350993Y363947I1575J-20D01*
G01X350782Y354245D02*
Y363179D01*
G01X352357Y351460D02*
X350782Y354245D01*
G01X332048Y401141D02*
Y405793D01*
G01X333080Y400109D02*
X332048Y401141D01*
G01X333080Y380197D02*
Y400109D01*
G01X333462Y379513D02*
X333080Y380197D01*
G01X333443Y377972D02*
G03X333462Y379513I-1365J787D01*
G01X333418Y375689D02*
G02X333443Y377972I2040J1119D01*
G01Y375647D02*
X333418Y375689D01*
G01X333462Y375613D02*
X333443Y375647D01*
G01Y374072D02*
G03X333462Y375613I-1365J787D01*
G01X335373Y370584D02*
G02X333443Y374072I85J2325D01*
G01X335529Y370584D02*
X335373D01*
G01X336823Y368223D02*
G03X335529Y370584I-1365J787D01*
G01X336823Y365897D02*
G02Y368223I2015J1163D01*
G01X336842Y364356D02*
G03X336823Y365897I-1384J754D01*
G01Y364322D02*
X336842Y364356D01*
G01X336798Y364280D02*
X336823Y364322D01*
G01Y361997D02*
G02X336798Y364280I2015J1164D01*
G01X336842Y360456D02*
G03X336823Y361997I-1384J754D01*
G01X336772Y360334D02*
X336842Y360456D01*
G01X336286Y359680D02*
X336772Y360334D01*
G01X336286Y359491D02*
Y359680D01*
G01X336204Y359349D02*
X336286Y359491D01*
G01X335400Y358884D02*
G03X336204Y359349I0J928D01*
G01X335399Y358884D02*
X335400D01*
G01X334093Y358097D02*
G02X335399Y358884I1365J-788D01*
G01X333738Y357742D02*
X334093Y358097D01*
G01X333738Y356621D02*
Y357742D01*
G01X334588Y355771D02*
X333738Y356621D01*
G01X334588Y355161D02*
Y355771D01*
G01X333508Y354081D02*
X334588Y355161D01*
G01X333508Y352171D02*
Y354081D01*
G01X334190Y351489D02*
X333508Y352171D01*
G01X334738Y351489D02*
X334190D01*
G01X335458Y352209D02*
X334738Y351489D01*
G01X335458Y353409D02*
Y352209D01*
G01X314842Y400988D02*
X315668Y401814D01*
G01X314842Y396195D02*
Y400988D01*
G01X316816Y394221D02*
X314842Y396195D01*
G01X317191Y393571D02*
X316816Y394221D01*
G01X317193Y393572D02*
X317191Y393571D01*
G01X318487Y392785D02*
G02X317193Y393572I71J1574D01*
G01X318650Y392785D02*
X318487D01*
G01X320579Y389306D02*
G03X318650Y392785I-1929J1205D01*
G01X320573Y389297D02*
X320579Y389306D01*
G01X320554Y387756D02*
G02X320573Y389297I1384J754D01*
G01Y387722D02*
X320554Y387756D01*
G01X320598Y387680D02*
X320573Y387722D01*
G01Y385397D02*
G03X320598Y387680I-2015J1164D01*
G01X320554Y383856D02*
G02X320573Y385397I1384J754D01*
G01Y383822D02*
X320554Y383856D01*
G01X320598Y381539D02*
G03X320573Y383822I-2040J1119D01*
G01Y381497D02*
X320598Y381539D01*
G01X320554Y379956D02*
G02X320573Y381497I1384J754D01*
G01Y379922D02*
X320554Y379956D01*
G01X320598Y379880D02*
X320573Y379922D01*
G01Y377597D02*
G03X320598Y379880I-2015J1164D01*
G01X320554Y376056D02*
G02X320573Y377597I1384J754D01*
G01Y376022D02*
X320554Y376056D01*
G01X320598Y375980D02*
X320573Y376022D01*
G01Y373697D02*
G03X320598Y375980I-2015J1164D01*
G01X320554Y372156D02*
G02X320573Y373697I1384J754D01*
G01Y372122D02*
X320554Y372156D01*
G01X320598Y369839D02*
G03X320573Y372122I-2040J1119D01*
G01Y369797D02*
X320598Y369839D01*
G01X320573Y368223D02*
G02Y369797I1365J787D01*
G01Y365897D02*
G03Y368223I-2015J1163D01*
G01X321894Y363534D02*
G02X320573Y365897I44J1575D01*
G01X322023Y363534D02*
X321894D01*
G01X323953Y362372D02*
G03X322023Y363534I-2015J-1163D01*
G01X324019Y362259D02*
X323953Y362372D01*
G01X325318Y359260D02*
X324019Y362259D01*
G01X345792Y393264D02*
Y398948D01*
G01X346982Y391213D02*
X345792Y393264D01*
G01X346963Y389672D02*
G03X346982Y391213I-1365J787D01*
G01X346938Y387389D02*
G02X346963Y389672I2040J1119D01*
G01Y387347D02*
X346938Y387389D01*
G01X346982Y387313D02*
X346963Y387347D01*
G01Y385772D02*
G03X346982Y387313I-1365J787D01*
G01X346938Y383489D02*
G02X346963Y385772I2040J1119D01*
G01Y383447D02*
X346938Y383489D01*
G01X346982Y383413D02*
X346963Y383447D01*
G01Y381872D02*
G03X346982Y383413I-1365J787D01*
G01X346938Y379589D02*
G02X346963Y381872I2040J1119D01*
G01Y379547D02*
X346938Y379589D01*
G01X346982Y379513D02*
X346963Y379547D01*
G01Y377972D02*
G03X346982Y379513I-1365J787D01*
G01X346938Y375689D02*
G02X346963Y377972I2040J1119D01*
G01Y375647D02*
X346938Y375689D01*
G01X346982Y375613D02*
X346963Y375647D01*
G01Y374072D02*
G03X346982Y375613I-1365J787D01*
G01X346963Y371746D02*
G02Y374072I2015J1163D01*
G01Y370172D02*
G03Y371746I-1365J787D01*
G01X346938Y370130D02*
X346963Y370172D01*
G01Y367847D02*
G02X346938Y370130I2015J1164D01*
G01X346982Y367813D02*
X346963Y367847D01*
G01Y366272D02*
G03X346982Y367813I-1365J787D01*
G01X346938Y363989D02*
G02X346963Y366272I2040J1119D01*
G01Y363947D02*
X346938Y363989D01*
G01X346982Y363913D02*
X346963Y363947D01*
G01Y362372D02*
G03X346982Y363913I-1365J787D01*
G01X346938Y360089D02*
G02X346963Y362372I2040J1119D01*
G01Y360047D02*
X346938Y360089D01*
G01X346982Y360013D02*
X346963Y360047D01*
G01Y358472D02*
G03X346982Y360013I-1365J787D01*
G01X346706Y357811D02*
G02X346963Y358472I2272J-503D01*
G01X345598Y355360D02*
X346706Y357811D01*
G01X310245Y400093D02*
X310549Y400397D01*
G01X310245Y394507D02*
Y400093D01*
G01X313917Y390835D02*
X310245Y394507D01*
G01X315250Y390835D02*
X313917D01*
G01X317218Y387389D02*
G03X315250Y390835I-2040J1120D01*
G01X317193Y387347D02*
X317218Y387389D01*
G01X317174Y387313D02*
X317193Y387347D01*
G01Y385772D02*
G02X317174Y387313I1365J787D01*
G01X317218Y383489D02*
G03X317193Y385772I-2040J1119D01*
G01Y383447D02*
X317218Y383489D01*
G01X317174Y383413D02*
X317193Y383447D01*
G01Y381872D02*
G02X317174Y383413I1365J787D01*
G01X317218Y379589D02*
G03X317193Y381872I-2040J1119D01*
G01Y379547D02*
X317218Y379589D01*
G01X317174Y379513D02*
X317193Y379547D01*
G01Y377972D02*
G02X317174Y379513I1365J787D01*
G01X317218Y375689D02*
G03X317193Y377972I-2040J1119D01*
G01Y375647D02*
X317218Y375689D01*
G01X317174Y375613D02*
X317193Y375647D01*
G01Y374072D02*
G02X317174Y375613I1365J787D01*
G01X317193Y371746D02*
G03Y374072I-2015J1163D01*
G01Y370172D02*
G02Y371746I1365J787D01*
G01X317218Y370130D02*
X317193Y370172D01*
G01Y367847D02*
G03X317218Y370130I-2015J1164D01*
G01X317174Y367813D02*
X317193Y367847D01*
G01Y366272D02*
G02X317174Y367813I1365J787D01*
G01X317218Y363989D02*
G03X317193Y366272I-2040J1119D01*
G01Y363947D02*
X317218Y363989D01*
G01X317174Y363913D02*
X317193Y363947D01*
G01X318499Y361585D02*
G02X317174Y363913I59J1575D01*
G01X318628Y361585D02*
X318499D01*
G01X320573Y358097D02*
G03X318628Y361585I-2015J1163D01*
G01X321710Y355750D02*
G02X320573Y358097I228J1559D01*
G01X321938Y355978D02*
X321710Y355750D01*
G01X321938Y357309D02*
Y355978D01*
G01X327778Y399459D02*
Y405869D01*
G01X330509Y396728D02*
X327778Y399459D01*
G01X330509Y396729D02*
Y396728D01*
G01X330728Y396510D02*
X330509Y396729D01*
G01X330728Y380099D02*
Y396510D01*
G01X330249Y379620D02*
X330728Y380099D01*
G01X330249Y378774D02*
Y379620D01*
G01X330713Y377972D02*
X330249Y378774D01*
G01X330738Y375689D02*
G03X330713Y377972I-2040J1119D01*
G01Y375647D02*
X330738Y375689D01*
G01X330694Y375613D02*
X330713Y375647D01*
G01Y374072D02*
G02X330694Y375613I1365J787D01*
G01X330713Y371746D02*
G03Y374072I-2015J1163D01*
G01X332007Y369385D02*
G02X330713Y371746I71J1574D01*
G01X332163Y369385D02*
X332007D01*
G01X334093Y365897D02*
G03X332163Y369385I-2015J1163D01*
G01X334074Y364356D02*
G02X334093Y365897I1384J754D01*
G01Y364322D02*
X334074Y364356D01*
G01X334118Y364280D02*
X334093Y364322D01*
G01Y361997D02*
G03X334118Y364280I-2015J1164D01*
G01X332078Y359260D02*
G03X334093Y361997I-11295J10426D01*
G01X294970Y397883D02*
X294814D01*
G01X296264Y397096D02*
G03X294970Y397883I-1365J-787D01*
G01X298209Y395933D02*
G02X296264Y397096I70J2325D01*
G01X298350Y395933D02*
X298209D01*
G01X299644Y395146D02*
G03X298350Y395933I-1365J-787D01*
G01X301608Y393983D02*
G02X299644Y395146I51J2326D01*
G01X301718Y393983D02*
X301608D01*
G01X303024Y393196D02*
G03X301718Y393983I-1365J-788D01*
G01X304954Y392034D02*
G02X303024Y393196I85J2325D01*
G01X305087Y392034D02*
X304954D01*
G01X306403Y389673D02*
G03X305087Y392034I-1364J787D01*
G01X306368Y387407D02*
G02X306403Y389673I2050J1102D01*
G01Y387347D02*
G02X306368Y387407I843J532D01*
G01X306403Y385773D02*
G03Y387347I-1364J787D01*
G01X306368Y383507D02*
G02X306403Y385773I2050J1102D01*
G01Y383447D02*
X306368Y383507D01*
G01X306403Y381873D02*
G03Y383447I-1364J787D01*
G01X308161Y378397D02*
G02X306403Y381873I256J2312D01*
G01X308418Y378140D02*
X308161Y378397D01*
G01X308418Y376809D02*
Y378140D01*
G01X337792Y398800D02*
Y399687D01*
G01X339492Y397100D02*
X337792Y398800D01*
G01X339492Y390600D02*
Y397100D01*
G01X339692Y390400D02*
X339492Y390600D01*
G01X339692Y387957D02*
Y390400D01*
G01X339871Y387778D02*
X339692Y387957D01*
G01X340203Y387347D02*
G03X339871Y387778I-1630J-912D01*
G01X340222Y387313D02*
X340203Y387347D01*
G01Y385772D02*
G03X340222Y387313I-1365J787D01*
G01X340178Y383489D02*
G02X340203Y385772I2040J1119D01*
G01Y383447D02*
X340178Y383489D01*
G01X340222Y383413D02*
X340203Y383447D01*
G01Y381872D02*
G03X340222Y383413I-1365J787D01*
G01X340178Y379589D02*
G02X340203Y381872I2040J1119D01*
G01Y379547D02*
X340178Y379589D01*
G01X340222Y379513D02*
X340203Y379547D01*
G01Y377972D02*
G03X340222Y379513I-1365J787D01*
G01X340178Y375689D02*
G02X340203Y377972I2040J1119D01*
G01Y375647D02*
X340178Y375689D01*
G01X340222Y375613D02*
X340203Y375647D01*
G01Y374072D02*
G03X340222Y375613I-1365J787D01*
G01X340203Y371746D02*
G02Y374072I2015J1163D01*
G01Y370172D02*
G03Y371746I-1365J787D01*
G01X340178Y370130D02*
X340203Y370172D01*
G01Y367847D02*
G02X340178Y370130I2015J1164D01*
G01X340222Y367813D02*
X340203Y367847D01*
G01Y366272D02*
G03X340222Y367813I-1365J787D01*
G01X340178Y363989D02*
G02X340203Y366272I2040J1119D01*
G01Y363947D02*
X340178Y363989D01*
G01X340222Y363913D02*
X340203Y363947D01*
G01Y362372D02*
G03X340222Y363913I-1365J787D01*
G01X339946Y361710D02*
G02X340203Y362372I2272J-501D01*
G01X339946Y360946D02*
Y361710D01*
G01X342218Y358674D02*
X339946Y360946D01*
G01X342218Y357309D02*
Y358674D01*
G01X349618Y399074D02*
Y404226D01*
G01X350692Y398000D02*
X349618Y399074D01*
G01X350692Y389017D02*
Y398000D01*
G01X350342Y387722D02*
G03X350692Y389017I-2219J1295D01*
G01X350307Y387662D02*
X350342Y387722D01*
G01Y385396D02*
G02X350307Y387662I2015J1164D01*
G01X350342Y383822D02*
G03Y385396I-1364J787D01*
G01X350307Y383762D02*
X350342Y383822D01*
G01Y381496D02*
G02X350307Y383762I2015J1164D01*
G01X350342Y379922D02*
G03Y381496I-1364J787D01*
G01X350307Y379862D02*
X350342Y379922D01*
G01Y377596D02*
G02X350307Y379862I2015J1164D01*
G01X350342Y376022D02*
G03Y377596I-1364J787D01*
G01X350307Y375962D02*
X350342Y376022D01*
G01Y373696D02*
G02X350307Y375962I2015J1164D01*
G01X350342Y372122D02*
G03Y373696I-1364J787D01*
G01X350317Y369839D02*
G02X350342Y372122I2040J1119D01*
G01Y369797D02*
X350317Y369839D01*
G01X350342Y368223D02*
G03Y369797I-1364J787D01*
G01X350317Y368181D02*
X350342Y368223D01*
G01Y365896D02*
G02X350317Y368181I2015J1165D01*
G01X350342Y364322D02*
G03Y365896I-1364J787D01*
G01X350276Y364208D02*
X350342Y364322D01*
G01X348978Y361209D02*
X350276Y364208D01*
G01X294970Y393984D02*
X294814D01*
G01X296264Y393197D02*
G03X294970Y393984I-1365J-787D01*
G01X298209Y392034D02*
G02X296264Y393197I70J2325D01*
G01X298350Y392034D02*
X298209D01*
G01X299644Y391247D02*
G03X298350Y392034I-1365J-787D01*
G01X301574Y390086D02*
G02X299644Y391247I0J2185D01*
G01X301611Y390086D02*
X301574D01*
G01X301718Y390084D02*
G03X301611Y390086I-107J-2851D01*
G01X303235Y388509D02*
G03X301718Y390084I-1576J0D01*
G01X303235Y387517D02*
Y388509D01*
G01X303701Y386015D02*
G02X303235Y387517I2667J1651D01*
G01X303986Y385013D02*
G03X303701Y386015I-1904J0D01*
G01X303986Y384611D02*
Y385013D01*
G01X303699Y383489D02*
G03X303986Y384611I-2040J1119D01*
G01X303662Y383427D02*
X303699Y383489D01*
G01X303674Y381872D02*
G02X303662Y383427I1289J787D01*
G01X303699Y379589D02*
G03X303674Y381872I-2040J1119D01*
G01Y379547D02*
X303699Y379589D01*
G01X303655Y379513D02*
X303674Y379547D01*
G01Y377972D02*
G02X303655Y379513I1365J787D01*
G01X303740Y377859D02*
X303674Y377972D01*
G01X305039Y374860D02*
X303740Y377859D01*
G01X341792Y398900D02*
Y399889D01*
G01X343692Y397000D02*
X341792Y398900D01*
G01X343692Y392100D02*
Y397000D01*
G01X343473Y391571D02*
G02X343692Y392100I748J0D01*
G01X343473Y391409D02*
Y391571D01*
G01X343583Y389297D02*
G02X343473Y391409I2015J1164D01*
G01X343602Y387756D02*
G03X343583Y389297I-1384J754D01*
G01Y387722D02*
X343602Y387756D01*
G01X343558Y387680D02*
X343583Y387722D01*
G01Y385397D02*
G02X343558Y387680I2015J1164D01*
G01X343602Y383856D02*
G03X343583Y385397I-1384J754D01*
G01Y383822D02*
X343602Y383856D01*
G01X343558Y383780D02*
X343583Y383822D01*
G01Y381497D02*
G02X343558Y383780I2015J1164D01*
G01X343602Y379956D02*
G03X343583Y381497I-1384J754D01*
G01Y379922D02*
X343602Y379956D01*
G01X343558Y379880D02*
X343583Y379922D01*
G01Y377597D02*
G02X343558Y379880I2015J1164D01*
G01X343602Y376056D02*
G03X343583Y377597I-1384J754D01*
G01Y376022D02*
X343602Y376056D01*
G01X343558Y375980D02*
X343583Y376022D01*
G01Y373697D02*
G02X343558Y375980I2015J1164D01*
G01X343602Y372156D02*
G03X343583Y373697I-1384J754D01*
G01Y372122D02*
X343602Y372156D01*
G01X342692Y370800D02*
G03X343583Y372122I-7456J5987D01*
G01X342218Y369010D02*
G02X342692Y370800I2254J361D01*
G01X314094Y400943D02*
X313099Y401938D01*
G01X314094Y395885D02*
Y400943D01*
G01X316217Y393762D02*
X314094Y395885D01*
G01X316543Y393197D02*
X316217Y393762D01*
G01X318488Y392034D02*
G02X316543Y393197I70J2325D01*
G01X318583Y392034D02*
X318488D01*
G01X319926Y389676D02*
G03X318583Y392034I-1343J797D01*
G01X319923Y389672D02*
X319926Y389676D01*
G01X319898Y387389D02*
G02X319923Y389672I2040J1119D01*
G01Y387347D02*
X319898Y387389D01*
G01X319942Y387313D02*
X319923Y387347D01*
G01Y385772D02*
G03X319942Y387313I-1365J787D01*
G01X319923Y383446D02*
G02Y385772I2015J1163D01*
G01Y381872D02*
G03Y383446I-1365J787D01*
G01X319898Y379589D02*
G02X319923Y381872I2040J1119D01*
G01Y379547D02*
X319898Y379589D01*
G01X319942Y379513D02*
X319923Y379547D01*
G01Y377972D02*
G03X319942Y379513I-1365J787D01*
G01X319898Y375689D02*
G02X319923Y377972I2040J1119D01*
G01Y375647D02*
X319898Y375689D01*
G01X319942Y375613D02*
X319923Y375647D01*
G01Y374072D02*
G03X319942Y375613I-1365J787D01*
G01X319923Y371746D02*
G02Y374072I2015J1163D01*
G01Y370172D02*
G03Y371746I-1365J787D01*
G01X319898Y370130D02*
X319923Y370172D01*
G01Y367847D02*
G02X319898Y370130I2015J1164D01*
G01X319942Y367813D02*
X319923Y367847D01*
G01Y366272D02*
G03X319942Y367813I-1365J787D01*
G01X321868Y362784D02*
G02X319923Y366272I70J2325D01*
G01X321997Y362784D02*
X321868D01*
G01X323322Y360456D02*
G03X321997Y362784I-1384J753D01*
G01X323303Y360422D02*
X323322Y360456D01*
G01X323278Y360380D02*
X323303Y360422D01*
G01Y358097D02*
G02X323278Y360380I2015J1164D01*
G01X323322Y356556D02*
G03X323303Y358097I-1384J754D01*
G01Y356522D02*
X323322Y356556D01*
G01X323278Y356480D02*
X323303Y356522D01*
G01Y354197D02*
G02X323278Y356480I2015J1164D01*
G01X323369Y354081D02*
X323303Y354197D01*
G01X325318Y351460D02*
X323369Y354081D01*
G01X332796Y401451D02*
Y405787D01*
G01X333828Y400419D02*
X332796Y401451D01*
G01X333828Y380396D02*
Y400419D01*
G01X334118Y379880D02*
X333828Y380396D01*
G01X334093Y377597D02*
G03X334118Y379880I-2015J1164D01*
G01X334074Y376056D02*
G02X334093Y377597I1384J754D01*
G01Y376022D02*
X334074Y376056D01*
G01X334118Y375980D02*
X334093Y376022D01*
G01Y373697D02*
G03X334118Y375980I-2015J1164D01*
G01X335387Y371335D02*
G02X334093Y373697I71J1574D01*
G01X335528Y371335D02*
X335387D01*
G01X337473Y367847D02*
G03X335528Y371335I-2015J1163D01*
G01X337454Y367813D02*
X337473Y367847D01*
G01Y366272D02*
G02X337454Y367813I1365J787D01*
G01X337498Y363989D02*
G03X337473Y366272I-2040J1119D01*
G01Y363947D02*
X337498Y363989D01*
G01X337454Y363913D02*
X337473Y363947D01*
G01Y362372D02*
G02X337454Y363913I1365J787D01*
G01X337498Y360089D02*
G03X337473Y362372I-2040J1119D01*
G01Y360047D02*
X337498Y360089D01*
G01X337407Y359931D02*
X337473Y360047D01*
G01X337262Y359736D02*
X337407Y359931D01*
G01X337262Y358315D02*
Y359736D01*
G01X336554Y357607D02*
X337262Y358315D01*
G01X335756Y357607D02*
X336554D01*
G01X335458Y357309D02*
X335756Y357607D01*
G01X353792Y394254D02*
Y405714D01*
G01X353092Y393554D02*
X353792Y394254D01*
G01X353092Y389766D02*
Y393554D01*
G01X353722Y387347D02*
G02X353092Y389766I4328J2419D01*
G01X353741Y387313D02*
X353722Y387347D01*
G01Y385772D02*
G03X353741Y387313I-1365J787D01*
G01X353697Y383489D02*
G02X353722Y385772I2040J1119D01*
G01Y383447D02*
X353697Y383489D01*
G01X353741Y383413D02*
X353722Y383447D01*
G01Y381872D02*
G03X353741Y383413I-1365J787D01*
G01X353697Y379589D02*
G02X353722Y381872I2040J1119D01*
G01Y379547D02*
X353697Y379589D01*
G01X353741Y379513D02*
X353722Y379547D01*
G01Y377972D02*
G03X353741Y379513I-1365J787D01*
G01X353697Y375689D02*
G02X353722Y377972I2040J1119D01*
G01Y375647D02*
X353697Y375689D01*
G01X353741Y375613D02*
X353722Y375647D01*
G01Y374072D02*
G03X353741Y375613I-1365J787D01*
G01X353722Y371746D02*
G02Y374072I2015J1163D01*
G01Y370172D02*
G03Y371746I-1365J787D01*
G01X353697Y370130D02*
X353722Y370172D01*
G01Y367847D02*
G02X353697Y370130I2015J1164D01*
G01X353741Y367813D02*
X353722Y367847D01*
G01Y366272D02*
G03X353741Y367813I-1365J787D01*
G01X353697Y363989D02*
G02X353722Y366272I2040J1119D01*
G01Y363947D02*
X353697Y363989D01*
G01X353741Y363913D02*
X353722Y363947D01*
G01Y362372D02*
G03X353741Y363913I-1365J787D01*
G01X353697Y360089D02*
G02X353722Y362372I2040J1119D01*
G01Y360047D02*
X353697Y360089D01*
G01X353741Y360013D02*
X353722Y360047D01*
G01Y358472D02*
G03X353741Y360013I-1365J787D01*
G01X353656Y358359D02*
X353722Y358472D01*
G01X352357Y355360D02*
X353656Y358359D01*
G01X294855Y383034D02*
G02X293534Y383822I44J1575D01*
G01X295045Y383034D02*
X294855D01*
G01X298279Y382660D02*
X295045Y383034D01*
G01X309494Y398034D02*
X307971Y399557D01*
G01X309494Y394195D02*
Y398034D01*
G01X313605Y390084D02*
X309494Y394195D01*
G01X315237Y390084D02*
X313605D01*
G01X316562Y387756D02*
G03X315237Y390084I-1384J753D01*
G01X316543Y387722D02*
X316562Y387756D01*
G01X316518Y387680D02*
X316543Y387722D01*
G01Y385397D02*
G02X316518Y387680I2015J1164D01*
G01X316562Y383856D02*
G03X316543Y385397I-1384J754D01*
G01Y383822D02*
X316562Y383856D01*
G01X316518Y383780D02*
X316543Y383822D01*
G01Y381497D02*
G02X316518Y383780I2015J1164D01*
G01X316562Y379956D02*
G03X316543Y381497I-1384J754D01*
G01Y379922D02*
X316562Y379956D01*
G01X316518Y379880D02*
X316543Y379922D01*
G01Y377597D02*
G02X316518Y379880I2015J1164D01*
G01X316562Y376056D02*
G03X316543Y377597I-1384J754D01*
G01Y376022D02*
X316562Y376056D01*
G01X316518Y375980D02*
X316543Y376022D01*
G01Y373697D02*
G02X316518Y375980I2015J1164D01*
G01X316562Y372156D02*
G03X316543Y373697I-1384J754D01*
G01Y372122D02*
X316562Y372156D01*
G01X316518Y369839D02*
G02X316543Y372122I2040J1119D01*
G01Y369797D02*
X316518Y369839D01*
G01X316543Y368223D02*
G03Y369797I-1365J787D01*
G01Y365897D02*
G02Y368223I2015J1163D01*
G01X316562Y364356D02*
G03X316543Y365897I-1384J754D01*
G01Y364322D02*
X316562Y364356D01*
G01X316518Y364280D02*
X316543Y364322D01*
G01X318473Y360835D02*
G02X316518Y364280I85J2325D01*
G01X318602Y360835D02*
X318473D01*
G01X319923Y358472D02*
G03X318602Y360835I-1365J788D01*
G01X321681Y354997D02*
G02X319923Y358472I257J2312D01*
G01X321938Y354740D02*
X321681Y354997D01*
G01X321938Y353409D02*
Y354740D01*
G01X340921Y364205D02*
X342218Y361209D01*
G01X340834Y364356D02*
X340921Y364205D01*
G01X340853Y365897D02*
G03X340834Y364356I1365J-787D01*
G01X340853Y368223D02*
G02Y365897I-2015J-1163D01*
G01Y369797D02*
G03Y368223I1365J-787D01*
G01X340878Y369839D02*
X340853Y369797D01*
G01Y372122D02*
G02X340878Y369839I-2015J-1164D01*
G01X340834Y372156D02*
X340853Y372122D01*
G01Y373697D02*
G03X340834Y372156I1365J-787D01*
G01X340878Y375980D02*
G02X340853Y373697I-2040J-1119D01*
G01Y376022D02*
X340878Y375980D01*
G01X340834Y376056D02*
X340853Y376022D01*
G01Y377597D02*
G03X340834Y376056I1365J-787D01*
G01X340878Y379880D02*
G02X340853Y377597I-2040J-1119D01*
G01Y379922D02*
X340878Y379880D01*
G01X340834Y379956D02*
X340853Y379922D01*
G01Y381497D02*
G03X340834Y379956I1365J-787D01*
G01X340878Y383780D02*
G02X340853Y381497I-2040J-1119D01*
G01Y383822D02*
X340878Y383780D01*
G01X340834Y383856D02*
X340853Y383822D01*
G01Y385397D02*
G03X340834Y383856I1365J-787D01*
G01X340878Y387680D02*
G02X340853Y385397I-2040J-1119D01*
G01Y387722D02*
X340878Y387680D01*
G01X340545Y388797D02*
G03X340853Y387722I2194J47D01*
G01X340545Y390647D02*
Y388797D01*
G01X340292Y390900D02*
X340545Y390647D01*
G01X340292Y398154D02*
Y390900D01*
G01X339792Y398654D02*
X340292Y398154D01*
G01X339792Y399607D02*
Y398654D01*
G01X330627Y354747D02*
G02X330506Y355474I1451J615D01*
G01X332078Y351460D02*
X330627Y354747D01*
G01X327030Y399149D02*
Y405711D01*
G01X329980Y396199D02*
X327030Y399149D01*
G01X329980Y380409D02*
Y396199D01*
G01X329501Y379930D02*
X329980Y380409D01*
G01X329501Y378570D02*
Y379930D01*
G01X330063Y377597D02*
X329501Y378570D01*
G01X330082Y376056D02*
G03X330063Y377597I-1384J754D01*
G01Y376022D02*
X330082Y376056D01*
G01X330038Y375980D02*
X330063Y376022D01*
G01Y373697D02*
G02X330038Y375980I2015J1164D01*
G01X330082Y372156D02*
G03X330063Y373697I-1384J754D01*
G01Y372122D02*
X330082Y372156D01*
G01X332008Y368634D02*
G02X330063Y372122I70J2325D01*
G01X332149Y368634D02*
X332008D01*
G01X333443Y366272D02*
G03X332149Y368634I-1365J788D01*
G01X333418Y363989D02*
G02X333443Y366272I2040J1119D01*
G01Y363947D02*
X333418Y363989D01*
G01X333462Y363913D02*
X333443Y363947D01*
G01Y362372D02*
G03X333462Y363913I-1365J787D01*
G01X332812Y361767D02*
G03X333443Y362372I-723J1386D01*
G01X330998Y360408D02*
G02X332812Y361767I5140J-4970D01*
G01X330504Y359184D02*
G02X330998Y360408I1574J77D01*
G01X330506Y355474D02*
X330504Y359184D01*
G01X351792Y404600D02*
Y406100D01*
G01X352792Y403600D02*
X351792Y404600D01*
G01X332048Y405793D02*
X331150Y406691D01*
G01X327778Y405869D02*
X328600Y406691D01*
G01X349792Y404400D02*
Y405706D01*
G01X349618Y404226D02*
X349792Y404400D01*
G01X332796Y405787D02*
X333700Y406691D01*
G01X327030Y405711D02*
X326050Y406691D01*
G01X392632Y191060D02*
Y190218D01*
G01X390048Y193644D02*
X392632Y191060D01*
G01X390048Y200145D02*
Y193644D01*
G01X388348Y201845D02*
X390048Y200145D01*
G01X388348Y205691D02*
Y201845D01*
G01X387841Y207375D02*
X388348Y205691D01*
G01X387522Y207946D02*
X387841Y207375D01*
G01X387522Y210272D02*
G03Y207946I2015J-1163D01*
G01X387541Y211813D02*
G02X387522Y210272I-1384J-754D01*
G01Y211847D02*
X387541Y211813D01*
G01X387497Y211889D02*
X387522Y211847D01*
G01Y214172D02*
G03X387497Y211889I2015J-1164D01*
G01X387541Y215713D02*
G02X387522Y214172I-1384J-754D01*
G01Y215747D02*
X387541Y215713D01*
G01X387497Y215789D02*
X387522Y215747D01*
G01Y218072D02*
G03X387497Y215789I2015J-1164D01*
G01X408632Y190360D02*
Y189343D01*
G01X402392Y196600D02*
X408632Y190360D01*
G01X402392Y202900D02*
Y196600D01*
G01X403192Y203700D02*
X402392Y202900D01*
G01X403192Y230944D02*
Y203700D01*
G01X412740Y189852D02*
Y188712D01*
G01X406792Y195800D02*
X412740Y189852D01*
G01X406792Y203501D02*
Y195800D01*
G01X406092Y204201D02*
X406792Y203501D01*
G01X406092Y221500D02*
Y204201D01*
G01X390632Y191061D02*
Y190240D01*
G01X388498Y193195D02*
X390632Y191061D01*
G01X388498Y199994D02*
Y193195D01*
G01X387292Y201200D02*
X388498Y199994D01*
G01X387292Y203705D02*
Y201200D01*
G01X384468Y206529D02*
X387292Y203705D01*
G01X384468Y207377D02*
Y206529D01*
G01X384792Y207946D02*
X384468Y207377D01*
G01X384792Y210272D02*
G02Y207946I-2015J-1163D01*
G01X384773Y211813D02*
G03X384792Y210272I1384J-754D01*
G01Y211847D02*
X384773Y211813D01*
G01X384817Y211889D02*
X384792Y211847D01*
G01Y214172D02*
G02X384817Y211889I-2015J-1164D01*
G01X384773Y215713D02*
G03X384792Y214172I1384J-754D01*
G01Y215747D02*
X384773Y215713D01*
G01X384817Y215789D02*
X384792Y215747D01*
G01Y218072D02*
G02X384817Y215789I-2015J-1164D01*
G01X377382Y217697D02*
G02X377357Y219980I2015J1164D01*
G01X377401Y216156D02*
G03X377382Y217697I-1384J754D01*
G01Y216122D02*
X377401Y216156D01*
G01X377357Y216080D02*
X377382Y216122D01*
G01Y213797D02*
G02X377357Y216080I2015J1164D01*
G01X377401Y212256D02*
G03X377382Y213797I-1384J754D01*
G01Y212222D02*
X377401Y212256D01*
G01X377357Y212180D02*
X377382Y212222D01*
G01Y209897D02*
G02X377357Y212180I2015J1164D01*
G01X377401Y208356D02*
G03X377382Y209897I-1384J754D01*
G01Y208322D02*
X377401Y208356D01*
G01X377357Y206039D02*
G02X377382Y208322I2040J1119D01*
G01Y205997D02*
X377357Y206039D01*
G01X377729Y205108D02*
G03X377382Y205997I-2851J-601D01*
G01X377814Y205022D02*
X377729Y205108D01*
G01X378490Y204347D02*
X377814Y205022D01*
G01X378490Y199399D02*
Y204347D01*
G01X380630Y197259D02*
X378490Y199399D01*
G01X380630Y190273D02*
Y197259D01*
G01X355298Y201894D02*
Y190725D01*
G01X406632Y190860D02*
Y189743D01*
G01X401468Y196024D02*
X406632Y190860D01*
G01X401468Y228767D02*
Y196024D01*
G01X394281Y215748D02*
G02Y218074I2015J1163D01*
G01Y214174D02*
G03Y215748I-1365J787D01*
G01Y211848D02*
G02Y214174I2017J1163D01*
G01Y210274D02*
G03Y211848I-1365J787D01*
G01Y207948D02*
G02Y210274I2015J1163D01*
G01X395492Y205852D02*
X394281Y207948D01*
G01X395492Y200440D02*
Y205852D01*
G01X398162Y197770D02*
X395492Y200440D01*
G01X398162Y194530D02*
Y197770D01*
G01X400632Y192060D02*
X398162Y194530D01*
G01X400632Y190799D02*
Y192060D01*
G01X361132Y217698D02*
G03Y220024I-2015J1163D01*
G01Y216124D02*
G02Y217698I1365J787D01*
G01Y213798D02*
G03Y216124I-2015J1163D01*
G01Y212224D02*
G02Y213798I1365J787D01*
G01Y209898D02*
G03Y212224I-2015J1163D01*
G01X360913Y209080D02*
G02X361132Y209898I1638J0D01*
G01X360913Y202499D02*
Y209080D01*
G01X365298Y198114D02*
X360913Y202499D01*
G01X365298Y196325D02*
Y198114D01*
G01X357102Y217698D02*
G02Y220024I2015J1163D01*
G01Y216124D02*
G03Y217698I-1365J787D01*
G01Y213798D02*
G02Y216124I2015J1163D01*
G01Y212224D02*
G03Y213798I-1364J787D01*
G01Y209898D02*
G02Y212224I2015J1163D01*
G01X357363Y208923D02*
G03X357102Y209898I-1952J0D01*
G01X357363Y199626D02*
Y208923D01*
G01X359598Y197391D02*
X357363Y199626D01*
G01X359598Y192741D02*
Y197391D01*
G01X359298Y192441D02*
X359598Y192741D01*
G01X359298Y191225D02*
Y192441D01*
G01X397948Y200244D02*
Y234741D01*
G01X400392Y197800D02*
X397948Y200244D01*
G01X400392Y195740D02*
Y197800D01*
G01X404632Y191500D02*
X400392Y195740D01*
G01X404632Y190277D02*
Y191500D01*
G01X391587Y215807D02*
G03X391552Y218073I-2050J1102D01*
G01Y215747D02*
X391587Y215807D01*
G01X391552Y214173D02*
G02Y215747I1364J787D01*
G01X391587Y211907D02*
G03X391552Y214173I-2050J1102D01*
G01Y211847D02*
X391587Y211907D01*
G01X391552Y210273D02*
G02Y211847I1364J787D01*
G01X394490Y205181D02*
X391552Y210273D01*
G01X394490Y196938D02*
Y205181D01*
G01X398632Y192796D02*
X394490Y196938D01*
G01X398632Y191296D02*
Y192796D01*
G01X357298Y191791D02*
Y191175D01*
G01X356398Y192691D02*
X357298Y191791D01*
G01X356398Y202094D02*
Y192691D01*
G01X382632Y197261D02*
Y190375D01*
G01X379692Y200201D02*
X382632Y197261D01*
G01X379692Y204418D02*
Y200201D01*
G01X378305Y205805D02*
X379692Y204418D01*
G01X378032Y206373D02*
G02X378305Y205805I-3154J-1865D01*
G01X378013Y206407D02*
X378032Y206373D01*
G01Y207946D02*
G03X378013Y206407I1365J-786D01*
G01X378032Y210272D02*
G02Y207946I-2015J-1163D01*
G01X378013Y211813D02*
G03X378032Y210272I1384J-754D01*
G01Y211847D02*
X378013Y211813D01*
G01X378057Y211889D02*
X378032Y211847D01*
G01Y214172D02*
G02X378057Y211889I-2015J-1164D01*
G01X378013Y215713D02*
G03X378032Y214172I1384J-754D01*
G01Y215747D02*
X378013Y215713D01*
G01X378057Y215789D02*
X378032Y215747D01*
G01Y218072D02*
G02X378057Y215789I-2015J-1164D01*
G01X384632Y190912D02*
Y190071D01*
G01X383892Y191652D02*
X384632Y190912D01*
G01X383892Y197861D02*
Y191652D01*
G01X380992Y200761D02*
X383892Y197861D01*
G01X380992Y207087D02*
Y200761D01*
G01X380762Y207946D02*
G02X380992Y207087I-1488J-859D01*
G01X380762Y210272D02*
G03Y207946I2015J-1163D01*
G01X380781Y211813D02*
G02X380762Y210272I-1384J-754D01*
G01Y211847D02*
X380781Y211813D01*
G01X380737Y211889D02*
X380762Y211847D01*
G01Y214172D02*
G03X380737Y211889I2015J-1164D01*
G01X380781Y215713D02*
G02X380762Y214172I-1384J-754D01*
G01Y215747D02*
X380781Y215713D01*
G01X380737Y215789D02*
X380762Y215747D01*
G01Y218072D02*
G03X380737Y215789I2015J-1164D01*
G01X394931Y217698D02*
G03Y220024I-2015J1163D01*
G01Y216124D02*
G02Y217698I1365J787D01*
G01Y213798D02*
G03Y216124I-2015J1163D01*
G01Y212224D02*
G02Y213798I1364J787D01*
G01Y209898D02*
G03Y212224I-2015J1163D01*
G01Y208324D02*
G02Y209898I1365J787D01*
G01X395087Y208053D02*
X394931Y208324D01*
G01X396598Y206542D02*
X395087Y208053D01*
G01X396598Y200494D02*
Y206542D01*
G01X399092Y198000D02*
X396598Y200494D01*
G01X399092Y195300D02*
Y198000D01*
G01X402632Y191760D02*
X399092Y195300D01*
G01X402632Y190520D02*
Y191760D01*
G01X394632Y191025D02*
Y190266D01*
G01X391292Y194365D02*
X394632Y191025D01*
G01X391292Y200699D02*
Y194365D01*
G01X389698Y202293D02*
X391292Y200699D01*
G01X389698Y205677D02*
Y202293D01*
G01X388153Y208356D02*
X389698Y205677D01*
G01X388172Y209897D02*
G03X388153Y208356I1365J-787D01*
G01X388197Y212180D02*
G02X388172Y209897I-2040J-1119D01*
G01Y212222D02*
X388197Y212180D01*
G01X388153Y212256D02*
X388172Y212222D01*
G01Y213797D02*
G03X388153Y212256I1365J-787D01*
G01X388197Y216080D02*
G02X388172Y213797I-2040J-1119D01*
G01Y216122D02*
X388197Y216080D01*
G01X388153Y216156D02*
X388172Y216122D01*
G01Y217697D02*
G03X388153Y216156I1365J-787D01*
G01X388197Y219980D02*
G02X388172Y217697I-2040J-1119D01*
G01X396632Y193584D02*
Y191585D01*
G01X392692Y197524D02*
X396632Y193584D01*
G01X392692Y201199D02*
Y197524D01*
G01X391298Y202593D02*
X392692Y201199D01*
G01X391298Y209209D02*
Y202593D01*
G01X390901Y209896D02*
X391298Y209209D01*
G01X390866Y212162D02*
G03X390901Y209896I2050J-1102D01*
G01Y212222D02*
X390866Y212162D01*
G01X390901Y213796D02*
G02Y212222I-1364J-787D01*
G01X390866Y216062D02*
G03X390901Y213796I2050J-1102D01*
G01Y216122D02*
X390866Y216062D01*
G01X390901Y217696D02*
G02Y216122I-1364J-787D01*
G01X390866Y219962D02*
G03X390901Y217696I2050J-1102D01*
G01X410632Y190159D02*
Y188943D01*
G01X405992Y194799D02*
X410632Y190159D01*
G01X405992Y202601D02*
Y194799D01*
G01X404648Y203945D02*
X405992Y202601D01*
G01X404648Y221651D02*
Y203945D01*
G01X363298Y198181D02*
Y196375D01*
G01X359818Y201661D02*
X363298Y198181D01*
G01X359818Y207795D02*
Y201661D01*
G01X360482Y210274D02*
G03X359818Y207795I4295J-2479D01*
G01X360482Y211848D02*
G02Y210274I-1365J-787D01*
G01Y214174D02*
G03Y211848I2015J-1163D01*
G01Y215748D02*
G02Y214174I-1365J-787D01*
G01Y218074D02*
G03Y215748I2015J-1163D01*
G01X386632Y191046D02*
Y190168D01*
G01X385492Y192186D02*
X386632Y191046D01*
G01X385492Y199300D02*
Y192186D01*
G01X384748Y200044D02*
X385492Y199300D01*
G01X384748Y202344D02*
Y200044D01*
G01X382092Y205000D02*
X384748Y202344D01*
G01X382092Y206200D02*
Y205000D01*
G01X381651Y207895D02*
G02X382092Y206200I-3034J-1694D01*
G01X381393Y208356D02*
X381651Y207895D01*
G01X381412Y209897D02*
G03X381393Y208356I1365J-787D01*
G01X381437Y212180D02*
G02X381412Y209897I-2040J-1119D01*
G01Y212222D02*
X381437Y212180D01*
G01X381393Y212256D02*
X381412Y212222D01*
G01Y213797D02*
G03X381393Y212256I1365J-787D01*
G01X381437Y216080D02*
G02X381412Y213797I-2040J-1119D01*
G01Y216122D02*
X381437Y216080D01*
G01X381393Y216156D02*
X381412Y216122D01*
G01Y217697D02*
G03X381393Y216156I1365J-787D01*
G01X381437Y219980D02*
G02X381412Y217697I-2040J-1119D01*
G01X388632Y191060D02*
Y190084D01*
G01X386948Y192744D02*
X388632Y191060D01*
G01X386948Y199645D02*
Y192744D01*
G01X385992Y200601D02*
X386948Y199645D01*
G01X385992Y203101D02*
Y200601D01*
G01X383626Y205467D02*
X385992Y203101D01*
G01X383626Y207498D02*
Y205467D01*
G01X384142Y208322D02*
X383626Y207498D01*
G01X384161Y208356D02*
X384142Y208322D01*
G01Y209897D02*
G02X384161Y208356I-1365J-787D01*
G01X384117Y212180D02*
G03X384142Y209897I2040J-1119D01*
G01Y212222D02*
X384117Y212180D01*
G01X384161Y212256D02*
X384142Y212222D01*
G01Y213797D02*
G02X384161Y212256I-1365J-787D01*
G01X384117Y216080D02*
G03X384142Y213797I2040J-1119D01*
G01Y216122D02*
X384117Y216080D01*
G01X384161Y216156D02*
X384142Y216122D01*
G01Y217697D02*
G02X384161Y216156I-1365J-787D01*
G01X384117Y219980D02*
G03X384142Y217697I2040J-1119D01*
G01X361298Y197792D02*
Y191275D01*
G01X358403Y200687D02*
X361298Y197792D01*
G01X358403Y207844D02*
Y200687D01*
G01X357752Y210274D02*
G02X358403Y207844I-4211J-2430D01*
G01X357752Y211848D02*
G03Y210274I1365J-787D01*
G01Y214174D02*
G02Y211848I-2017J-1163D01*
G01Y215748D02*
G03Y214174I1365J-787D01*
G01Y218074D02*
G02Y215748I-2015J-1163D01*
G01X387541Y219613D02*
G02X387522Y218072I-1384J-754D01*
G01Y219647D02*
X387541Y219613D01*
G01X387497Y219689D02*
X387522Y219647D01*
G01Y221972D02*
G03X387497Y219689I2015J-1164D01*
G01X387541Y223513D02*
G02X387522Y221972I-1384J-754D01*
G01Y223547D02*
X387541Y223513D01*
G01X387497Y223589D02*
X387522Y223547D01*
G01Y225872D02*
G03X387497Y223589I2015J-1164D01*
G01X387541Y227413D02*
G02X387522Y225872I-1384J-754D01*
G01X387457Y227559D02*
X387541Y227413D01*
G01X386157Y230559D02*
X387457Y227559D01*
G01X399676Y234460D02*
X403192Y230944D01*
G01X407392Y222800D02*
X406092Y221500D01*
G01X408092Y222800D02*
X407392D01*
G01X409292Y224000D02*
X408092Y222800D01*
G01X409292Y227024D02*
Y224000D01*
G01X407706Y228610D02*
X409292Y227024D01*
G01X384773Y219613D02*
G03X384792Y218072I1384J-754D01*
G01Y219647D02*
X384773Y219613D01*
G01X384817Y219689D02*
X384792Y219647D01*
G01Y221972D02*
G02X384817Y219689I-2015J-1164D01*
G01X384773Y223513D02*
G03X384792Y221972I1384J-754D01*
G01Y223547D02*
X384773Y223513D01*
G01X384817Y223589D02*
X384792Y223547D01*
G01Y225872D02*
G02X384817Y223589I-2015J-1164D01*
G01X384773Y227413D02*
G03X384792Y225872I1384J-754D01*
G01Y227447D02*
X384773Y227413D01*
G01X384817Y229730D02*
G02X384792Y227447I-2040J-1119D01*
G01Y229772D02*
X384817Y229730D01*
G01X384792Y231346D02*
G03Y229772I1365J-787D01*
G01Y233672D02*
G02Y231346I-2015J-1163D01*
G01X384726Y233788D02*
X384792Y233672D01*
G01X382777Y236409D02*
X384726Y233788D01*
G01X377316Y225611D02*
X376017Y228610D01*
G01X377382Y225497D02*
X377316Y225611D01*
G01X377401Y223956D02*
G03X377382Y225497I-1384J754D01*
G01Y223922D02*
X377401Y223956D01*
G01X377357Y223880D02*
X377382Y223922D01*
G01Y221597D02*
G02X377357Y223880I2015J1164D01*
G01X377401Y220056D02*
G03X377382Y221597I-1384J754D01*
G01Y220022D02*
X377401Y220056D01*
G01X377357Y219980D02*
X377382Y220022D01*
G01X356495Y231128D02*
X355210Y230293D01*
G01X357102Y233297D02*
G02X356495Y231128I-1365J-787D01*
G01X357036Y233410D02*
X357102Y233297D01*
G01X355737Y236409D02*
X357036Y233410D01*
G01X399676Y230559D02*
X401468Y228767D01*
G01X394116Y227798D02*
X392916Y230559D01*
G01X394281Y227448D02*
G02X394116Y227798I2015J1164D01*
G01X394281Y225874D02*
G03Y227448I-1365J787D01*
G01Y223548D02*
G02Y225874I2015J1163D01*
G01Y221974D02*
G03Y223548I-1365J787D01*
G01Y219648D02*
G02Y221974I2015J1163D01*
G01Y218074D02*
G03Y219648I-1365J787D01*
G01X361197Y237310D02*
X362497Y240309D01*
G01X361132Y237198D02*
X361197Y237310D01*
G01X361132Y235624D02*
G02Y237198I1365J787D01*
G01Y233298D02*
G03Y235624I-2015J1163D01*
G01Y231724D02*
G02Y233298I1365J787D01*
G01Y229398D02*
G03Y231724I-2015J1163D01*
G01Y227824D02*
G02Y229398I1365J787D01*
G01Y225498D02*
G03Y227824I-2015J1163D01*
G01Y223924D02*
G02Y225498I1365J787D01*
G01Y221598D02*
G03Y223924I-2015J1163D01*
G01Y220024D02*
G02Y221598I1365J787D01*
G01X358068Y231881D02*
X359117Y234460D01*
G01X357752Y231348D02*
X358068Y231881D01*
G01X357552Y230379D02*
G02X357752Y231348I1565J182D01*
G01X357420Y229289D02*
G03X357552Y230379I-2197J819D01*
G01X357311Y228546D02*
G02X357420Y229289I3579J-146D01*
G01X357102Y227824D02*
G03X357311Y228546I-1365J786D01*
G01X357102Y225498D02*
G02Y227824I2015J1163D01*
G01Y223924D02*
G03Y225498I-1365J787D01*
G01Y221598D02*
G02Y223924I2015J1163D01*
G01Y220024D02*
G03Y221598I-1365J787D01*
G01X396296Y236393D02*
Y236409D01*
G01X397948Y234741D02*
X396296Y236393D01*
G01X391491Y233781D02*
X389537Y236409D01*
G01X391552Y233673D02*
X391491Y233781D01*
G01X391577Y231388D02*
G03X391552Y233673I-2040J1120D01*
G01Y231346D02*
X391577Y231388D01*
G01X391552Y229772D02*
G02Y231346I1364J787D01*
G01X391577Y229730D02*
X391552Y229772D01*
G01Y227447D02*
G03X391577Y229730I-2015J1164D01*
G01X391552Y225873D02*
G02Y227447I1364J787D01*
G01X391587Y223607D02*
G03X391552Y225873I-2050J1102D01*
G01Y223547D02*
X391587Y223607D01*
G01X391552Y221973D02*
G02Y223547I1364J787D01*
G01X391587Y219707D02*
G03X391552Y221973I-2050J1102D01*
G01Y219647D02*
X391587Y219707D01*
G01X391552Y218073D02*
G02Y219647I1364J787D01*
G01X355737Y228610D02*
X354938Y226475D01*
G01X378013Y219613D02*
G03X378032Y218072I1384J-754D01*
G01Y219647D02*
X378013Y219613D01*
G01X378057Y219689D02*
X378032Y219647D01*
G01Y221972D02*
G02X378057Y219689I-2015J-1164D01*
G01X378013Y223513D02*
G03X378032Y221972I1384J-754D01*
G01Y223547D02*
X378013Y223513D01*
G01X378057Y223589D02*
X378032Y223547D01*
G01Y225872D02*
G02X378057Y223589I-2015J-1164D01*
G01X378013Y227413D02*
G03X378032Y225872I1384J-754D01*
G01Y227447D02*
X378013Y227413D01*
G01X378057Y229730D02*
G02X378032Y227447I-2040J-1119D01*
G01Y229772D02*
X378057Y229730D01*
G01X377822Y230599D02*
G03X378032Y229772I1575J-40D01*
G01X377822Y234604D02*
Y230599D01*
G01X376017Y236409D02*
X377822Y234604D01*
G01X380781Y219613D02*
G02X380762Y218072I-1384J-754D01*
G01Y219647D02*
X380781Y219613D01*
G01X380737Y219689D02*
X380762Y219647D01*
G01Y221972D02*
G03X380737Y219689I2015J-1164D01*
G01X380781Y223513D02*
G02X380762Y221972I-1384J-754D01*
G01Y223547D02*
X380781Y223513D01*
G01X380737Y223589D02*
X380762Y223547D01*
G01Y225872D02*
G03X380737Y223589I2015J-1164D01*
G01X380781Y227413D02*
G02X380762Y225872I-1384J-754D01*
G01X380697Y227559D02*
X380781Y227413D01*
G01X379397Y230559D02*
X380697Y227559D01*
G01X394635Y232129D02*
X392916Y234460D01*
G01X394931Y229398D02*
G03X394635Y232129I-2015J1163D01*
G01X394931Y227824D02*
G02Y229398I1365J787D01*
G01Y225498D02*
G03Y227824I-2015J1163D01*
G01Y223924D02*
G02Y225498I1365J787D01*
G01Y221598D02*
G03Y223924I-2015J1163D01*
G01Y220024D02*
G02Y221598I1365J787D01*
G01X388172Y220022D02*
X388197Y219980D01*
G01X388153Y220056D02*
X388172Y220022D01*
G01Y221597D02*
G03X388153Y220056I1365J-787D01*
G01X388197Y223880D02*
G02X388172Y221597I-2040J-1119D01*
G01Y223922D02*
X388197Y223880D01*
G01X388153Y223956D02*
X388172Y223922D01*
G01Y225497D02*
G03X388153Y223956I1365J-787D01*
G01X388172Y227823D02*
G02Y225497I-2015J-1163D01*
G01Y229397D02*
G03Y227823I1365J-787D01*
G01X388197Y229439D02*
X388172Y229397D01*
G01Y231722D02*
G02X388197Y229439I-2015J-1164D01*
G01X388107Y231835D02*
X388172Y231722D01*
G01X386157Y234460D02*
X388107Y231835D01*
G01X390901Y220022D02*
X390866Y219962D01*
G01X390901Y221596D02*
G02Y220022I-1364J-787D01*
G01X390866Y223862D02*
G03X390901Y221596I2050J-1102D01*
G01Y223922D02*
X390866Y223862D01*
G01X390901Y225496D02*
G02Y223922I-1364J-787D01*
G01X390838Y225603D02*
X390901Y225496D01*
G01X389537Y228610D02*
X390838Y225603D01*
G01X407706Y224709D02*
X404648Y221651D01*
G01X360482Y219648D02*
G02Y218074I-1365J-787D01*
G01Y221974D02*
G03Y219648I2015J-1163D01*
G01Y223548D02*
G02Y221974I-1365J-787D01*
G01Y225874D02*
G03Y223548I2015J-1163D01*
G01Y227448D02*
G02Y225874I-1365J-787D01*
G01Y229774D02*
G03Y227448I2015J-1163D01*
G01Y231348D02*
G02Y229774I-1365J-787D01*
G01Y233674D02*
G03Y231348I2015J-1163D01*
G01Y235248D02*
G02Y233674I-1365J-787D01*
G01Y237574D02*
G03Y235248I2015J-1163D01*
G01Y239148D02*
G02Y237574I-1365J-787D01*
G01X360417Y239260D02*
X360482Y239148D01*
G01X359117Y242260D02*
X360417Y239260D01*
G01X381412Y220022D02*
X381437Y219980D01*
G01X381393Y220056D02*
X381412Y220022D01*
G01Y221597D02*
G03X381393Y220056I1365J-787D01*
G01X381437Y223880D02*
G02X381412Y221597I-2040J-1119D01*
G01Y223922D02*
X381437Y223880D01*
G01X381393Y223956D02*
X381412Y223922D01*
G01Y225497D02*
G03X381393Y223956I1365J-787D01*
G01X381412Y227823D02*
G02Y225497I-2015J-1163D01*
G01X381201Y228599D02*
G03X381412Y227823I1576J12D01*
G01X381201Y232656D02*
Y228599D01*
G01X379397Y234460D02*
X381201Y232656D01*
G01X384142Y220022D02*
X384117Y219980D01*
G01X384161Y220056D02*
X384142Y220022D01*
G01Y221597D02*
G02X384161Y220056I-1365J-787D01*
G01X384117Y223880D02*
G03X384142Y221597I2040J-1119D01*
G01Y223922D02*
X384117Y223880D01*
G01X384161Y223956D02*
X384142Y223922D01*
G01Y225497D02*
G02X384161Y223956I-1365J-787D01*
G01X383845Y226009D02*
X384142Y225497D01*
G01X382749Y228540D02*
X383845Y226009D01*
G01X382777Y228610D02*
X382749Y228540D01*
G01X357752Y219648D02*
G03Y218074I1365J-787D01*
G01Y221974D02*
G02Y219648I-2015J-1163D01*
G01Y223548D02*
G03Y221974I1365J-787D01*
G01Y225874D02*
G02Y223548I-2015J-1163D01*
G01Y227448D02*
G03Y225874I1365J-787D01*
G01X357817Y227560D02*
X357752Y227448D01*
G01X359117Y230559D02*
X357817Y227560D01*
G01X387192Y399864D02*
Y405200D01*
G01X383398Y396070D02*
X387192Y399864D01*
G01X383398Y391906D02*
Y396070D01*
G01X383392Y391900D02*
X383398Y391906D01*
G01X384142Y389297D02*
G02X383392Y391900I4887J2818D01*
G01X384161Y387756D02*
G03X384142Y389297I-1384J754D01*
G01Y387722D02*
X384161Y387756D01*
G01X384117Y387680D02*
X384142Y387722D01*
G01Y385397D02*
G02X384117Y387680I2015J1164D01*
G01X384161Y383856D02*
G03X384142Y385397I-1384J754D01*
G01Y383822D02*
X384161Y383856D01*
G01X384117Y383780D02*
X384142Y383822D01*
G01Y381497D02*
G02X384117Y383780I2015J1164D01*
G01X384161Y379956D02*
G03X384142Y381497I-1384J754D01*
G01Y379922D02*
X384161Y379956D01*
G01X384117Y379880D02*
X384142Y379922D01*
G01Y377597D02*
G02X384117Y379880I2015J1164D01*
G01X384161Y376056D02*
G03X384142Y377597I-1384J754D01*
G01Y376022D02*
X384161Y376056D01*
G01X384117Y375980D02*
X384142Y376022D01*
G01Y373697D02*
G02X384117Y375980I2015J1164D01*
G01X384161Y372156D02*
G03X384142Y373697I-1384J754D01*
G01X384077Y372010D02*
X384161Y372156D01*
G01X382777Y369010D02*
X384077Y372010D01*
G01X354892Y394104D02*
Y403728D01*
G01X390092Y398500D02*
Y403719D01*
G01X386678Y395086D02*
X390092Y398500D01*
G01X386678Y392414D02*
Y395086D01*
G01X387292Y391800D02*
X386678Y392414D01*
G01X387522Y389672D02*
G03X387292Y391800I-1570J907D01*
G01X387497Y387389D02*
G02X387522Y389672I2040J1119D01*
G01Y387347D02*
X387497Y387389D01*
G01X387541Y387313D02*
X387522Y387347D01*
G01Y385772D02*
G03X387541Y387313I-1365J787D01*
G01X387497Y383489D02*
G02X387522Y385772I2040J1119D01*
G01Y383447D02*
X387497Y383489D01*
G01X387541Y383413D02*
X387522Y383447D01*
G01Y381872D02*
G03X387541Y383413I-1365J787D01*
G01X387497Y379589D02*
G02X387522Y381872I2040J1119D01*
G01Y379547D02*
X387497Y379589D01*
G01X387541Y379513D02*
X387522Y379547D01*
G01Y377972D02*
G03X387541Y379513I-1365J787D01*
G01X387497Y375689D02*
G02X387522Y377972I2040J1119D01*
G01Y375647D02*
X387497Y375689D01*
G01X387541Y375613D02*
X387522Y375647D01*
G01Y374072D02*
G03X387541Y375613I-1365J787D01*
G01X387522Y371746D02*
G02Y374072I2015J1163D01*
G01Y370172D02*
G03Y371746I-1365J787D01*
G01X387455Y370057D02*
X387522Y370172D01*
G01X386157Y367060D02*
X387455Y370057D01*
G01X359692Y402000D02*
Y403348D01*
G01X358518Y400826D02*
X359692Y402000D01*
G01X358518Y390209D02*
Y400826D01*
G01X357752Y387347D02*
G03X358518Y390209I-4963J2862D01*
G01X357733Y387313D02*
X357752Y387347D01*
G01Y385772D02*
G02X357733Y387313I1365J787D01*
G01X357777Y383489D02*
G03X357752Y385772I-2040J1119D01*
G01Y383447D02*
X357777Y383489D01*
G01X357733Y383413D02*
X357752Y383447D01*
G01Y381872D02*
G02X357733Y383413I1365J787D01*
G01X357777Y379589D02*
G03X357752Y381872I-2040J1119D01*
G01Y379547D02*
X357777Y379589D01*
G01X357733Y379513D02*
X357752Y379547D01*
G01Y377972D02*
G02X357733Y379513I1365J787D01*
G01X357777Y375689D02*
G03X357752Y377972I-2040J1119D01*
G01Y375647D02*
X357777Y375689D01*
G01X357733Y375613D02*
X357752Y375647D01*
G01Y374072D02*
G02X357733Y375613I1365J787D01*
G01X357752Y371746D02*
G03Y374072I-2015J1163D01*
G01Y370172D02*
G02Y371746I1365J787D01*
G01X357777Y370130D02*
X357752Y370172D01*
G01Y367847D02*
G03X357777Y370130I-2015J1164D01*
G01X357733Y367813D02*
X357752Y367847D01*
G01Y366272D02*
G02X357733Y367813I1365J787D01*
G01X357777Y363989D02*
G03X357752Y366272I-2040J1119D01*
G01Y363947D02*
X357777Y363989D01*
G01X357686Y363831D02*
X357752Y363947D01*
G01X355737Y361209D02*
X357686Y363831D01*
G01X379868Y401770D02*
Y403624D01*
G01X377592Y399494D02*
X379868Y401770D01*
G01X377592Y392407D02*
Y399494D01*
G01X377382Y391623D02*
G03X377592Y392407I-1358J784D01*
G01X377382Y389297D02*
G02Y391623I2015J1163D01*
G01X377401Y387756D02*
G03X377382Y389297I-1384J754D01*
G01Y387722D02*
X377401Y387756D01*
G01X377357Y387680D02*
X377382Y387722D01*
G01Y385397D02*
G02X377357Y387680I2015J1164D01*
G01X377401Y383856D02*
G03X377382Y385397I-1384J754D01*
G01Y383822D02*
X377401Y383856D01*
G01X377357Y383780D02*
X377382Y383822D01*
G01Y381497D02*
G02X377357Y383780I2015J1164D01*
G01X377401Y379956D02*
G03X377382Y381497I-1384J754D01*
G01Y379922D02*
X377401Y379956D01*
G01X377357Y379880D02*
X377382Y379922D01*
G01Y377597D02*
G02X377357Y379880I2015J1164D01*
G01X377401Y376056D02*
G03X377382Y377597I-1384J754D01*
G01Y376022D02*
X377401Y376056D01*
G01X377357Y375980D02*
X377382Y376022D01*
G01Y373697D02*
G02X377357Y375980I2015J1164D01*
G01X377401Y372156D02*
G03X377382Y373697I-1384J754D01*
G01X377317Y372010D02*
X377401Y372156D01*
G01X376017Y369010D02*
X377317Y372010D01*
G01X360532Y400840D02*
Y404760D01*
G01X359718Y400026D02*
X360532Y400840D01*
G01X359718Y388703D02*
Y400026D01*
G01X359732Y388689D02*
X359718Y388703D01*
G01X360501Y387313D02*
X359732Y388689D01*
G01X360482Y385772D02*
G03X360501Y387313I-1365J787D01*
G01X360457Y383489D02*
G02X360482Y385772I2040J1119D01*
G01Y383447D02*
X360457Y383489D01*
G01X360501Y383413D02*
X360482Y383447D01*
G01Y381872D02*
G03X360501Y383413I-1365J787D01*
G01X360457Y379589D02*
G02X360482Y381872I2040J1119D01*
G01Y379547D02*
X360457Y379589D01*
G01X360501Y379513D02*
X360482Y379547D01*
G01Y377972D02*
G03X360501Y379513I-1365J787D01*
G01X360457Y375689D02*
G02X360482Y377972I2040J1119D01*
G01Y375647D02*
X360457Y375689D01*
G01X360501Y375613D02*
X360482Y375647D01*
G01Y374072D02*
G03X360501Y375613I-1365J787D01*
G01X360482Y371746D02*
G02Y374072I2015J1163D01*
G01Y370172D02*
G03Y371746I-1365J787D01*
G01X360457Y370130D02*
X360482Y370172D01*
G01Y367847D02*
G02X360457Y370130I2015J1164D01*
G01X360501Y367813D02*
X360482Y367847D01*
G01Y366272D02*
G03X360501Y367813I-1365J787D01*
G01X360416Y366159D02*
X360482Y366272D01*
G01X359117Y363160D02*
X360416Y366159D01*
G01X394830Y365737D02*
X392916Y363160D01*
G01X394931Y368223D02*
G02X394830Y365737I-2015J-1163D01*
G01X394931Y369797D02*
G03Y368223I1365J-787D01*
G01X394956Y369839D02*
X394931Y369797D01*
G01Y372122D02*
G02X394956Y369839I-2015J-1164D01*
G01X394912Y372156D02*
X394931Y372122D01*
G01Y373697D02*
G03X394912Y372156I1365J-787D01*
G01X394956Y375980D02*
G02X394931Y373697I-2040J-1119D01*
G01Y376022D02*
X394956Y375980D01*
G01X394912Y376056D02*
X394931Y376022D01*
G01Y377597D02*
G03X394912Y376056I1365J-787D01*
G01X394956Y379880D02*
G02X394931Y377597I-2040J-1119D01*
G01Y379922D02*
X394956Y379880D01*
G01X394912Y379956D02*
X394931Y379922D01*
G01Y381497D02*
G03X394912Y379956I1365J-787D01*
G01X394956Y383780D02*
G02X394931Y381497I-2040J-1119D01*
G01Y383822D02*
X394956Y383780D01*
G01X394912Y383856D02*
X394931Y383822D01*
G01Y385397D02*
G03X394912Y383856I1365J-787D01*
G01X395084Y385715D02*
G02X394931Y385397I-2167J847D01*
G01X396159Y386790D02*
X395084Y385715D01*
G01X397028Y386790D02*
X396159D01*
G01X398092Y387854D02*
X397028Y386790D01*
G01X398092Y400200D02*
Y387854D01*
G01X400292Y402400D02*
X398092Y400200D01*
G01X400292Y405128D02*
Y402400D01*
G01X395192Y394528D02*
Y403301D01*
G01X393086Y392422D02*
X395192Y394528D01*
G01X391551Y391248D02*
G02X393086Y392422I2178J-1257D01*
G01X391520Y389729D02*
G02X391551Y391248I1396J731D01*
G01X391552Y389673D02*
X391520Y389729D01*
G01X391587Y387407D02*
G03X391552Y389673I-2050J1102D01*
G01Y387347D02*
X391587Y387407D01*
G01X391552Y385773D02*
G02Y387347I1364J787D01*
G01X391587Y383507D02*
G03X391552Y385773I-2050J1102D01*
G01Y383447D02*
X391587Y383507D01*
G01X391552Y381873D02*
G02Y383447I1364J787D01*
G01X391587Y379607D02*
G03X391552Y381873I-2050J1102D01*
G01Y379547D02*
X391587Y379607D01*
G01X391552Y377973D02*
G02Y379547I1364J787D01*
G01X391587Y375707D02*
G03X391552Y377973I-2050J1102D01*
G01Y375647D02*
X391587Y375707D01*
G01X391552Y374073D02*
G02Y375647I1364J787D01*
G01X391577Y371788D02*
G03X391552Y374073I-2040J1120D01*
G01Y371746D02*
X391577Y371788D01*
G01X391552Y370172D02*
G02Y371746I1364J787D01*
G01X391577Y370130D02*
X391552Y370172D01*
G01Y367847D02*
G03X391577Y370130I-2015J1164D01*
G01X391552Y366273D02*
G02Y367847I1364J787D01*
G01X391587Y364007D02*
G03X391552Y366273I-2050J1102D01*
G01X391488Y363834D02*
X391587Y364007D01*
G01X389537Y361209D02*
X391488Y363834D01*
G01X388492Y399044D02*
Y404266D01*
G01X384488Y395040D02*
X388492Y399044D01*
G01X384488Y392104D02*
Y395040D01*
G01X384492Y392100D02*
X384488Y392104D01*
G01X384792Y389672D02*
G02X384492Y392100I2714J1568D01*
G01X384817Y387389D02*
G03X384792Y389672I-2040J1119D01*
G01Y387347D02*
X384817Y387389D01*
G01X384773Y387313D02*
X384792Y387347D01*
G01Y385772D02*
G02X384773Y387313I1365J787D01*
G01X384817Y383489D02*
G03X384792Y385772I-2040J1119D01*
G01Y383447D02*
X384817Y383489D01*
G01X384773Y383413D02*
X384792Y383447D01*
G01Y381872D02*
G02X384773Y383413I1365J787D01*
G01X384817Y379589D02*
G03X384792Y381872I-2040J1119D01*
G01Y379547D02*
X384817Y379589D01*
G01X384773Y379513D02*
X384792Y379547D01*
G01Y377972D02*
G02X384773Y379513I1365J787D01*
G01X384817Y375689D02*
G03X384792Y377972I-2040J1119D01*
G01Y375647D02*
X384817Y375689D01*
G01X384773Y375613D02*
X384792Y375647D01*
G01Y374072D02*
G02X384773Y375613I1365J787D01*
G01X384792Y371746D02*
G03Y374072I-2015J1163D01*
G01Y370172D02*
G02Y371746I1365J787D01*
G01X384817Y370130D02*
X384792Y370172D01*
G01Y367847D02*
G03X384817Y370130I-2015J1164D01*
G01X384773Y367813D02*
X384792Y367847D01*
G01X384605Y366785D02*
G02X384773Y367813I1552J274D01*
G01X384605Y364513D02*
Y366785D01*
G01X382777Y362685D02*
X384605Y364513D01*
G01X382777Y361209D02*
Y362685D01*
G01X394111Y369810D02*
X392916Y367060D01*
G01X394256Y370130D02*
G03X394111Y369810I2041J-1118D01*
G01X394281Y370172D02*
X394256Y370130D01*
G01X394281Y371746D02*
G02Y370172I-1365J-787D01*
G01Y374072D02*
G03Y371746I2015J-1163D01*
G01X394300Y375613D02*
G02X394281Y374072I-1384J-754D01*
G01Y375647D02*
X394300Y375613D01*
G01X394256Y375689D02*
X394281Y375647D01*
G01Y377972D02*
G03X394256Y375689I2015J-1164D01*
G01X394300Y379513D02*
G02X394281Y377972I-1384J-754D01*
G01Y379547D02*
X394300Y379513D01*
G01X394256Y379589D02*
X394281Y379547D01*
G01Y381872D02*
G03X394256Y379589I2015J-1164D01*
G01X394300Y383413D02*
G02X394281Y381872I-1384J-754D01*
G01Y383447D02*
X394300Y383413D01*
G01X394256Y383489D02*
X394281Y383447D01*
G01Y385772D02*
G03X394256Y383489I2015J-1164D01*
G01X394300Y387313D02*
G02X394281Y385772I-1384J-754D01*
G01Y387347D02*
X394300Y387313D01*
G01X394256Y387389D02*
X394281Y387347D01*
G01Y389672D02*
G03X394256Y387389I2015J-1164D01*
G01X394841Y390642D02*
X394281Y389672D01*
G01X396092Y391893D02*
X394841Y390642D01*
G01X396092Y402672D02*
Y391893D01*
G01X399292Y405872D02*
X396092Y402672D01*
G01X394192Y395400D02*
Y404000D01*
G01X392692Y393900D02*
X394192Y395400D01*
G01X390858Y391546D02*
G02X392692Y393900I7524J-3970D01*
G01X390901Y389296D02*
G02X390858Y391546I2015J1164D01*
G01X390901Y387722D02*
G03Y389296I-1364J787D01*
G01X390866Y387662D02*
X390901Y387722D01*
G01Y385396D02*
G02X390866Y387662I2015J1164D01*
G01X390901Y383822D02*
G03Y385396I-1364J787D01*
G01X390866Y383762D02*
X390901Y383822D01*
G01Y381496D02*
G02X390866Y383762I2015J1164D01*
G01X390901Y379922D02*
G03Y381496I-1364J787D01*
G01X390866Y379862D02*
X390901Y379922D01*
G01Y377596D02*
G02X390866Y379862I2015J1164D01*
G01X390901Y376022D02*
G03Y377596I-1364J787D01*
G01X390866Y375962D02*
X390901Y376022D01*
G01Y373696D02*
G02X390866Y375962I2015J1164D01*
G01X390901Y372122D02*
G03Y373696I-1364J787D01*
G01X390838Y372014D02*
X390901Y372122D01*
G01X389537Y369010D02*
X390838Y372014D01*
G01X385192Y400274D02*
Y405100D01*
G01X382092Y397174D02*
X385192Y400274D01*
G01X382092Y391838D02*
Y397174D01*
G01X381412Y389297D02*
G03X382092Y391838I-4407J2541D01*
G01X381393Y387756D02*
G02X381412Y389297I1384J754D01*
G01Y387722D02*
X381393Y387756D01*
G01X381437Y387680D02*
X381412Y387722D01*
G01Y385397D02*
G03X381437Y387680I-2015J1164D01*
G01X381393Y383856D02*
G02X381412Y385397I1384J754D01*
G01Y383822D02*
X381393Y383856D01*
G01X381437Y383780D02*
X381412Y383822D01*
G01Y381497D02*
G03X381437Y383780I-2015J1164D01*
G01X381393Y379956D02*
G02X381412Y381497I1384J754D01*
G01Y379922D02*
X381393Y379956D01*
G01X381437Y379880D02*
X381412Y379922D01*
G01Y377597D02*
G03X381437Y379880I-2015J1164D01*
G01X381393Y376056D02*
G02X381412Y377597I1384J754D01*
G01Y376022D02*
X381393Y376056D01*
G01X381437Y375980D02*
X381412Y376022D01*
G01Y373697D02*
G03X381437Y375980I-2015J1164D01*
G01X381393Y372156D02*
G02X381412Y373697I1384J754D01*
G01Y372122D02*
X381393Y372156D01*
G01X381437Y369839D02*
G03X381412Y372122I-2040J1119D01*
G01Y369797D02*
X381437Y369839D01*
G01X381412Y368223D02*
G02Y369797I1365J787D01*
G01X381385Y365850D02*
G03X381412Y368223I-1988J1209D01*
G01X379397Y363160D02*
X381385Y365850D01*
G01X381192Y400904D02*
Y405204D01*
G01X378844Y398556D02*
X381192Y400904D01*
G01X378844Y392166D02*
Y398556D01*
G01X378032Y391247D02*
G02X378844Y392166I2517J-1405D01*
G01X378013Y391213D02*
X378032Y391247D01*
G01Y389672D02*
G02X378013Y391213I1365J787D01*
G01X378057Y387389D02*
G03X378032Y389672I-2040J1119D01*
G01Y387347D02*
X378057Y387389D01*
G01X378013Y387313D02*
X378032Y387347D01*
G01Y385772D02*
G02X378013Y387313I1365J787D01*
G01X378057Y383489D02*
G03X378032Y385772I-2040J1119D01*
G01Y383447D02*
X378057Y383489D01*
G01X378013Y383413D02*
X378032Y383447D01*
G01Y381872D02*
G02X378013Y383413I1365J787D01*
G01X378057Y379589D02*
G03X378032Y381872I-2040J1119D01*
G01Y379547D02*
X378057Y379589D01*
G01X378013Y379513D02*
X378032Y379547D01*
G01Y377972D02*
G02X378013Y379513I1365J787D01*
G01X378057Y375689D02*
G03X378032Y377972I-2040J1119D01*
G01Y375647D02*
X378057Y375689D01*
G01X378013Y375613D02*
X378032Y375647D01*
G01Y374072D02*
G02X378013Y375613I1365J787D01*
G01X378032Y371746D02*
G03Y374072I-2015J1163D01*
G01Y370172D02*
G02Y371746I1365J787D01*
G01X378057Y370130D02*
X378032Y370172D01*
G01Y367847D02*
G03X378057Y370130I-2015J1164D01*
G01X378013Y367813D02*
X378032Y367847D01*
G01Y366272D02*
G02X378013Y367813I1365J787D01*
G01X378079Y366097D02*
G03X378032Y366272I-351J0D01*
G01X378079Y364787D02*
Y366097D01*
G01X376017Y362725D02*
X378079Y364787D01*
G01X376017Y361209D02*
Y362725D01*
G01X356192Y395586D02*
Y403300D01*
G01X357318Y394460D02*
X356192Y395586D01*
G01X357318Y391500D02*
Y394460D01*
G01X357313Y391495D02*
X357318Y391500D01*
G01X357313Y388501D02*
Y391495D01*
G01X357102Y387722D02*
G03X357313Y388501I-1365J788D01*
G01X357077Y387680D02*
X357102Y387722D01*
G01Y385397D02*
G02X357077Y387680I2015J1164D01*
G01X357121Y383856D02*
G03X357102Y385397I-1384J754D01*
G01Y383822D02*
X357121Y383856D01*
G01X357077Y383780D02*
X357102Y383822D01*
G01Y381497D02*
G02X357077Y383780I2015J1164D01*
G01X357121Y379956D02*
G03X357102Y381497I-1384J754D01*
G01Y379922D02*
X357121Y379956D01*
G01X357077Y379880D02*
X357102Y379922D01*
G01Y377597D02*
G02X357077Y379880I2015J1164D01*
G01X357121Y376056D02*
G03X357102Y377597I-1384J754D01*
G01Y376022D02*
X357121Y376056D01*
G01X357077Y375980D02*
X357102Y376022D01*
G01Y373697D02*
G02X357077Y375980I2015J1164D01*
G01X357121Y372156D02*
G03X357102Y373697I-1384J754D01*
G01X357037Y372010D02*
X357121Y372156D01*
G01X355737Y369010D02*
X357037Y372010D01*
G01X383192Y400744D02*
Y402828D01*
G01X380977Y398529D02*
X383192Y400744D01*
G01X380977Y391215D02*
Y398529D01*
G01X380992Y391200D02*
X380977Y391215D01*
G01X380762Y389672D02*
G03X380992Y391200I-1829J1057D01*
G01X380737Y387389D02*
G02X380762Y389672I2040J1119D01*
G01Y387347D02*
X380737Y387389D01*
G01X380781Y387313D02*
X380762Y387347D01*
G01Y385772D02*
G03X380781Y387313I-1365J787D01*
G01X380737Y383489D02*
G02X380762Y385772I2040J1119D01*
G01Y383447D02*
X380737Y383489D01*
G01X380781Y383413D02*
X380762Y383447D01*
G01Y381872D02*
G03X380781Y383413I-1365J787D01*
G01X380737Y379589D02*
G02X380762Y381872I2040J1119D01*
G01Y379547D02*
X380737Y379589D01*
G01X380781Y379513D02*
X380762Y379547D01*
G01Y377972D02*
G03X380781Y379513I-1365J787D01*
G01X380737Y375689D02*
G02X380762Y377972I2040J1119D01*
G01Y375647D02*
X380737Y375689D01*
G01X380781Y375613D02*
X380762Y375647D01*
G01Y374072D02*
G03X380781Y375613I-1365J787D01*
G01X380762Y371746D02*
G02Y374072I2015J1163D01*
G01Y370172D02*
G03Y371746I-1365J787D01*
G01X380737Y370130D02*
X380762Y370172D01*
G01X380585Y369792D02*
G02X380737Y370130I2191J-782D01*
G01X379397Y367060D02*
X380585Y369792D01*
G01X362532Y400739D02*
Y401713D01*
G01X360918Y399125D02*
X362532Y400739D01*
G01X360918Y388115D02*
Y399125D01*
G01X361132Y387722D02*
X360918Y388115D01*
G01X361157Y387680D02*
X361132Y387722D01*
G01Y385397D02*
G03X361157Y387680I-2015J1164D01*
G01X361113Y383856D02*
G02X361132Y385397I1384J754D01*
G01Y383822D02*
X361113Y383856D01*
G01X361157Y383780D02*
X361132Y383822D01*
G01Y381497D02*
G03X361157Y383780I-2015J1164D01*
G01X361113Y379956D02*
G02X361132Y381497I1384J754D01*
G01Y379922D02*
X361113Y379956D01*
G01X361157Y379880D02*
X361132Y379922D01*
G01Y377597D02*
G03X361157Y379880I-2015J1164D01*
G01X361113Y376056D02*
G02X361132Y377597I1384J754D01*
G01Y376022D02*
X361113Y376056D01*
G01X361157Y375980D02*
X361132Y376022D01*
G01Y373697D02*
G03X361157Y375980I-2015J1164D01*
G01X361113Y372156D02*
G02X361132Y373697I1384J754D01*
G01Y372122D02*
X361113Y372156D01*
G01X361157Y369839D02*
G03X361132Y372122I-2040J1119D01*
G01Y369797D02*
X361157Y369839D01*
G01X361132Y368223D02*
G02Y369797I1365J787D01*
G01Y365897D02*
G03Y368223I-2015J1163D01*
G01X360908Y365060D02*
G02X361132Y365897I1677J0D01*
G01X360908Y358951D02*
Y365060D01*
G01X359117Y355360D02*
X360908Y358951D01*
G01X393392Y399584D02*
Y404200D01*
G01X388492Y394684D02*
X393392Y399584D01*
G01X388492Y392400D02*
Y394684D01*
G01X388592Y392300D02*
X388492Y392400D01*
G01X388172Y389297D02*
G03X388592Y392300I-3506J2021D01*
G01X388153Y387756D02*
G02X388172Y389297I1384J754D01*
G01Y387722D02*
X388153Y387756D01*
G01X388197Y387680D02*
X388172Y387722D01*
G01Y385397D02*
G03X388197Y387680I-2015J1164D01*
G01X388153Y383856D02*
G02X388172Y385397I1384J754D01*
G01Y383822D02*
X388153Y383856D01*
G01X388197Y383780D02*
X388172Y383822D01*
G01Y381497D02*
G03X388197Y383780I-2015J1164D01*
G01X388153Y379956D02*
G02X388172Y381497I1384J754D01*
G01Y379922D02*
X388153Y379956D01*
G01X388197Y379880D02*
X388172Y379922D01*
G01Y377597D02*
G03X388197Y379880I-2015J1164D01*
G01X388153Y376056D02*
G02X388172Y377597I1384J754D01*
G01Y376022D02*
X388153Y376056D01*
G01X388197Y375980D02*
X388172Y376022D01*
G01Y373697D02*
G03X388197Y375980I-2015J1164D01*
G01X388153Y372156D02*
G02X388172Y373697I1384J754D01*
G01Y372122D02*
X388153Y372156D01*
G01X388197Y369839D02*
G03X388172Y372122I-2040J1119D01*
G01Y369797D02*
X388197Y369839D01*
G01X388021Y368580D02*
G02X388172Y369797I1516J430D01*
G01X388021Y366329D02*
Y368580D01*
G01X386157Y364465D02*
X388021Y366329D01*
G01X386157Y363160D02*
Y364465D01*
G01X355792Y404628D02*
Y413600D01*
G01X354892Y403728D02*
X355792Y404628D01*
G01X391258Y404885D02*
Y405606D01*
G01X390092Y403719D02*
X391258Y404885D01*
G01X358501Y404539D02*
Y405305D01*
G01X359692Y403348D02*
X358501Y404539D01*
G01X379192Y404300D02*
Y405271D01*
G01X379868Y403624D02*
X379192Y404300D01*
G01X401292Y406128D02*
X400292Y405128D01*
G01X401292Y407111D02*
Y406128D01*
G01X397292Y405401D02*
Y406829D01*
G01X395192Y403301D02*
X397292Y405401D01*
G01X389192Y404966D02*
Y405821D01*
G01X388492Y404266D02*
X389192Y404966D01*
G01X399292Y407111D02*
Y405872D01*
G01X395292Y405100D02*
Y406265D01*
G01X394192Y404000D02*
X395292Y405100D01*
G01X357792Y412759D02*
Y413816D01*
G01X356712Y411679D02*
X357792Y412759D01*
G01X356712Y403820D02*
Y411679D01*
G01X356192Y403300D02*
X356712Y403820D01*
G01X393292Y404300D02*
Y405741D01*
G01X393392Y404200D02*
X393292Y404300D01*
G01X453848Y189956D02*
X454868Y188936D01*
G01X453848Y196611D02*
Y189956D01*
G01X453555Y196904D02*
X453848Y196611D01*
G01X453555Y199578D02*
Y196904D01*
G01X454144Y200167D02*
X453555Y199578D01*
G01X454144Y202805D02*
Y200167D01*
G01X455022Y203683D02*
X454144Y202805D01*
G01X455022Y211370D02*
Y203683D01*
G01X454817Y211575D02*
X455022Y211370D01*
G01X454817Y212296D02*
Y211575D01*
G01X455028Y213084D02*
G03X454817Y212296I1365J-788D01*
G01X455053Y215367D02*
G02X455028Y213084I-2040J-1119D01*
G01Y215409D02*
X455053Y215367D01*
G01X455009Y215443D02*
X455028Y215409D01*
G01X455563Y217536D02*
G03X455009Y215443I830J-1340D01*
G01X457514Y218887D02*
X455563Y217536D01*
G01X427226Y185633D02*
X426592Y184999D01*
G01X427226Y198107D02*
Y185633D01*
G01X431619Y202500D02*
X427226Y198107D01*
G01X431619Y206871D02*
Y202500D01*
G01X434396Y209648D02*
X431619Y206871D01*
G01X434396Y212478D02*
Y209648D01*
G01X434746Y213085D02*
X434396Y212478D01*
G01X434748Y213084D02*
X434746Y213085D01*
G01X434748Y215410D02*
G02Y213084I-2017J-1163D01*
G01Y216984D02*
G03Y215410I1365J-787D01*
G01X436687Y218630D02*
G03X434748Y216984I1328J-3530D01*
G01X471858Y194346D02*
X471108Y193596D01*
G01X471858Y195481D02*
Y194346D01*
G01X469855Y197484D02*
X471858Y195481D01*
G01X469855Y201710D02*
Y197484D01*
G01X468198Y203367D02*
X469855Y201710D01*
G01X468198Y210421D02*
Y203367D01*
G01X467544Y211075D02*
X468198Y210421D01*
G01X467544Y216745D02*
Y211075D01*
G01X467898Y217359D02*
X467544Y216745D01*
G01X467917Y218900D02*
G02X467898Y217359I-1384J-754D01*
G01X448156Y194374D02*
X447218Y193436D01*
G01X448156Y195593D02*
Y194374D01*
G01X449776Y197213D02*
X448156Y195593D01*
G01X449776Y200889D02*
Y197213D01*
G01X450546Y201659D02*
X449776Y200889D01*
G01X450546Y204299D02*
Y201659D01*
G01X451252Y205005D02*
X450546Y204299D01*
G01X451252Y212644D02*
Y205005D01*
G01X450998Y213084D02*
X451252Y212644D01*
G01X450973Y215367D02*
G03X450998Y213084I2040J-1119D01*
G01Y215409D02*
X450973Y215367D01*
G01X451017Y215443D02*
X450998Y215409D01*
G01Y216984D02*
G02X451017Y215443I-1365J-787D01*
G01X450973Y219267D02*
G03X450998Y216984I2040J-1119D01*
G01X466835Y191423D02*
X466008Y190596D01*
G01X466835Y200428D02*
Y191423D01*
G01X464207Y203056D02*
X466835Y200428D01*
G01X464207Y210516D02*
Y203056D01*
G01X464729Y211038D02*
X464207Y210516D01*
G01X464729Y216196D02*
Y211038D01*
G01X464518Y216984D02*
G02X464729Y216196I-1365J-788D01*
G01X464391Y217238D02*
G03X464518Y216984I2141J912D01*
G01X463153Y220096D02*
X464391Y217238D01*
G01X477715Y205174D02*
X483392Y199497D01*
G01X477715Y207890D02*
Y205174D01*
G01X474292Y211313D02*
X477715Y207890D01*
G01X474292Y212752D02*
Y211313D01*
G01X474657Y213459D02*
X474292Y212752D01*
G01X474676Y215000D02*
G02X474657Y213459I-1384J-754D01*
G01Y215034D02*
X474676Y215000D01*
G01X474632Y215076D02*
X474657Y215034D01*
G01Y217359D02*
G03X474632Y215076I2015J-1164D01*
G01X474900Y217786D02*
X474657Y217359D01*
G01X476611Y220087D02*
X474900Y217786D01*
G01X467585Y191569D02*
X468558Y190596D01*
G01X467585Y200770D02*
Y191569D01*
G01X464958Y203397D02*
X467585Y200770D01*
G01X464958Y210113D02*
Y203397D01*
G01X465480Y210635D02*
X464958Y210113D01*
G01X465480Y216196D02*
Y210635D01*
G01X465242Y217219D02*
G02X465480Y216196I-2097J-1027D01*
G01X465168Y217360D02*
G02X465242Y217219I-1738J-1002D01*
G01X465168Y218934D02*
G03Y217360I1365J-787D01*
G01X448906Y194298D02*
X449768Y193436D01*
G01X448906Y195281D02*
Y194298D01*
G01X450526Y196901D02*
X448906Y195281D01*
G01X450526Y200577D02*
Y196901D01*
G01X451296Y201347D02*
X450526Y200577D01*
G01X451296Y203988D02*
Y201347D01*
G01X452002Y204694D02*
X451296Y203988D01*
G01X452002Y212901D02*
Y204694D01*
G01X451648Y213459D02*
X452002Y212901D01*
G01X451629Y215000D02*
G03X451648Y213459I1384J-754D01*
G01Y215034D02*
X451629Y215000D01*
G01X451673Y215076D02*
X451648Y215034D01*
G01Y217359D02*
G02X451673Y215076I-2015J-1164D01*
G01X451629Y218900D02*
G03X451648Y217359I1384J-754D01*
G01X474861Y203668D02*
X478595Y199934D01*
G01X474861Y206787D02*
Y203668D01*
G01X471492Y210156D02*
X474861Y206787D01*
G01X471492Y212712D02*
Y210156D01*
G01X471277Y213084D02*
X471492Y212712D01*
G01X471252Y215367D02*
G03X471277Y213084I2040J-1119D01*
G01Y215409D02*
X471252Y215367D01*
G01X471296Y215443D02*
X471277Y215409D01*
G01Y216984D02*
G02X471296Y215443I-1365J-787D01*
G01X471252Y219267D02*
G03X471277Y216984I2040J-1119D01*
G01X424276Y187284D02*
X421692Y184700D01*
G01X424276Y199188D02*
Y187284D01*
G01X428769Y203681D02*
X424276Y199188D01*
G01X428769Y208051D02*
Y203681D01*
G01X431718Y211000D02*
X428769Y208051D01*
G01X431718Y212858D02*
Y211000D01*
G01X431369Y213459D02*
X431718Y212858D01*
G01X431350Y215000D02*
G03X431369Y213459I1383J-754D01*
G01Y215034D02*
X431350Y215000D01*
G01X431404Y215094D02*
X431369Y215034D01*
G01Y217360D02*
G02X431404Y215094I-2015J-1164D01*
G01X431270Y218728D02*
G03X431369Y217360I1463J-582D01*
G01X423526Y189469D02*
X419592Y185535D01*
G01X423526Y199499D02*
Y189469D01*
G01X428019Y203992D02*
X423526Y199499D01*
G01X428019Y208362D02*
Y203992D01*
G01X430968Y211311D02*
X428019Y208362D01*
G01X430968Y212652D02*
Y211311D01*
G01X430718Y213082D02*
X430968Y212652D01*
G01X430676Y215336D02*
G03X430718Y213082I2057J-1089D01*
G01Y215409D02*
X430676Y215336D01*
G01X430718Y216983D02*
G02Y215409I-1364J-787D01*
G01X430601Y219081D02*
G03X430718Y216983I2132J-933D01*
G01X472608Y194646D02*
X473658Y193596D01*
G01X472608Y195793D02*
Y194646D01*
G01X470605Y197796D02*
X472608Y195793D01*
G01X470605Y202022D02*
Y197796D01*
G01X468948Y203679D02*
X470605Y202022D01*
G01X468948Y210732D02*
Y203679D01*
G01X468294Y211386D02*
X468948Y210732D01*
G01X468294Y216544D02*
Y211386D01*
G01X468548Y216984D02*
X468294Y216544D01*
G01X468573Y219267D02*
G02X468548Y216984I-2040J-1119D01*
G01X439018Y187674D02*
X440092Y186600D01*
G01X439018Y192417D02*
Y187674D01*
G01X443957Y197356D02*
X439018Y192417D01*
G01X443957Y201880D02*
Y197356D01*
G01X447828Y205751D02*
X443957Y201880D01*
G01X447828Y207841D02*
Y205751D01*
G01X447308Y208361D02*
X447828Y207841D01*
G01X447308Y216822D02*
Y208361D01*
G01X447618Y217359D02*
X447308Y216822D01*
G01X447637Y218900D02*
G02X447618Y217359I-1384J-754D01*
G01X475611Y203981D02*
X479392Y200200D01*
G01X475611Y207098D02*
Y203981D01*
G01X472242Y210467D02*
X475611Y207098D01*
G01X472242Y212963D02*
Y210467D01*
G01X471927Y213459D02*
X472242Y212963D01*
G01X471908Y215000D02*
G03X471927Y213459I1384J-754D01*
G01Y215034D02*
X471908Y215000D01*
G01X471952Y215076D02*
X471927Y215034D01*
G01Y217359D02*
G02X471952Y215076I-2015J-1164D01*
G01X471908Y218900D02*
G03X471927Y217359I1384J-754D01*
G01X439768Y189321D02*
X441992Y187097D01*
G01X439768Y192106D02*
Y189321D01*
G01X444707Y197045D02*
X439768Y192106D01*
G01X444707Y201566D02*
Y197045D01*
G01X448578Y205437D02*
X444707Y201566D01*
G01X448578Y208153D02*
Y205437D01*
G01X448058Y208673D02*
X448578Y208153D01*
G01X448058Y216609D02*
Y208673D01*
G01X448268Y216984D02*
X448058Y216609D01*
G01X448293Y219267D02*
G02X448268Y216984I-2040J-1119D01*
G01X453098Y189716D02*
X452318Y188936D01*
G01X453098Y196299D02*
Y189716D01*
G01X452805Y196592D02*
X453098Y196299D01*
G01X452805Y199890D02*
Y196592D01*
G01X453394Y200479D02*
X452805Y199890D01*
G01X453394Y203116D02*
Y200479D01*
G01X454272Y203994D02*
X453394Y203116D01*
G01X454272Y211057D02*
Y203994D01*
G01X454066Y211263D02*
X454272Y211057D01*
G01X454066Y212296D02*
Y211263D01*
G01X454378Y213459D02*
G03X454066Y212296I2015J-1164D01*
G01X454397Y215000D02*
G02X454378Y213459I-1384J-754D01*
G01Y215034D02*
X454397Y215000D01*
G01X454353Y215076D02*
X454378Y215034D01*
G01Y217359D02*
G03X454353Y215076I2015J-1164D01*
G01X454444Y217475D02*
X454378Y217359D01*
G01X456393Y220096D02*
X454444Y217475D01*
G01X475042Y211625D02*
X478465Y208202D01*
G01X475042Y212570D02*
Y211625D01*
G01X475307Y213084D02*
X475042Y212570D01*
G01X475332Y215367D02*
G02X475307Y213084I-2040J-1119D01*
G01Y215409D02*
X475332Y215367D01*
G01X475288Y215443D02*
X475307Y215409D01*
G01Y216984D02*
G03X475288Y215443I1365J-787D01*
G01X475491Y217303D02*
X475307Y216984D01*
G01X476036Y217889D02*
X475491Y217303D01*
G01X476758Y218423D02*
X476036Y217889D01*
G01X435760Y186432D02*
X436292Y185900D01*
G01X435760Y193190D02*
Y186432D01*
G01X439418Y196848D02*
X435760Y193190D01*
G01X439418Y203583D02*
Y196848D01*
G01X444449Y208614D02*
X439418Y203583D01*
G01X444449Y216196D02*
Y208614D01*
G01X444238Y216984D02*
G02X444449Y216196I-1365J-788D01*
G01X444088Y217296D02*
G03X444238Y216984I2166J849D01*
G01X442873Y220096D02*
X444088Y217296D01*
G01X444888Y217360D02*
G02Y218934I1365J787D01*
G01X445199Y216241D02*
G03X444888Y217360I-2326J-44D01*
G01X436510Y187882D02*
X438192Y186200D01*
G01X436510Y192879D02*
Y187882D01*
G01X440168Y196537D02*
X436510Y192879D01*
G01X440168Y203267D02*
Y196537D01*
G01X445199Y208298D02*
X440168Y203267D01*
G01X445199Y216241D02*
Y208298D01*
G01X426148Y186756D02*
X424692Y185300D01*
G01X426148Y188941D02*
Y186756D01*
G01X426476Y189269D02*
X426148Y188941D01*
G01X426476Y198418D02*
Y189269D01*
G01X430869Y202811D02*
X426476Y198418D01*
G01X430869Y207182D02*
Y202811D01*
G01X433646Y209959D02*
X430869Y207182D01*
G01X433646Y212676D02*
Y209959D01*
G01X434098Y213459D02*
X433646Y212676D01*
G01X434098Y215034D02*
G02Y213459I-1364J-788D01*
G01Y217360D02*
G03Y215034I2015J-1163D01*
G01X434114Y217388D02*
X434098Y217360D01*
G01X435947Y219920D02*
G03X434114Y217388I11333J-10134D01*
G01X457777Y219343D02*
X457514Y218887D01*
G01X457758Y220884D02*
G02X457777Y219343I-1365J-787D01*
G01X457592Y221172D02*
X457758Y220884D01*
G01X455094Y224897D02*
X456393Y227896D01*
G01X455028Y224784D02*
X455094Y224897D01*
G01X455463Y222724D02*
G02X455028Y224784I930J1272D01*
G01X456868Y221774D02*
X455463Y222724D01*
G01X457592Y221172D02*
X456868Y221774D01*
G01X477250Y268850D02*
X478847Y267253D01*
G01X475689Y268850D02*
X477250D01*
G01X474123Y270416D02*
X475689Y268850D01*
G01X472606Y270416D02*
X474123D01*
G01X471417Y269227D02*
X472606Y270416D01*
G01X468774Y269227D02*
X471417D01*
G01X467585Y270416D02*
X468774Y269227D01*
G01X463955Y270416D02*
X467585D01*
G01X463067Y269528D02*
X463955Y270416D01*
G01X460572Y269528D02*
X463067D01*
G01X459385Y270715D02*
X460572Y269528D01*
G01X454985Y270715D02*
X459385D01*
G01X454050Y271650D02*
X454985Y270715D01*
G01X451550Y271650D02*
X454050D01*
G01X450800Y270900D02*
X451550Y271650D01*
G01X450800Y267947D02*
Y270900D01*
G01X449288Y266435D02*
X450800Y267947D01*
G01X437363Y221056D02*
G02X436687Y218630I-1250J-959D01*
G01X435509Y222542D02*
G02X437363Y221056I-1636J-3940D01*
G01X434748Y224784D02*
G03X435509Y222542I1365J-787D01*
G01X436113Y227896D02*
X434748Y224784D01*
G01X467898Y218934D02*
X467917Y218900D01*
G01X467873Y218976D02*
X467898Y218934D01*
G01X467720Y219317D02*
G03X467873Y218976I2193J779D01*
G01X466533Y222047D02*
X467720Y219317D01*
G01X450998Y219309D02*
X450973Y219267D01*
G01X451311Y219860D02*
X450998Y219309D01*
G01X452928Y222034D02*
X451311Y219860D01*
G01X453013Y222047D02*
X452928Y222034D01*
G01X476672Y220096D02*
X476611Y220087D01*
G01X465168Y221260D02*
G02Y218934I-2015J-1163D01*
G01X464705Y223727D02*
G03X465168Y221260I3741J-575D01*
G01X464518Y224784D02*
G02X464705Y223727I-1365J-787D01*
G01X463153Y227896D02*
X464518Y224784D01*
G01X451810Y219215D02*
X451629Y218900D01*
G01X452225Y219724D02*
X451810Y219215D01*
G01X452840Y220278D02*
X452225Y219724D01*
G01X453656Y220608D02*
X452840Y220278D01*
G01X454397Y222800D02*
G02X453656Y220608I-1384J-753D01*
G01X454310Y222951D02*
X454397Y222800D01*
G01X453013Y225947D02*
X454310Y222951D01*
G01X476757Y265321D02*
G02X478687Y264159I-85J-2325D01*
G01X476628Y265321D02*
X476757D01*
G01X475307Y266109D02*
G03X476628Y265321I1365J787D01*
G01X471277Y266109D02*
G02X475307I2015J-1162D01*
G01X471264Y266086D02*
X471277Y266109D01*
G01X468548D02*
G03X471264Y266086I1365J787D01*
G01X466603Y267272D02*
G02X468548Y266109I-70J-2325D01*
G01X465626Y267272D02*
X466603D01*
G01X465624Y267274D02*
X465626Y267272D01*
G01X460239Y267274D02*
X465624D01*
G01X466577Y266522D02*
X464976D01*
G01X467898Y265734D02*
G03X466577Y266522I-1365J-787D01*
G01X471928Y265734D02*
G02X467898I-2015J1162D01*
G01X471941Y265757D02*
X471928Y265734D01*
G01X474657D02*
G03X471941Y265757I-1365J-787D01*
G01X476602Y264571D02*
G02X474657Y265734I70J2325D01*
G01X476731Y264571D02*
X476602D01*
G01X478037Y263784D02*
G03X476731Y264571I-1365J-788D01*
G01X479967Y262622D02*
G02X478037Y263784I85J2325D01*
G01X471277Y219309D02*
X471252Y219267D01*
G01X471590Y219860D02*
X471277Y219309D01*
G01X471673Y220171D02*
G02X471590Y219860I-636J3D01*
G01X471673Y221836D02*
Y220171D01*
G01X471884Y222047D02*
X471673Y221836D01*
G01X473292Y222047D02*
X471884D01*
G01X441399Y263699D02*
X439764D01*
G01X442651Y264951D02*
X441399Y263699D01*
G01X442651Y267848D02*
Y264951D01*
G01X448003Y273200D02*
X442651Y267848D01*
G01X448089Y273200D02*
X448003D01*
G01X448090Y273201D02*
X448089Y273200D01*
G01X460847Y273201D02*
X448090D01*
G01X461062Y273416D02*
X460847Y273201D01*
G01X462984Y273416D02*
X461062D01*
G01X463150Y273250D02*
X462984Y273416D01*
G01X471050Y273250D02*
X463150D01*
G01X472300Y272000D02*
X471050Y273250D01*
G01X475000Y272000D02*
X472300D01*
G01X475822Y271178D02*
X475000Y272000D01*
G01X479278Y271178D02*
X475822D01*
G01X477142Y278978D02*
X472000Y284120D01*
G01X477702Y278978D02*
X477142D01*
G01X479653Y277027D02*
X477702Y278978D01*
G01X431497Y219122D02*
G03X431270Y218728I1244J-979D01*
G01X432340Y219672D02*
G03X431497Y219122I394J-1525D01*
G01X433986Y221064D02*
G02X432340Y219672I-2267J1011D01*
G01X434098Y221259D02*
X433986Y221064D01*
G01X434117Y222800D02*
G02X434098Y221259I-1384J-754D01*
G01X434030Y222951D02*
X434117Y222800D01*
G01X432733Y225947D02*
X434030Y222951D01*
G01X440500Y266757D02*
Y266500D01*
G01X441901Y268158D02*
X440500Y266757D01*
G01X441901Y268159D02*
Y268158D01*
G01X447692Y273950D02*
X441901Y268159D01*
G01X447779Y273950D02*
X447692D01*
G01X447828Y273999D02*
X447779Y273950D01*
G01X454809Y273999D02*
X447828D01*
G01X455467Y274657D02*
X454809Y273999D01*
G01X465856Y274657D02*
X455467D01*
G01X467849Y276650D02*
X465856Y274657D01*
G01X469501Y276650D02*
X467849D01*
G01X473051Y273100D02*
X469501Y276650D01*
G01X475700Y273100D02*
X473051D01*
G01X476950Y274350D02*
X475700Y273100D01*
G01X478299Y274350D02*
X476950D01*
G01X430718Y219309D02*
G03X430601Y219081I1790J-1062D01*
G01X430782Y219422D02*
X430718Y219309D01*
G01X432733Y222047D02*
X430782Y219422D01*
G01X444408Y268458D02*
Y267305D01*
G01X448401Y272451D02*
X444408Y268458D01*
G01X461158Y272451D02*
X448401D01*
G01X461373Y272666D02*
X461158Y272451D01*
G01X462673Y272666D02*
X461373D01*
G01X462839Y272500D02*
X462673Y272666D01*
G01X470739Y272500D02*
X462839D01*
G01X471989Y271250D02*
X470739Y272500D01*
G01X474350Y271250D02*
X471989D01*
G01X476000Y269600D02*
X474350Y271250D01*
G01X477901Y269600D02*
X476000D01*
G01X478274Y269227D02*
X477901Y269600D01*
G01X468548Y219309D02*
X468573Y219267D01*
G01X468529Y219343D02*
X468548Y219309D01*
G01Y220884D02*
G03X468529Y219343I1365J-787D01*
G01X468235Y223633D02*
G02X468548Y220884I-1702J-1586D01*
G01X466533Y225947D02*
X468235Y223633D01*
G01X447593Y218976D02*
G03X447637Y218900I1668J915D01*
G01X447618Y221259D02*
G03X447593Y218976I2015J-1164D01*
G01X446481Y223606D02*
G02X447618Y221259I-228J-1559D01*
G01X446253Y223378D02*
X446481Y223606D01*
G01X446253Y222047D02*
Y223378D01*
G01X472089Y219215D02*
X471908Y218900D01*
G01X472504Y219724D02*
X472089Y219215D01*
G01X473119Y220278D02*
X472504Y219724D01*
G01X473935Y220608D02*
X473119Y220278D01*
G01X474676Y222800D02*
G02X473935Y220608I-1384J-753D01*
G01X474589Y222951D02*
X474676Y222800D01*
G01X473292Y225947D02*
X474589Y222951D01*
G01X448268Y219309D02*
X448293Y219267D01*
G01X448249Y219343D02*
X448268Y219309D01*
G01Y220884D02*
G03X448249Y219343I1365J-787D01*
G01X448293Y223167D02*
G02X448268Y220884I-2040J-1119D01*
G01Y223209D02*
X448293Y223167D01*
G01X446510Y224359D02*
G02X448268Y223209I-257J-2312D01*
G01X446253Y224616D02*
X446510Y224359D01*
G01X446253Y225947D02*
Y224616D01*
G01X477245Y218628D02*
X476758Y218423D01*
G01X478037Y220884D02*
G02X477245Y218628I-1365J-788D01*
G01X478012Y223167D02*
G03X478037Y220884I2040J-1119D01*
G01Y223209D02*
X478012Y223167D01*
G01X478056Y223243D02*
X478037Y223209D01*
G01Y224784D02*
G02X478056Y223243I-1365J-787D01*
G01X477971Y224897D02*
X478037Y224784D01*
G01X476672Y227896D02*
X477971Y224897D01*
G01X444331Y227896D02*
X442873D01*
G01X444579Y227648D02*
X444331Y227896D01*
G01X444579Y226523D02*
Y227648D01*
G01X444106Y226050D02*
X444579Y226523D01*
G01X444238Y224784D02*
G02X444106Y226050I1355J781D01*
G01X444425Y223727D02*
G03X444238Y224784I-1552J270D01*
G01X444888Y221260D02*
G02X444425Y223727I3278J1892D01*
G01X444888Y218934D02*
G03Y221260I-2015J1163D01*
G01X436113Y220096D02*
X435947Y219920D01*
G01X468344Y290174D02*
X466066Y292452D01*
G01X468344Y289646D02*
Y290174D01*
G01X470025Y287965D02*
X468344Y289646D01*
G01X470563Y287965D02*
X470025D01*
G01X472000Y286528D02*
X470563Y287965D01*
G01X472000Y284120D02*
Y286528D01*
G01X477142Y282878D02*
X479335D01*
G01X474800Y285220D02*
X477142Y282878D01*
G01X474800Y289740D02*
Y285220D01*
G01X472700Y291840D02*
X474800Y289740D01*
G01X472700Y293628D02*
Y291840D01*
G01X469801Y296527D02*
X472700Y293628D01*
G01X469263Y296527D02*
X469801D01*
G01X468100Y297690D02*
X469263Y296527D01*
G01X468100Y298021D02*
Y297690D01*
G01X466100Y300021D02*
X468100Y298021D01*
G01X467200Y294500D02*
X464000D01*
G01X469073Y292627D02*
X467200Y294500D01*
G01X469801Y292627D02*
X469073D01*
G01X473500Y288928D02*
X469801Y292627D01*
G01X473500Y285459D02*
Y288928D01*
G01X476843Y282116D02*
X473500Y285459D01*
G01X479333Y282116D02*
X476843D01*
G01X452328Y399657D02*
X449000Y402985D01*
G01X452328Y393222D02*
Y399657D01*
G01X452118Y392859D02*
X452328Y393222D01*
G01X450812Y392072D02*
G03X452118Y392859I-59J1575D01*
G01X450753Y392072D02*
X450812D01*
G01X450036Y391658D02*
G02X450753Y392072I717J-414D01*
G01X449369Y390500D02*
X450036Y391658D01*
G01X449388Y388959D02*
G02X449369Y390500I1365J787D01*
G01X449413Y386676D02*
G03X449388Y388959I-2040J1119D01*
G01Y386634D02*
X449413Y386676D01*
G01X449369Y386600D02*
X449388Y386634D01*
G01Y385059D02*
G02X449369Y386600I1365J787D01*
G01X449454Y384946D02*
X449388Y385059D01*
G01X450753Y381947D02*
X449454Y384946D01*
G01X476463Y402294D02*
G03X476428Y404560I-2050J1102D01*
G01Y402234D02*
X476463Y402294D01*
G01X476428Y400660D02*
G02Y402234I1364J787D01*
G01X476463Y398394D02*
G03X476428Y400660I-2050J1102D01*
G01Y398334D02*
X476463Y398394D01*
G01X476428Y396760D02*
G02Y398334I1364J787D01*
G01X476463Y394494D02*
G03X476428Y396760I-2050J1102D01*
G01Y394434D02*
X476463Y394494D01*
G01X476428Y392860D02*
G02Y394434I1364J787D01*
G01X476463Y390595D02*
G03X476428Y392860I-2049J1101D01*
G01X476298Y390314D02*
G03X476463Y390595I-3642J2328D01*
G01X476295Y390309D02*
X476298Y390314D01*
G01X474413Y387796D02*
G03X476295Y390309I-11321J10439D01*
G01X458843Y402293D02*
G02X458565Y403395I2049J1103D01*
G01X458905Y402185D02*
X458843Y402293D01*
G01X458878Y400659D02*
G03X458905Y402185I-1365J787D01*
G01X458843Y398393D02*
G02X458878Y400659I2050J1102D01*
G01X458905Y398285D02*
X458843Y398393D01*
G01X458878Y396759D02*
G03X458905Y398285I-1365J787D01*
G01X458843Y394493D02*
G02X458878Y396759I2050J1102D01*
G01X458905Y394385D02*
X458843Y394493D01*
G01X458878Y392859D02*
G03X458905Y394385I-1365J787D01*
G01X458677Y392408D02*
G02X458878Y392859I2266J-740D01*
G01Y390536D02*
G02X458677Y392408I2015J1163D01*
G01X458878Y388962D02*
G03Y390536I-1365J787D01*
G01X458761Y386866D02*
G02X458878Y388962I2132J932D01*
G01Y386636D02*
G02X458761Y386866I1906J1114D01*
G01X459088Y386426D02*
X458878Y386636D01*
G01X459088Y384246D02*
Y386426D01*
G01X459438Y383896D02*
X459088Y384246D01*
G01X460893Y383896D02*
X459438D01*
G01X462933Y402274D02*
G03X462908Y404559I-2040J1120D01*
G01Y402232D02*
X462933Y402274D01*
G01X462908Y400658D02*
G02Y402232I1365J787D01*
G01Y398332D02*
G03Y400658I-2015J1163D01*
G01X462889Y396791D02*
G02X462908Y398332I1384J754D01*
G01Y396757D02*
X462889Y396791D01*
G01X462933Y396715D02*
X462908Y396757D01*
G01Y394432D02*
G03X462933Y396715I-2015J1164D01*
G01X462824Y394265D02*
G02X462908Y394432I1308J-553D01*
G01Y392859D02*
G02X462824Y394265I1377J788D01*
G01X463120Y392368D02*
G03X462908Y392859I-2227J-670D01*
G01X464273Y389747D02*
X463120Y392368D01*
G01X432497Y400638D02*
X423016Y410119D01*
G01X432497Y398693D02*
Y400638D01*
G01X435882Y392837D02*
X432497Y398693D01*
G01X437233Y392072D02*
G02X435882Y392837I0J1575D01*
G01X437303Y392072D02*
X437233D01*
G01X439248Y388584D02*
G03X437303Y392072I-2015J1163D01*
G01X440385Y386237D02*
G02X439248Y388584I228J1559D01*
G01X440613Y386465D02*
X440385Y386237D01*
G01X440613Y387796D02*
Y386465D01*
G01X455381Y401473D02*
X452018Y404836D01*
G01X455381Y394045D02*
Y401473D01*
G01X455708Y393718D02*
X455381Y394045D01*
G01X455708Y391740D02*
Y393718D01*
G01X454177Y390121D02*
G03X455708Y391740I-44J1575D01*
G01X454133Y390121D02*
X454177D01*
G01X453416Y389707D02*
G02X454133Y390121I717J-414D01*
G01X452768Y388584D02*
X453416Y389707D01*
G01X452749Y387043D02*
G02X452768Y388584I1384J754D01*
G01X452836Y386892D02*
X452749Y387043D01*
G01X454133Y383896D02*
X452836Y386892D01*
G01X453076Y399967D02*
X449748Y403295D01*
G01X453076Y393020D02*
Y399967D01*
G01X452702Y392368D02*
X453076Y393020D01*
G01X450753Y389747D02*
X452702Y392368D01*
G01X431747Y400330D02*
X422268Y409809D01*
G01X431747Y398486D02*
Y400330D01*
G01X435216Y392485D02*
X431747Y398486D01*
G01X435218Y392483D02*
X435216Y392485D01*
G01X437135Y391322D02*
G02X435218Y392483I98J2325D01*
G01X437277Y391322D02*
X437135D01*
G01X438598Y388959D02*
G03X437277Y391322I-1365J788D01*
G01X440356Y385484D02*
G02X438598Y388959I257J2312D01*
G01X440613Y385227D02*
X440356Y385484D01*
G01X440613Y383896D02*
Y385227D01*
G01X459500Y402657D02*
G02X459316Y403396I1392J739D01*
G01X459501Y402657D02*
X459500D01*
G01X459563Y402549D02*
X459501Y402657D01*
G01X459528Y400283D02*
G03X459563Y402549I-2015J1164D01*
G01X459501Y398757D02*
G02X459528Y400283I1392J739D01*
G01X459563Y398649D02*
X459501Y398757D01*
G01X459528Y396383D02*
G03X459563Y398649I-2015J1164D01*
G01X459501Y394857D02*
G02X459528Y396383I1392J739D01*
G01Y394809D02*
X459501Y394857D01*
G01X459553Y394767D02*
X459528Y394809D01*
G01Y392484D02*
G03X459553Y394767I-2015J1164D01*
G01X459392Y392178D02*
G02X459528Y392484I1462J-467D01*
G01Y390912D02*
G02X459392Y392178I1365J787D01*
G01X460893Y387796D02*
G03X459528Y390912I-14773J-4615D01*
G01X475777Y402609D02*
G03Y404183I-1364J787D01*
G01X475742Y402549D02*
X475777Y402609D01*
G01Y400283D02*
G02X475742Y402549I2015J1164D01*
G01X475777Y398709D02*
G03Y400283I-1364J787D01*
G01X475742Y398649D02*
X475777Y398709D01*
G01Y396383D02*
G02X475742Y398649I2015J1164D01*
G01X475777Y394809D02*
G03Y396383I-1364J787D01*
G01X475742Y394749D02*
X475777Y394809D01*
G01Y392483D02*
G02X475742Y394749I2015J1164D01*
G01X475777Y390910D02*
G03Y392483I-1363J787D01*
G01X475610Y390648D02*
G03X475777Y390910I-3270J2269D01*
G01X474029Y389340D02*
G03X475610Y390648I-1546J3478D01*
G01X473930Y389296D02*
X474029Y389340D01*
G01X473029Y387043D02*
G02X473930Y389296I1384J753D01*
G01X473116Y386892D02*
X473029Y387043D01*
G01X474413Y383896D02*
X473116Y386892D01*
G01X472982Y392368D02*
X471033Y389747D01*
G01X473048Y392484D02*
X472982Y392368D01*
G01X473073Y394767D02*
G02X473048Y392484I-2040J-1119D01*
G01Y394809D02*
X473073Y394767D01*
G01X473029Y394843D02*
X473048Y394809D01*
G01Y396384D02*
G03X473029Y394843I1365J-787D01*
G01X473073Y398667D02*
G02X473048Y396384I-2040J-1119D01*
G01Y398709D02*
X473073Y398667D01*
G01X473029Y398743D02*
X473048Y398709D01*
G01Y400284D02*
G03X473029Y398743I1365J-787D01*
G01X473073Y402567D02*
G02X473048Y400284I-2040J-1119D01*
G01Y402609D02*
X473073Y402567D01*
G01X473029Y402643D02*
X473048Y402609D01*
G01Y404184D02*
G03X473029Y402643I1365J-787D01*
G01X462852Y381947D02*
X464273D01*
G01X462498Y382301D02*
X462852Y381947D01*
G01X462498Y383791D02*
Y382301D01*
G01X462783Y384076D02*
X462498Y383791D01*
G01X462783Y385338D02*
Y384076D01*
G01X462717Y386097D02*
G03X462783Y385338I1556J-247D01*
G01X462277Y402642D02*
G03X462258Y404183I-1384J754D01*
G01Y402608D02*
X462277Y402642D01*
G01X462258Y400282D02*
G02Y402608I2015J1163D01*
G01X462277Y400248D02*
X462258Y400282D01*
G01Y398707D02*
G03X462277Y400248I-1365J787D01*
G01X462233Y396424D02*
G02X462258Y398707I2040J1119D01*
G01Y396382D02*
X462233Y396424D01*
G01X462258Y394808D02*
G03Y396382I-1365J787D01*
G01X462157Y394614D02*
G02X462258Y394808I1938J-886D01*
G01Y392484D02*
G02X462157Y394614I2015J1163D01*
G01X462258Y390912D02*
G03Y392484I-1362J786D01*
G01Y388586D02*
G02Y390912I2015J1163D01*
G01X462717Y386097D02*
G03X462258Y388586I-3743J597D01*
G01X435167Y400019D02*
Y405482D01*
G01X438116Y394916D02*
X435167Y400019D01*
G01X438129Y394896D02*
X438116Y394916D01*
G01X439263Y393701D02*
G02X438129Y394896I2503J3511D01*
G01X440543Y393270D02*
G02X439263Y393701I70J2325D01*
G01X440684Y393270D02*
X440543D01*
G01X441978Y390909D02*
G03X440684Y393270I-1365J787D01*
G01X441953Y390867D02*
X441978Y390909D01*
G01Y388584D02*
G02X441953Y390867I2015J1164D01*
G01X441997Y387043D02*
G03X441978Y388584I-1384J754D01*
G01Y387009D02*
X441997Y387043D01*
G01X441953Y386967D02*
X441978Y387009D01*
G01Y384684D02*
G02X441953Y386967I2015J1164D01*
G01X442044Y384568D02*
X441978Y384684D01*
G01X443993Y381947D02*
X442044Y384568D01*
G01X435915Y400229D02*
Y405792D01*
G01X438267Y396160D02*
X435915Y400229D01*
G01X439466Y394516D02*
G02X438267Y396160I5957J5604D01*
G01X440554Y394021D02*
G02X439466Y394516I59J1574D01*
G01X440683Y394021D02*
X440554D01*
G01X442628Y392858D02*
G03X440683Y394021I-2015J-1162D01*
G01X442694Y392745D02*
X442628Y392858D01*
G01X443993Y389747D02*
X442694Y392745D01*
G01X472373Y402276D02*
G02X472398Y404559I2040J1119D01*
G01Y402234D02*
X472373Y402276D01*
G01X472417Y402200D02*
X472398Y402234D01*
G01Y400659D02*
G03X472417Y402200I-1365J787D01*
G01X472373Y398376D02*
G02X472398Y400659I2040J1119D01*
G01Y398334D02*
X472373Y398376D01*
G01X472417Y398300D02*
X472398Y398334D01*
G01Y396759D02*
G03X472417Y398300I-1365J787D01*
G01X472373Y394476D02*
G02X472398Y396759I2040J1119D01*
G01Y394434D02*
X472373Y394476D01*
G01X472417Y394400D02*
X472398Y394434D01*
G01Y392859D02*
G03X472417Y394400I-1365J787D01*
G01X472003Y392407D02*
G03X472398Y392859I-981J1255D01*
G01X471768Y392255D02*
G03X472003Y392407I-735J1394D01*
G01X469954Y390896D02*
G02X471768Y392255I5140J-4970D01*
G01X469918Y390861D02*
X469954Y390896D01*
G01X469668Y388959D02*
G02X469918Y390861I1364J788D01*
G01X471546Y387337D02*
G02X469668Y388959I1394J3512D01*
G01X472398Y385059D02*
G03X471546Y387337I-1365J788D01*
G01X472332Y384946D02*
X472398Y385059D01*
G01X471033Y381947D02*
X472332Y384946D01*
G01X456129Y401783D02*
X452766Y405146D01*
G01X456129Y394355D02*
Y401783D01*
G01X456456Y394028D02*
X456129Y394355D01*
G01X456456Y391754D02*
Y394028D01*
G01X456460Y391750D02*
X456456Y391754D01*
G01X456178Y390584D02*
G03X456460Y391750I-2045J1112D01*
G01X456150Y390533D02*
X456178Y390584D01*
G01X456147Y390533D02*
X456150D01*
G01X456082Y390418D02*
X456147Y390533D01*
G01X454133Y387796D02*
X456082Y390418D01*
G01X443696Y416269D02*
X442498Y417467D01*
G01X443696Y413489D02*
Y416269D01*
G01X449000Y408185D02*
X443696Y413489D01*
G01X449000Y402985D02*
Y408185D01*
G01X476891Y417064D02*
X478104Y418277D01*
G01X476891Y411047D02*
Y417064D01*
G01X476428Y410034D02*
X476891Y411047D01*
G01X476428Y408460D02*
G02Y410034I1364J787D01*
G01X476463Y406194D02*
G03X476428Y408460I-2050J1102D01*
G01Y406134D02*
X476463Y406194D01*
G01X476428Y404560D02*
G02Y406134I1364J787D01*
G01X454966Y413838D02*
X454068Y414736D01*
G01X454966Y410611D02*
Y413838D01*
G01X458565Y407012D02*
X454966Y410611D01*
G01X458565Y403395D02*
Y407012D01*
G01X460687Y414454D02*
X461718Y415485D01*
G01X460687Y413900D02*
Y414454D01*
G01X462697Y411890D02*
X460687Y413900D01*
G01X462697Y405346D02*
Y411890D01*
G01X462908Y404559D02*
G02X462697Y405346I1365J788D01*
G01X423016Y416255D02*
X423948Y417187D01*
G01X423016Y410119D02*
Y416255D01*
G01X448948Y416285D02*
X448092Y417141D01*
G01X448948Y412359D02*
Y416285D01*
G01X452018Y409289D02*
X448948Y412359D01*
G01X452018Y404836D02*
Y409289D01*
G01X444444Y416423D02*
X445428Y417407D01*
G01X444444Y413799D02*
Y416423D01*
G01X449748Y408495D02*
X444444Y413799D01*
G01X449748Y403295D02*
Y408495D01*
G01X422268Y415968D02*
X421049Y417187D01*
G01X422268Y409809D02*
Y415968D01*
G01X455716Y413804D02*
X456618Y414706D01*
G01X455716Y410919D02*
Y413804D01*
G01X459316Y407319D02*
X455716Y410919D01*
G01X459316Y403396D02*
Y407319D01*
G01X477514Y418747D02*
Y420136D01*
G01X476141Y417374D02*
X477514Y418747D01*
G01X476141Y411218D02*
Y417374D01*
G01X475742Y410349D02*
X476141Y411218D01*
G01X475777Y408083D02*
G02X475742Y410349I2015J1164D01*
G01X475777Y406509D02*
G03Y408083I-1364J787D01*
G01X475742Y406449D02*
X475777Y406509D01*
G01Y404183D02*
G02X475742Y406449I2015J1164D01*
G01X473073Y406467D02*
G02X473048Y404184I-2040J-1119D01*
G01Y406509D02*
X473073Y406467D01*
G01X473029Y406543D02*
X473048Y406509D01*
G01Y408084D02*
G03X473029Y406543I1365J-787D01*
G01X473073Y410367D02*
G02X473048Y408084I-2040J-1119D01*
G01X473073Y418079D02*
Y410367D01*
G01X474218Y419224D02*
X473073Y418079D01*
G01X459936Y414682D02*
X459168Y415450D01*
G01X459936Y413588D02*
Y414682D01*
G01X461946Y411578D02*
X459936Y413588D01*
G01X461946Y405347D02*
Y411578D01*
G01X462258Y404183D02*
G02X461946Y405347I2015J1164D01*
G01X427382Y416403D02*
X426498Y417287D01*
G01X427382Y413267D02*
Y416403D01*
G01X435167Y405482D02*
X427382Y413267D01*
G01X428130Y416369D02*
X429048Y417287D01*
G01X428130Y413577D02*
Y416369D01*
G01X435915Y405792D02*
X428130Y413577D01*
G01X472323Y417736D02*
X471668Y418391D01*
G01X472323Y410169D02*
Y417736D01*
G01X472417Y410000D02*
X472323Y410169D01*
G01X472398Y408459D02*
G03X472417Y410000I-1365J787D01*
G01X472373Y406176D02*
G02X472398Y408459I2040J1119D01*
G01Y406134D02*
X472373Y406176D01*
G01X472417Y406100D02*
X472398Y406134D01*
G01Y404559D02*
G03X472417Y406100I-1365J787D01*
G01X449696Y416171D02*
X450666Y417141D01*
G01X449696Y412669D02*
Y416171D01*
G01X452766Y409599D02*
X449696Y412669D01*
G01X452766Y405146D02*
Y409599D01*
G01X497748Y206900D02*
X502292D01*
G01X492208Y212440D02*
X497748Y206900D01*
G01X492208Y221512D02*
Y212440D01*
G01X496480Y203900D02*
X497392D01*
G01X489188Y211192D02*
X496480Y203900D01*
G01X489188Y219081D02*
Y211192D01*
G01X483392Y199497D02*
Y197701D01*
G01X500291Y206100D02*
X501097Y205294D01*
G01X497486Y206100D02*
X500291D01*
G01X491458Y212128D02*
X497486Y206100D01*
G01X491458Y221201D02*
Y212128D01*
G01X479692Y195403D02*
Y194501D01*
G01X478595Y196500D02*
X479692Y195403D01*
G01X478595Y199934D02*
Y196500D01*
G01X495592Y203727D02*
Y202900D01*
G01X488438Y210881D02*
X495592Y203727D01*
G01X488438Y218771D02*
Y210881D01*
G01X483689Y217784D02*
G03X485447Y218934I-257J2312D01*
G01X483432Y217527D02*
X483689Y217784D01*
G01X483432Y216196D02*
Y217527D01*
G01X480392Y196301D02*
X481192D01*
G01X479392Y197301D02*
X480392Y196301D01*
G01X479392Y200200D02*
Y197301D01*
G01X478465Y205489D02*
X484992Y198962D01*
G01X478465Y208202D02*
Y205489D01*
G01X504285Y268300D02*
X504832Y268847D01*
G01X502303Y268300D02*
X504285D01*
G01X502138Y268465D02*
X502303Y268300D01*
G01X500766Y268465D02*
X502138D01*
G01X499554Y267253D02*
X500766Y268465D01*
G01X497194Y267253D02*
X499554D01*
G01X495957Y268490D02*
X497194Y267253D01*
G01X493491Y268490D02*
X495957D01*
G01X492254Y267253D02*
X493491Y268490D01*
G01X490646Y267253D02*
X492254D01*
G01X489409Y268490D02*
X490646Y267253D01*
G01X486559Y268490D02*
X489409D01*
G01X485322Y267253D02*
X486559Y268490D01*
G01X478847Y267253D02*
X485322D01*
G01X489348Y224372D02*
X492208Y221512D01*
G01X486753Y224372D02*
X489348D01*
G01X485428Y226700D02*
G03X486753Y224372I1384J-753D01*
G01X485447Y226734D02*
X485428Y226700D01*
G01X485472Y226776D02*
X485447Y226734D01*
G01Y229059D02*
G02X485472Y226776I-2015J-1164D01*
G01X483689Y230209D02*
G02X485447Y229059I-257J-2312D01*
G01X483432Y230466D02*
X483689Y230209D01*
G01X483432Y231797D02*
Y230466D01*
G01X487799Y220470D02*
X489188Y219081D01*
G01X486814Y220470D02*
X487799D01*
G01X486812Y220472D02*
X486814Y220470D01*
G01X486742Y220472D02*
X486812D01*
G01X484797Y219309D02*
G02X486742Y220472I2015J-1162D01*
G01X484616Y219057D02*
G03X484797Y219309I-1199J1052D01*
G01X483660Y218537D02*
G03X484616Y219057I-228J1559D01*
G01X483432Y218765D02*
X483660Y218537D01*
G01X483432Y220096D02*
Y218765D01*
G01X490772Y259473D02*
X492743Y257502D01*
G01X486809Y259473D02*
X490772D01*
G01X485447Y260259D02*
G03X486809Y259473I1362J787D01*
G01X483517Y261421D02*
G02X485447Y260259I-85J-2325D01*
G01X483388Y261421D02*
X483517D01*
G01X482067Y262209D02*
G03X483388Y261421I1365J787D01*
G01X480122Y263372D02*
G02X482067Y262209I-70J-2325D01*
G01X479993Y263372D02*
X480122D01*
G01X478687Y264159D02*
G03X479993Y263372I1365J788D01*
G01X480096Y262622D02*
X479967D01*
G01X481417Y261834D02*
G03X480096Y262622I-1365J-787D01*
G01X483362Y260671D02*
G02X481417Y261834I70J2325D01*
G01X483491Y260671D02*
X483362D01*
G01X484797Y259884D02*
G03X483491Y260671I-1365J-788D01*
G01X486814Y258719D02*
G02X484797Y259884I0J2328D01*
G01X487461Y258719D02*
X486814D01*
G01X488382Y257798D02*
X487461Y258719D01*
G01X489037Y223622D02*
X491458Y221201D01*
G01X486727Y223622D02*
X489037D01*
G01X484501Y225679D02*
G03X486727Y223622I2311J268D01*
G01X483432Y227896D02*
X484501Y225679D01*
G01X481100Y273000D02*
X479278Y271178D01*
G01X482200Y273000D02*
X481100D01*
G01X483516Y274316D02*
X482200Y273000D01*
G01X485884Y274316D02*
X483516D01*
G01X487073Y273127D02*
X485884Y274316D01*
G01X489228Y273127D02*
X487073D01*
G01X490417Y274316D02*
X489228Y273127D01*
G01X492084Y274316D02*
X490417D01*
G01X494010Y272390D02*
X492084Y274316D01*
G01X495353Y272390D02*
X494010D01*
G01X496590Y271153D02*
X495353Y272390D01*
G01X499554Y271153D02*
X496590D01*
G01X500797Y272396D02*
X499554Y271153D01*
G01X502216Y272396D02*
X500797D01*
G01X504516Y274696D02*
X502216Y272396D01*
G01X508212Y274696D02*
X504516D01*
G01X481822Y277027D02*
X479653D01*
G01X483010Y278215D02*
X481822Y277027D01*
G01X486094Y278215D02*
X483010D01*
G01X487282Y277027D02*
X486094Y278215D01*
G01X488582Y277027D02*
X487282D01*
G01X489798Y278243D02*
X488582Y277027D01*
G01X490336Y278243D02*
X489798D01*
G01X490351Y278228D02*
X490336Y278243D01*
G01X492841Y278228D02*
X490351D01*
G01X494042Y277027D02*
X492841Y278228D01*
G01X496126Y277027D02*
X494042D01*
G01X497499Y278400D02*
X496126Y277027D01*
G01X498800Y278400D02*
X497499D01*
G01X500173Y277027D02*
X498800Y278400D01*
G01X502427Y277027D02*
X500173D01*
G01X503700Y278300D02*
X502427Y277027D01*
G01X505399Y278300D02*
X503700D01*
G01X507434Y276265D02*
X505399Y278300D01*
G01X508862Y276265D02*
X507434D01*
G01X510431Y274696D02*
X508862Y276265D01*
G01X514972Y274696D02*
X510431D01*
G01X480214Y276265D02*
X478299Y274350D01*
G01X481952Y276265D02*
X480214D01*
G01X483140Y275077D02*
X481952Y276265D01*
G01X485202Y275077D02*
X483140D01*
G01X486390Y276265D02*
X485202Y275077D01*
G01X489435Y276265D02*
X486390D01*
G01X490623Y275077D02*
X489435Y276265D01*
G01X491962Y275077D02*
X490623D01*
G01X493150Y276265D02*
X491962Y275077D01*
G01X495342Y276265D02*
X493150D01*
G01X496530Y275077D02*
X495342Y276265D01*
G01X498852Y275077D02*
X496530D01*
G01X500040Y276265D02*
X498852Y275077D01*
G01X504450Y276265D02*
X500040D01*
G01X504832Y276647D02*
X504450Y276265D01*
G01X501452Y279386D02*
Y278596D01*
G01X498722Y282116D02*
X501452Y279386D01*
G01X481822Y269227D02*
X478274D01*
G01X483773Y271178D02*
X481822Y269227D01*
G01X485202Y271178D02*
X483773D01*
G01X486389Y272365D02*
X485202Y271178D01*
G01X490930Y272365D02*
X486389D01*
G01X491312Y272747D02*
X490930Y272365D01*
G01X487487Y219722D02*
X488438Y218771D01*
G01X486768Y219722D02*
X487487D01*
G01X485447Y218934D02*
G02X486768Y219722I1365J-787D01*
G01X483902Y278978D02*
X481953Y280927D01*
G01X485202Y278978D02*
X483902D01*
G01X486389Y280165D02*
X485202Y278978D01*
G01X490662D02*
X489475Y280165D01*
G01X492855Y278978D02*
X490662D01*
G01X494042Y280165D02*
X492855Y278978D01*
G01X497422Y282116D02*
X498722D01*
G01X496233Y280927D02*
X497422Y282116D01*
G01X493151Y280927D02*
X496233D01*
G01X491962Y282116D02*
X493151Y280927D01*
G01X489771Y282116D02*
X491962D01*
G01X488582Y280927D02*
X489771Y282116D01*
G01X486391Y280927D02*
X488582D01*
G01X485202Y282116D02*
X486391Y280927D01*
G01X483771Y282116D02*
X485202D01*
G01X481822Y284065D02*
X483771Y282116D01*
G01X480522Y284065D02*
X481822D01*
G01X479335Y282878D02*
X480522Y284065D01*
G01Y280927D02*
X479333Y282116D01*
G01X481953Y280927D02*
X480522D01*
G01X489475Y280165D02*
X486389D01*
G01X497690D02*
X494042D01*
G01X498072Y280547D02*
X497690Y280165D01*
G01X479897Y402783D02*
X479379Y403301D01*
G01X479897Y398042D02*
Y402783D01*
G01X479157Y396759D02*
X479897Y398042D01*
G01X479132Y394476D02*
G02X479157Y396759I2040J1119D01*
G01Y394434D02*
X479132Y394476D01*
G01X479176Y394400D02*
X479157Y394434D01*
G01Y392859D02*
G03X479176Y394400I-1365J787D01*
G01X479132Y390576D02*
G02X479157Y392859I2040J1119D01*
G01Y390534D02*
X479132Y390576D01*
G01X479176Y390500D02*
X479157Y390534D01*
G01Y388959D02*
G03X479176Y390500I-1365J787D01*
G01X480915Y385484D02*
G02X479157Y388959I257J2312D01*
G01X481172Y385227D02*
X480915Y385484D01*
G01X481172Y383896D02*
Y385227D01*
G01X496179Y402149D02*
X498628Y404598D01*
G01X496179Y400983D02*
Y402149D01*
G01X494692Y399496D02*
X496179Y400983D01*
G01X493329Y401788D02*
Y403339D01*
G01X492677Y400659D02*
X493329Y401788D01*
G01X492677Y398333D02*
G02Y400659I2015J1163D01*
G01Y396759D02*
G03Y398333I-1365J787D01*
G01X492168Y395801D02*
X492677Y396759D01*
G01X491312Y393647D02*
X492168Y395801D01*
G01X492579Y402714D02*
Y403651D01*
G01X491312Y401447D02*
X492579Y402714D01*
G01X495652Y402684D02*
X498316Y405348D01*
G01X495648Y402684D02*
X495652D01*
G01X495648Y402683D02*
Y402684D01*
G01X493469Y400504D02*
X495648Y402683D01*
G01X493327Y400284D02*
X493469Y400504D01*
G01X493308Y398743D02*
G02X493327Y400284I1384J754D01*
G01X493888Y397705D02*
X493308Y398743D01*
G01X494692Y396901D02*
X493888Y397705D01*
G01X494692Y395597D02*
Y396901D01*
G01X483253Y392746D02*
X484552Y389747D01*
G01X483187Y392859D02*
X483253Y392746D01*
G01X483168Y394400D02*
G03X483187Y392859I1384J-754D01*
G01X483497Y394972D02*
X483168Y394400D01*
G01X483497Y404175D02*
Y394972D01*
G01X480647Y397840D02*
Y403094D01*
G01X479807Y396384D02*
X480647Y397840D01*
G01X479788Y394843D02*
G02X479807Y396384I1384J754D01*
G01Y394809D02*
X479788Y394843D01*
G01X479832Y394767D02*
X479807Y394809D01*
G01Y392484D02*
G03X479832Y394767I-2015J1164D01*
G01X479788Y390943D02*
G02X479807Y392484I1384J754D01*
G01Y390909D02*
X479788Y390943D01*
G01X479832Y390867D02*
X479807Y390909D01*
G01Y388584D02*
G03X479832Y390867I-2015J1164D01*
G01X480944Y386237D02*
G02X479807Y388584I228J1559D01*
G01X481172Y386465D02*
X480944Y386237D01*
G01X481172Y387796D02*
Y386465D01*
G01X482747Y395173D02*
Y403864D01*
G01X482512Y394767D02*
X482747Y395173D01*
G01X482537Y392484D02*
G02X482512Y394767I2015J1164D01*
G01X482556Y390943D02*
G03X482537Y392484I-1384J754D01*
G01Y390909D02*
X482556Y390943D01*
G01X482512Y390867D02*
X482537Y390909D01*
G01Y388584D02*
G02X482512Y390867I2015J1164D01*
G01X482556Y387043D02*
G03X482537Y388584I-1384J754D01*
G01Y387009D02*
X482556Y387043D01*
G01X482512Y386967D02*
X482537Y387009D01*
G01Y384684D02*
G02X482512Y386967I2015J1164D01*
G01X482603Y384568D02*
X482537Y384684D01*
G01X484552Y381947D02*
X482603Y384568D01*
G01X478104Y418277D02*
X479092D01*
G01X491992Y422611D02*
Y423500D01*
G01X479379Y409998D02*
X491992Y422611D01*
G01X479379Y403301D02*
Y409998D01*
G01X521642Y410350D02*
X522492Y409500D01*
G01X517096Y410350D02*
X521642D01*
G01X511344Y404598D02*
X517096Y410350D01*
G01X498628Y404598D02*
X511344D01*
G01X522192Y414650D02*
X522742Y414100D01*
G01X517192Y414650D02*
X522192D01*
G01X509992Y407450D02*
X517192Y414650D01*
G01X497440Y407450D02*
X509992D01*
G01X493329Y403339D02*
X497440Y407450D01*
G01X522192Y415400D02*
X522792Y416000D01*
G01X516880Y415400D02*
X522192D01*
G01X509680Y408200D02*
X516880Y415400D01*
G01X497128Y408200D02*
X509680D01*
G01X492579Y403651D02*
X497128Y408200D01*
G01X521591Y411100D02*
X522491Y412000D01*
G01X516784Y411100D02*
X521591D01*
G01X511032Y405348D02*
X516784Y411100D01*
G01X498316Y405348D02*
X511032D01*
G01X482977Y404695D02*
X483497Y404175D01*
G01X482977Y406273D02*
Y404695D01*
G01X496254Y419550D02*
X482977Y406273D01*
G01X497454Y419550D02*
X496254D01*
G01X492392Y421950D02*
X493692D01*
G01X480129Y409687D02*
X492392Y421950D01*
G01X480129Y403612D02*
Y409687D01*
G01X480647Y403094D02*
X480129Y403612D01*
G01X495792Y420149D02*
Y421150D01*
G01X482229Y406586D02*
X495792Y420149D01*
G01X482229Y404382D02*
Y406586D01*
G01X482747Y403864D02*
X482229Y404382D01*
G01X908000Y260363D02*
X910386D01*
G01X907500Y240159D02*
X914570D01*
G01X910138Y262863D02*
X907500D01*
G01X910486Y257863D02*
X908000D01*
G01X909817Y225302D02*
X913106Y228591D01*
G01X909789Y247659D02*
X911288Y246160D01*
G01X908000Y247659D02*
X909789D01*
G01X910184Y265363D02*
X907500D01*
G01X909289Y242659D02*
X908000D01*
G01X909688Y242260D02*
X909289Y242659D01*
G01X913700Y242260D02*
X909688D01*
G01X909590Y245159D02*
X908000D01*
G01X910493Y244256D02*
X909590Y245159D01*
G01X911255Y332336D02*
X908841D01*
G01X912311Y337336D02*
X908914D01*
G01X911664Y334836D02*
X908899D01*
G01X914557Y330247D02*
X908732D01*
G01X913787Y347560D02*
X908942D01*
G01X907292Y382405D02*
X906008D01*
G01X907849Y381848D02*
X907292Y382405D01*
G01X907849Y379648D02*
Y381848D01*
G01X912556Y374941D02*
X907849Y379648D01*
G01X906356Y391599D02*
Y392878D01*
G01X912404Y385551D02*
X906356Y391599D01*
G01X912509Y354000D02*
X909088D01*
G01X907161Y404194D02*
X911026Y400329D01*
G01X914621Y349616D02*
X908942D01*
G01X907712Y383043D02*
Y384308D01*
G01X908597Y382158D02*
X907712Y383043D01*
G01X908597Y379958D02*
Y382158D01*
G01X912866Y375689D02*
X908597Y379958D01*
G01X905856Y391041D02*
X904586D01*
G01X911656Y385241D02*
X905856Y391041D01*
G01X913787Y351460D02*
X909030D01*
G01X910716Y399581D02*
X906788Y403509D01*
G01X909465Y406716D02*
X909416Y406667D01*
G01X910661Y406716D02*
X909465D01*
G01X907161Y405313D02*
Y404194D01*
G01X906788Y403509D02*
X905358D01*
G01X915912Y210841D02*
X923555Y218484D01*
G01X915355Y210841D02*
X915912D01*
G01X914344Y209830D02*
X915355Y210841D01*
G01X944755Y189941D02*
X943449D01*
G01X945506Y190692D02*
X944755Y189941D01*
G01X945506Y193746D02*
Y190692D01*
G01X949445Y197685D02*
X945506Y193746D01*
G01X950295Y197685D02*
X949445D01*
G01X959078Y206468D02*
X950295Y197685D01*
G01X959078Y211056D02*
Y206468D01*
G01X959366Y212179D02*
G03X959078Y211056I2047J-1123D01*
G01X959391Y212221D02*
X959366Y212179D01*
G01X959391Y213795D02*
G02Y212221I-1365J-787D01*
G01X958724Y214947D02*
X959391Y213795D01*
G01X958200Y216420D02*
X958724Y214947D01*
G01X958026Y216909D02*
X958200Y216420D01*
G01X915602Y211589D02*
X923247Y219234D01*
G01X915007Y211589D02*
X915602D01*
G01X914216Y212380D02*
X915007Y211589D01*
G01X918364Y207596D02*
X917056Y205756D01*
G01X918700Y208117D02*
X918364Y207596D01*
G01X918832Y208322D02*
X918700Y208117D01*
G01X920796Y209485D02*
G03X918832Y208322I51J-2326D01*
G01X920906Y209485D02*
X920796D01*
G01X922212Y210272D02*
G02X920906Y209485I-1365J788D01*
G01X924142Y211434D02*
G03X922212Y210272I85J-2325D01*
G01X924271Y211434D02*
X924142D01*
G01X925592Y213797D02*
G02X924271Y211434I-1365J-788D01*
G01X927537Y217285D02*
G03X925592Y213797I70J-2325D01*
G01X927666Y217285D02*
X927537D01*
G01X928844Y217884D02*
G02X927666Y217285I-1238J976D01*
G01X959608Y214947D02*
Y220549D01*
G01X960041Y214171D02*
X959608Y214947D01*
G01X960066Y211888D02*
G03X960041Y214171I-2040J1119D01*
G01Y211846D02*
X960066Y211888D01*
G01X959830Y211060D02*
G02X960041Y211846I1576J-2D01*
G01X959828Y209161D02*
X959830Y211060D01*
G01X959828Y206157D02*
Y209161D01*
G01X958200Y204529D02*
X959828Y206157D01*
G01X950606Y196935D02*
X958200Y204529D01*
G01X949756Y196935D02*
X950606D01*
G01X946256Y193435D02*
X949756Y196935D01*
G01X946256Y190241D02*
Y193435D01*
G01X945356Y189341D02*
X946256Y190241D01*
G01X945356Y188241D02*
Y189341D01*
G01X962746Y215789D02*
G02X962771Y218072I2040J1119D01*
G01Y215747D02*
X962746Y215789D01*
G01X962790Y215713D02*
X962771Y215747D01*
G01Y214172D02*
G03X962790Y215713I-1365J787D01*
G01X962746Y211889D02*
G02X962771Y214172I2040J1119D01*
G01Y211847D02*
X962746Y211889D01*
G01X962790Y211813D02*
X962771Y211847D01*
G01Y210272D02*
G03X962790Y211813I-1365J787D01*
G01X962187Y209259D02*
X962771Y210272D01*
G01X962187Y207172D02*
Y209259D01*
G01X960916Y205901D02*
X962187Y207172D01*
G01X960916Y203841D02*
Y205901D01*
G01X961356Y203401D02*
X960916Y203841D01*
G01X961356Y202382D02*
Y203401D01*
G01X954676Y195702D02*
X961356Y202382D01*
G01X954676Y194461D02*
Y195702D01*
G01X953826Y193611D02*
X954676Y194461D01*
G01X942558Y214288D02*
X944507Y216909D01*
G01X942492Y214172D02*
X942558Y214288D01*
G01X941186Y213385D02*
G03X942492Y214172I-59J1575D01*
G01X941057Y213385D02*
X941186D01*
G01X939112Y212222D02*
G02X941057Y213385I2015J-1162D01*
G01X937791Y211434D02*
G03X939112Y212222I-44J1575D01*
G01X937662Y211434D02*
X937791D01*
G01X935732Y210272D02*
G02X937662Y211434I2015J-1163D01*
G01X934426Y209485D02*
G03X935732Y210272I-59J1575D01*
G01X934316Y209485D02*
X934426D01*
G01X932352Y208322D02*
G02X934316Y209485I2015J-1163D01*
G01X931058Y207535D02*
G03X932352Y208322I-71J1574D01*
G01X930917Y207535D02*
X931058D01*
G01X928972Y206372D02*
G02X930917Y207535I2015J-1162D01*
G01X927678Y205585D02*
G03X928972Y206372I-71J1574D01*
G01X927522Y205585D02*
X927678D01*
G01X925592Y204423D02*
G02X927522Y205585I2015J-1163D01*
G01X924271Y203635D02*
G03X925592Y204423I-44J1575D01*
G01X924176Y203635D02*
X924271D01*
G01X922212Y202472D02*
G02X924176Y203635I2015J-1163D01*
G01X921226Y200871D02*
X922212Y202472D01*
G01X921049Y200697D02*
X921226Y200871D01*
G01X920331Y199979D02*
X921049Y200697D01*
G01X946767Y217752D02*
G02X946503Y219613I1120J1108D01*
G01X948574Y216378D02*
G02X946767Y217752I2504J5168D01*
G01X949252Y214172D02*
G03X948574Y216378I-1365J788D01*
G01X948056Y213041D02*
G03X949252Y214172I-1299J2571D01*
G01X946928Y212309D02*
G02X948056Y213041I5343J-6998D01*
G01X946522Y211847D02*
G02X946928Y212309I1355J-781D01*
G01X944577Y210684D02*
G03X946522Y211847I-70J2325D01*
G01X944448Y210684D02*
X944577D01*
G01X943142Y209897D02*
G02X944448Y210684I1365J-788D01*
G01X941178Y208734D02*
G03X943142Y209897I-51J2326D01*
G01X941083Y208734D02*
X941178D01*
G01X939762Y207946D02*
G02X941083Y208734I1365J-787D01*
G01X937832Y206784D02*
G03X939762Y207946I-85J2325D01*
G01X937676Y206784D02*
X937832D01*
G01X936382Y205997D02*
G02X937676Y206784I1365J-787D01*
G01X934437Y204834D02*
G03X936382Y205997I-70J2325D01*
G01X934296Y204834D02*
X934437D01*
G01X933002Y204047D02*
G02X934296Y204834I1365J-787D01*
G01X931038Y202884D02*
G03X933002Y204047I-51J2326D01*
G01X930928Y202884D02*
X931038D01*
G01X929622Y202097D02*
G02X930928Y202884I1365J-788D01*
G01X929232Y201346D02*
X929622Y202097D01*
G01X929232Y198059D02*
Y201346D01*
G01X927974Y196801D02*
X929232Y198059D01*
G01X945806Y217810D02*
X944507Y220809D01*
G01X945872Y217697D02*
X945806Y217810D01*
G01X945891Y216156D02*
G03X945872Y217697I-1384J754D01*
G01Y216122D02*
X945891Y216156D01*
G01X945224Y214998D02*
X945872Y216122D01*
G01X944507Y214584D02*
G03X945224Y214998I0J828D01*
G01X944448Y214584D02*
X944507D01*
G01X943142Y213797D02*
G02X944448Y214584I1365J-788D01*
G01X941212Y212635D02*
G03X943142Y213797I-85J2325D01*
G01X941083Y212635D02*
X941212D01*
G01X939762Y211847D02*
G02X941083Y212635I1365J-787D01*
G01X937817Y210684D02*
G03X939762Y211847I-70J2325D01*
G01X937688Y210684D02*
X937817D01*
G01X936382Y209897D02*
G02X937688Y210684I1365J-788D01*
G01X934418Y208734D02*
G03X936382Y209897I-51J2326D01*
G01X934323Y208734D02*
X934418D01*
G01X933002Y207946D02*
G02X934323Y208734I1365J-787D01*
G01X931072Y206784D02*
G03X933002Y207946I-85J2325D01*
G01X930916Y206784D02*
X931072D01*
G01X929622Y205997D02*
G02X930916Y206784I1365J-787D01*
G01X927677Y204834D02*
G03X929622Y205997I-70J2325D01*
G01X927536Y204834D02*
X927677D01*
G01X926242Y204047D02*
G02X927536Y204834I1365J-787D01*
G01X924278Y202884D02*
G03X926242Y204047I-51J2326D01*
G01X924168Y202884D02*
X924278D01*
G01X922862Y202097D02*
G02X924168Y202884I1365J-788D01*
G01X922436Y201351D02*
X922862Y202097D01*
G01X922436Y198477D02*
Y201351D01*
G01X921363Y197404D02*
X922436Y198477D01*
G01X966151Y217698D02*
G02Y220022I2015J1162D01*
G01X966481Y217073D02*
X966151Y217698D01*
G01X966481Y207626D02*
Y217073D01*
G01X966946Y207161D02*
X966481Y207626D01*
G01X966946Y203651D02*
Y207161D01*
G01X959786Y196491D02*
X966946Y203651D01*
G01X959786Y194851D02*
Y196491D01*
G01X959200Y194265D02*
X959786Y194851D01*
G01X919011Y204104D02*
X918220Y203313D01*
G01X919011Y207040D02*
Y204104D01*
G01X919300Y207596D02*
X919011Y207040D01*
G01X919482Y207946D02*
X919300Y207596D01*
G01X920803Y208734D02*
G03X919482Y207946I44J-1575D01*
G01X920898Y208734D02*
X920803D01*
G01X922862Y209897D02*
G02X920898Y208734I-2015J1163D01*
G01X924168Y210684D02*
G03X922862Y209897I59J-1575D01*
G01X924297Y210684D02*
X924168D01*
G01X926242Y214172D02*
G02X924297Y210684I-2015J-1163D01*
G01X927563Y216535D02*
G03X926242Y214172I44J-1575D01*
G01X927692Y216535D02*
X927563D01*
G01X929481Y217480D02*
G02X927692Y216535I-1873J1380D01*
G01X929833Y217575D02*
X929481Y217480D01*
G01X930987Y216909D02*
X929833Y217575D01*
G01X963421Y217697D02*
G03X963446Y219980I-2015J1164D01*
G01X963402Y216156D02*
G02X963421Y217697I1384J754D01*
G01Y216122D02*
X963402Y216156D01*
G01X963446Y216080D02*
X963421Y216122D01*
G01Y213797D02*
G03X963446Y216080I-2015J1164D01*
G01X963402Y212256D02*
G02X963421Y213797I1384J754D01*
G01Y212222D02*
X963402Y212256D01*
G01X963446Y212180D02*
X963421Y212222D01*
G01Y209897D02*
G03X963446Y212180I-2015J1164D01*
G01X962937Y209058D02*
X963421Y209897D01*
G01X962937Y207350D02*
Y209058D01*
G01X964106Y206181D02*
X962937Y207350D01*
G01X964106Y204062D02*
Y206181D01*
G01X955432Y195388D02*
X964106Y204062D01*
G01X955432Y194455D02*
Y195388D01*
G01X956376Y193511D02*
X955432Y194455D01*
G01X956661Y216123D02*
G02X956198Y218590I3278J1892D01*
G01X956661Y213797D02*
G03Y216123I-2015J1163D01*
G01Y212223D02*
G02Y213797I1365J787D01*
G01X956973Y211060D02*
G03X956661Y212223I-2327J-1D01*
G01X956973Y207581D02*
Y211060D01*
G01X956974Y207580D02*
X956973Y207581D01*
G01X950329Y200935D02*
X956974Y207580D01*
G01X947843Y200935D02*
X950329D01*
G01X946522Y200147D02*
G02X947843Y200935I1365J-787D01*
G01X944577Y198984D02*
G03X946522Y200147I-70J2325D01*
G01X944448Y198984D02*
X944577D01*
G01X943142Y198197D02*
G02X944448Y198984I1365J-788D01*
G01X942406Y196921D02*
X943142Y198197D01*
G01X942406Y193991D02*
Y196921D01*
G01X942156Y193741D02*
X942406Y193991D01*
G01X942156Y192255D02*
Y193741D01*
G01X941899Y191998D02*
X942156Y192255D01*
G01X940334Y194041D02*
X940145Y193852D01*
G01X941356Y194041D02*
X940334D01*
G01X941656Y194341D02*
X941356Y194041D01*
G01X941656Y197123D02*
Y194341D01*
G01X942492Y198572D02*
X941656Y197123D01*
G01X944422Y199734D02*
G03X942492Y198572I85J-2325D01*
G01X944551Y199734D02*
X944422D01*
G01X945872Y200522D02*
G02X944551Y199734I-1365J787D01*
G01X947817Y201685D02*
G03X945872Y200522I70J-2325D01*
G01X950018Y201685D02*
X947817D01*
G01X956224Y207891D02*
X950018Y201685D01*
G01X956224Y209151D02*
Y207891D01*
G01X956223Y209152D02*
X956224Y209151D01*
G01X956222Y211060D02*
X956223Y209152D01*
G01X956011Y211847D02*
G02X956222Y211060I-1365J-788D01*
G01X955849Y212188D02*
G03X956011Y211847I2176J825D01*
G01X954647Y214960D02*
X955849Y212188D01*
G01X967231Y217383D02*
X966801Y218073D01*
G01X967231Y207937D02*
Y217383D01*
G01X967694Y207474D02*
X967231Y207937D01*
G01X967694Y203341D02*
Y207474D01*
G01X960534Y196181D02*
X967694Y203341D01*
G01X960534Y194933D02*
Y196181D01*
G01X961476Y193991D02*
X960534Y194933D01*
G01X925060Y197494D02*
X924669Y197103D01*
G01X925060Y199116D02*
Y197494D01*
G01X925521Y199919D02*
X925060Y199116D01*
G01X928028Y201741D02*
G03X925521Y199919I1181J-4261D01*
G01X928972Y202472D02*
G02X928028Y201741I-1365J788D01*
G01X930936Y203635D02*
G03X928972Y202472I51J-2326D01*
G01X931031Y203635D02*
X930936D01*
G01X932352Y204423D02*
G02X931031Y203635I-1365J787D01*
G01X934282Y205585D02*
G03X932352Y204423I85J-2325D01*
G01X934438Y205585D02*
X934282D01*
G01X935732Y206372D02*
G02X934438Y205585I-1365J787D01*
G01X937677Y207535D02*
G03X935732Y206372I70J-2325D01*
G01X937818Y207535D02*
X937677D01*
G01X939112Y208322D02*
G02X937818Y207535I-1365J787D01*
G01X941076Y209485D02*
G03X939112Y208322I51J-2326D01*
G01X941186Y209485D02*
X941076D01*
G01X942492Y210272D02*
G02X941186Y209485I-1365J788D01*
G01X944422Y211434D02*
G03X942492Y210272I85J-2325D01*
G01X944551Y211434D02*
X944422D01*
G01X945872Y212222D02*
G02X944551Y211434I-1365J787D01*
G01X945938Y212338D02*
X945872Y212222D01*
G01X947887Y214960D02*
X945938Y212338D01*
G01X930621Y218860D02*
X934367D01*
G01X929161Y219948D02*
X930621Y218860D01*
G01X927692Y220435D02*
G02X929161Y219948I0J-2459D01*
G01X927563Y220435D02*
X927692D01*
G01X926242Y219647D02*
G02X927563Y220435I1365J-787D01*
G01X924297Y218484D02*
G03X926242Y219647I-70J2325D01*
G01X923555Y218484D02*
X924297D01*
G01X912889Y257860D02*
X913787D01*
G01X910386Y260363D02*
X912889Y257860D01*
G01X928761Y222094D02*
X927607Y222760D01*
G01X928844Y221784D02*
X928761Y222094D01*
G01X927666Y221185D02*
G03X928844Y221784I-60J1575D01*
G01X927537Y221185D02*
X927666D01*
G01X925592Y220022D02*
G02X927537Y221185I2015J-1162D01*
G01X924271Y219234D02*
G03X925592Y220022I-44J1575D01*
G01X923247Y219234D02*
X924271D01*
G01X916671Y242260D02*
X920847D01*
G01X914570Y240159D02*
X916671Y242260D01*
G01X934511Y228985D02*
X937747Y228610D01*
G01X934296Y228985D02*
X934511D01*
G01X933002Y229772D02*
G03X934296Y228985I1365J787D01*
G01X932817Y230093D02*
X933002Y229772D01*
G01X932547Y232733D02*
X932817Y230093D01*
G01X932352Y233297D02*
G02X932547Y232733I-1365J-788D01*
G01X931046Y234084D02*
G02X932352Y233297I-59J-1575D01*
G01X930917Y234084D02*
X931046D01*
G01X928972Y235247D02*
G03X930917Y234084I2015J1162D01*
G01X927651Y236035D02*
G02X928972Y235247I-44J-1575D01*
G01X926242D02*
G02X927651Y236035I1365J-787D01*
G01X924297Y234084D02*
G03X926242Y235247I-70J2325D01*
G01X918399Y234084D02*
X924297D01*
G01X916103Y231788D02*
X918399Y234084D01*
G01X912202Y231788D02*
X916103D01*
G01X910816Y230402D02*
X912202Y231788D01*
G01X910506Y230402D02*
X910816D01*
G01X929037Y231232D02*
X930987Y228610D01*
G01X928972Y231346D02*
X929037Y231232D01*
G01X926242Y231346D02*
G02X928972I1365J-787D01*
G01X925737Y230841D02*
X926242Y231346D01*
G01X924885Y230841D02*
X925737D01*
G01X924297Y230935D02*
G02X924885Y230841I-70J-2326D01*
G01X923657Y230935D02*
X924297D01*
G01X923656Y230934D02*
X923657Y230935D01*
G01X918691Y230934D02*
X923656D01*
G01X917098Y229341D02*
X918691Y230934D01*
G01X912782Y229341D02*
X917098D01*
G01X911293Y227852D02*
X912782Y229341D01*
G01X910448Y227852D02*
X911293D01*
G01X913145Y259856D02*
X910138Y262863D01*
G01X914867Y259856D02*
X913145D01*
G01X916771Y261760D02*
X914867Y259856D01*
G01X920847Y261760D02*
X916771D01*
G01X912386Y255963D02*
X910486Y257863D01*
G01X914799Y255963D02*
X912386D01*
G01X916696Y257860D02*
X914799Y255963D01*
G01X920847Y257860D02*
X916696D01*
G01X928761Y218194D02*
X928844Y217884D01*
G01X927607Y218860D02*
X928761Y218194D01*
G01X911044Y232952D02*
X910653D01*
G01X911458Y232538D02*
X911044Y232952D01*
G01X915795Y232538D02*
X911458D01*
G01X918091Y234834D02*
X915795Y232538D01*
G01X924271Y234834D02*
X918091D01*
G01X925592Y235622D02*
G02X924271Y234834I-1365J787D01*
G01X927537Y236785D02*
G03X925592Y235622I70J-2325D01*
G01X927677Y236785D02*
X927537D01*
G01X929622Y235622D02*
G03X927677Y236785I-2015J-1162D01*
G01X930943Y234834D02*
G02X929622Y235622I44J1575D01*
G01X931072Y234834D02*
X930943D01*
G01X933002Y233672D02*
G03X931072Y234834I-2015J-1163D01*
G01X933142Y233385D02*
G03X933002Y233672I-2156J-874D01*
G01X934367Y230559D02*
X933142Y233385D01*
G01X935797Y227334D02*
X937747Y224709D01*
G01X935732Y227447D02*
X935797Y227334D01*
G01X934438Y228234D02*
G02X935732Y227447I-71J-1574D01*
G01X934296Y228234D02*
X934438D01*
G01X933554Y228010D02*
G02X934296Y228234I812J-1350D01*
G01X932599Y227436D02*
X933554Y228010D01*
G01X931038Y227035D02*
G03X932599Y227436I108J2818D01*
G01X930943Y227035D02*
X931038D01*
G01X929622Y227823D02*
G03X930943Y227035I1365J787D01*
G01X927692Y228985D02*
G02X929622Y227823I-85J-2325D01*
G01X926004Y228985D02*
X927692D01*
G01X925592Y229397D02*
X926004Y228985D01*
G01X924298Y230184D02*
G02X925592Y229397I-71J-1574D01*
G01X918999Y230184D02*
X924298D01*
G01X917406Y228591D02*
X918999Y230184D01*
G01X913106Y228591D02*
X917406D01*
G01X959348Y220809D02*
X958026D01*
G01X959608Y220549D02*
X959348Y220809D01*
G01X969781Y237925D02*
X971546Y240309D01*
G01X969531Y237572D02*
G02X969781Y237925I2015J-1162D01*
G01X968225Y236785D02*
G03X969531Y237572I-59J1575D01*
G01X968096Y236785D02*
X968225D01*
G01X966151Y235622D02*
G02X968096Y236785I2015J-1162D01*
G01X964830Y234834D02*
G03X966151Y235622I-44J1575D01*
G01X964701Y234834D02*
X964830D01*
G01X962771Y231346D02*
G02X964701Y234834I2015J1163D01*
G01X962771Y229772D02*
G03Y231346I-1365J787D01*
G01X962746Y229730D02*
X962771Y229772D01*
G01Y227447D02*
G02X962746Y229730I2015J1164D01*
G01X962790Y227413D02*
X962771Y227447D01*
G01Y225872D02*
G03X962790Y227413I-1365J787D01*
G01X962746Y223589D02*
G02X962771Y225872I2040J1119D01*
G01Y223547D02*
X962746Y223589D01*
G01X962790Y223513D02*
X962771Y223547D01*
G01Y221972D02*
G03X962790Y223513I-1365J787D01*
G01X962746Y219689D02*
G02X962771Y221972I2040J1119D01*
G01Y219647D02*
X962746Y219689D01*
G01X962790Y219613D02*
X962771Y219647D01*
G01Y218072D02*
G03X962790Y219613I-1365J787D01*
G01X946590Y219764D02*
X947887Y222760D01*
G01X946503Y219613D02*
X946590Y219764D01*
G01X911288Y246160D02*
X913787D01*
G01Y261760D02*
X910184Y265363D01*
G01X971590Y234834D02*
G03X972911Y235622I-38J1564D01*
G01X971461Y234834D02*
X971590D01*
G01X969531Y233672D02*
G02X971461Y234834I2015J-1163D01*
G01X968225Y232885D02*
G03X969531Y233672I-59J1575D01*
G01X968115Y232885D02*
X968225D01*
G01X966126Y229439D02*
G02X968115Y232885I2040J1120D01*
G01X966151Y229397D02*
X966126Y229439D01*
G01X966151Y227823D02*
G03Y229397I-1365J787D01*
G01Y225497D02*
G02Y227823I2015J1163D01*
G01X966170Y223956D02*
G03X966151Y225497I-1384J754D01*
G01Y223922D02*
X966170Y223956D01*
G01X966126Y223880D02*
X966151Y223922D01*
G01Y221597D02*
G02X966126Y223880I2015J1164D01*
G01X966170Y220056D02*
G03X966151Y221597I-1384J754D01*
G01Y220022D02*
X966170Y220056D01*
G01X971546Y242710D02*
Y244209D01*
G01X972698Y241558D02*
X971546Y242710D01*
G01X970705Y237742D02*
X971873Y238510D01*
G01X970181Y237197D02*
G02X970705Y237742I1365J-788D01*
G01X968251Y236035D02*
G03X970181Y237197I-85J2325D01*
G01X968122Y236035D02*
X968251D01*
G01X966801Y235247D02*
G02X968122Y236035I1365J-787D01*
G01X964856Y234084D02*
G03X966801Y235247I-70J2325D01*
G01X964727Y234084D02*
X964856D01*
G01X963402Y231756D02*
G02X964727Y234084I1384J753D01*
G01X963421Y231722D02*
X963402Y231756D01*
G01X963446Y229439D02*
G03X963421Y231722I-2040J1119D01*
G01Y229397D02*
X963446Y229439D01*
G01X963421Y227823D02*
G02Y229397I1365J787D01*
G01Y225497D02*
G03Y227823I-2015J1163D01*
G01X963402Y223956D02*
G02X963421Y225497I1384J754D01*
G01Y223922D02*
X963402Y223956D01*
G01X963446Y223880D02*
X963421Y223922D01*
G01Y221597D02*
G03X963446Y223880I-2015J1164D01*
G01X963402Y220056D02*
G02X963421Y221597I1384J754D01*
G01Y220022D02*
X963402Y220056D01*
G01X963446Y219980D02*
X963421Y220022D01*
G01X955917Y222760D02*
X954647D01*
G01X956134Y222543D02*
X955917Y222760D01*
G01X956134Y219377D02*
Y222543D01*
G01X956198Y218590D02*
G03X956134Y219377I-1552J270D01*
G01X914791Y244256D02*
X910493D01*
G01X916695Y246160D02*
X914791Y244256D01*
G01X920847Y246160D02*
X916695D01*
G01X971616Y234084D02*
G03X973561Y235246I-68J2323D01*
G01X971487Y234084D02*
X971616D01*
G01X970181Y233297D02*
G02X971487Y234084I1365J-788D01*
G01X968217Y232134D02*
G03X970181Y233297I-51J2326D01*
G01X968122Y232134D02*
X968217D01*
G01X966801Y229772D02*
G02X968122Y232134I1365J787D01*
G01X966826Y229730D02*
X966801Y229772D01*
G01Y227447D02*
G03X966826Y229730I-2015J1164D01*
G01X966782Y227413D02*
X966801Y227447D01*
G01Y225872D02*
G02X966782Y227413I1365J787D01*
G01X966826Y223589D02*
G03X966801Y225872I-2040J1119D01*
G01Y223547D02*
X966826Y223589D01*
G01X966782Y223513D02*
X966801Y223547D01*
G01Y221972D02*
G02X966782Y223513I1365J787D01*
G01X966826Y219689D02*
G03X966801Y221972I-2040J1119D01*
G01Y219647D02*
X966826Y219689D01*
G01X966801Y218073D02*
G02Y219647I1365J787D01*
G01X911631Y331960D02*
X911255Y332336D01*
G01X913787Y331960D02*
X911631D01*
G01X966607Y340140D02*
X959837Y346910D01*
G01X972196Y340140D02*
X966607D01*
G01X913787Y335860D02*
X912311Y337336D01*
G01X912585Y333915D02*
X911664Y334836D01*
G01X914213Y333913D02*
X912585Y333915D01*
G01X914859Y333913D02*
X914213D01*
G01X916806Y335860D02*
X914859Y333913D01*
G01X920847Y335860D02*
X916806D01*
G01X915293Y330983D02*
X914557Y330247D01*
G01X917651Y331960D02*
X915293Y330983D01*
G01X920847Y331960D02*
X917651D01*
G01X962572Y339390D02*
X957927Y344035D01*
G01X973077Y339390D02*
X962572D01*
G01X963702Y400943D02*
X962707Y401938D01*
G01X963702Y395885D02*
Y400943D01*
G01X965825Y393762D02*
X963702Y395885D01*
G01X966151Y393197D02*
X965825Y393762D01*
G01X968096Y392034D02*
G02X966151Y393197I70J2325D01*
G01X968191Y392034D02*
X968096D01*
G01X969534Y389676D02*
G03X968191Y392034I-1343J797D01*
G01X969531Y389672D02*
X969534Y389676D01*
G01X969506Y387389D02*
G02X969531Y389672I2040J1119D01*
G01Y387347D02*
X969506Y387389D01*
G01X969550Y387313D02*
X969531Y387347D01*
G01Y385772D02*
G03X969550Y387313I-1365J787D01*
G01X969531Y383446D02*
G02Y385772I2015J1163D01*
G01Y381872D02*
G03Y383446I-1365J787D01*
G01X969506Y379589D02*
G02X969531Y381872I2040J1119D01*
G01Y379547D02*
X969506Y379589D01*
G01X969550Y379513D02*
X969531Y379547D01*
G01Y377972D02*
G03X969550Y379513I-1365J787D01*
G01X969506Y375689D02*
G02X969531Y377972I2040J1119D01*
G01Y375647D02*
X969506Y375689D01*
G01X969550Y375613D02*
X969531Y375647D01*
G01Y374072D02*
G03X969550Y375613I-1365J787D01*
G01X969531Y371746D02*
G02Y374072I2015J1163D01*
G01Y370172D02*
G03Y371746I-1365J787D01*
G01X969506Y370130D02*
X969531Y370172D01*
G01Y367847D02*
G02X969506Y370130I2015J1164D01*
G01X969550Y367813D02*
X969531Y367847D01*
G01Y366272D02*
G03X969550Y367813I-1365J787D01*
G01X971476Y362784D02*
G02X969531Y366272I70J2325D01*
G01X971605Y362784D02*
X971476D01*
G01X972930Y360456D02*
G03X971605Y362784I-1384J753D01*
G01X913814Y359439D02*
X912872Y360381D01*
G01X923146Y359439D02*
X913814D01*
G01X923341Y359634D02*
X923146Y359439D01*
G01X924271Y359634D02*
X923341D01*
G01X925592Y360422D02*
G02X924271Y359634I-1365J787D01*
G01X927537Y361585D02*
G03X925592Y360422I70J-2325D01*
G01X927666Y361585D02*
X927537D01*
G01X928972Y362372D02*
G02X927666Y361585I-1365J788D01*
G01X930902Y363534D02*
G03X928972Y362372I85J-2325D01*
G01X931031Y363534D02*
X930902D01*
G01X932352Y364322D02*
G02X931031Y363534I-1365J787D01*
G01X932418Y364437D02*
X932352Y364322D01*
G01X934367Y367060D02*
X932418Y364437D01*
G01X959102Y398034D02*
X957579Y399557D01*
G01X959102Y394195D02*
Y398034D01*
G01X963213Y390084D02*
X959102Y394195D01*
G01X964845Y390084D02*
X963213D01*
G01X966170Y387756D02*
G03X964845Y390084I-1384J753D01*
G01X966151Y387722D02*
X966170Y387756D01*
G01X966126Y387680D02*
X966151Y387722D01*
G01Y385397D02*
G02X966126Y387680I2015J1164D01*
G01X966170Y383856D02*
G03X966151Y385397I-1384J754D01*
G01Y383822D02*
X966170Y383856D01*
G01X966126Y383780D02*
X966151Y383822D01*
G01Y381497D02*
G02X966126Y383780I2015J1164D01*
G01X966170Y379956D02*
G03X966151Y381497I-1384J754D01*
G01Y379922D02*
X966170Y379956D01*
G01X966126Y379880D02*
X966151Y379922D01*
G01Y377597D02*
G02X966126Y379880I2015J1164D01*
G01X966170Y376056D02*
G03X966151Y377597I-1384J754D01*
G01Y376022D02*
X966170Y376056D01*
G01X966126Y375980D02*
X966151Y376022D01*
G01Y373697D02*
G02X966126Y375980I2015J1164D01*
G01X966170Y372156D02*
G03X966151Y373697I-1384J754D01*
G01Y372122D02*
X966170Y372156D01*
G01X966126Y369839D02*
G02X966151Y372122I2040J1119D01*
G01Y369797D02*
X966126Y369839D01*
G01X966151Y368223D02*
G03Y369797I-1365J787D01*
G01Y365897D02*
G02Y368223I2015J1163D01*
G01X966170Y364356D02*
G03X966151Y365897I-1384J754D01*
G01Y364322D02*
X966170Y364356D01*
G01X966126Y364280D02*
X966151Y364322D01*
G01X968081Y360835D02*
G02X966126Y364280I85J2325D01*
G01X968210Y360835D02*
X968081D01*
G01X969531Y358472D02*
G03X968210Y360835I-1365J788D01*
G01X971289Y354997D02*
G02X969531Y358472I257J2312D01*
G01X971546Y354740D02*
X971289Y354997D01*
G01X971546Y353409D02*
Y354740D01*
G01X919134Y399301D02*
X911268Y407167D01*
G01X919134Y397667D02*
Y399301D01*
G01X920116Y396685D02*
X919134Y397667D01*
G01X920898Y396685D02*
X920116D01*
G01X922862Y395522D02*
G03X920898Y396685I-2015J-1163D01*
G01X924156Y394735D02*
G02X922862Y395522I71J1574D01*
G01X924297Y394735D02*
X924156D01*
G01X926242Y393572D02*
G03X924297Y394735I-2015J-1162D01*
G01X927536Y392785D02*
G02X926242Y393572I71J1574D01*
G01X927692Y392785D02*
X927536D01*
G01X929622Y391623D02*
G03X927692Y392785I-2015J-1163D01*
G01X930943Y390835D02*
G02X929622Y391623I44J1575D01*
G01X931038Y390835D02*
X930943D01*
G01X933002Y389672D02*
G03X931038Y390835I-2015J-1163D01*
G01X934308Y388885D02*
G02X933002Y389672I59J1575D01*
G01X934437Y388885D02*
X934308D01*
G01X936382Y387722D02*
G03X934437Y388885I-2015J-1162D01*
G01X937703Y386934D02*
G02X936382Y387722I44J1575D01*
G01X937832Y386934D02*
X937703D01*
G01X939762Y385772D02*
G03X937832Y386934I-2015J-1163D01*
G01X941068Y384985D02*
G02X939762Y385772I59J1575D01*
G01X941197Y384985D02*
X941068D01*
G01X943142Y383822D02*
G03X941197Y384985I-2015J-1162D01*
G01X944463Y383034D02*
G02X943142Y383822I44J1575D01*
G01X944653Y383034D02*
X944463D01*
G01X947887Y382660D02*
X944653Y383034D01*
G01X922556Y374941D02*
X912556D01*
G01X923013Y374484D02*
X922556Y374941D01*
G01X924912Y374484D02*
X923013D01*
G01X926242Y374072D02*
X924912Y374484D01*
G01X927548Y373285D02*
G02X926242Y374072I59J1575D01*
G01X927666Y373285D02*
X927548D01*
G01X928972Y374072D02*
G02X927666Y373285I-1365J788D01*
G01X930902Y375234D02*
G03X928972Y374072I85J-2325D01*
G01X931031Y375234D02*
X930902D01*
G01X932352Y376022D02*
G02X931031Y375234I-1365J787D01*
G01X932418Y376138D02*
X932352Y376022D01*
G01X934367Y378760D02*
X932418Y376138D01*
G01X912404Y380925D02*
Y385551D01*
G01X914640Y378689D02*
X912404Y380925D01*
G01X921343Y378689D02*
X914640D01*
G01X921788Y379134D02*
X921343Y378689D01*
G01X925752Y379134D02*
X921788D01*
G01X926126Y378760D02*
X925752Y379134D01*
G01X927607Y378760D02*
X926126D01*
G01X966356Y347939D02*
X972328D01*
G01X964786Y349509D02*
X966356Y347939D01*
G01X965676Y343290D02*
X961406Y347560D01*
G01X973077Y343290D02*
X965676D01*
G01X935412Y399600D02*
X924851Y410161D01*
G01X935731Y399047D02*
X935412Y399600D01*
G01X937683Y397884D02*
G02X935731Y399047I63J2325D01*
G01X937693Y397884D02*
G02X937683I-5J2326D01*
G01X937806D02*
X937693D01*
G01X939112Y397097D02*
G03X937806Y397884I-1365J-788D01*
G01X941076Y395934D02*
G02X939112Y397097I51J2326D01*
G01X941171Y395934D02*
X941076D01*
G01X942492Y395146D02*
G03X941171Y395934I-1365J-787D01*
G01X944422Y393984D02*
G02X942492Y395146I85J2325D01*
G01X944578Y393984D02*
X944422D01*
G01X945872Y393197D02*
G03X944578Y393984I-1365J-787D01*
G01X947817Y392034D02*
G02X945872Y393197I70J2325D01*
G01X947958Y392034D02*
X947817D01*
G01X949252Y391247D02*
G03X947958Y392034I-1365J-787D01*
G01X951182Y390086D02*
G02X949252Y391247I0J2185D01*
G01X951219Y390086D02*
X951182D01*
G01X951326Y390084D02*
G03X951219Y390086I-107J-2851D01*
G01X952843Y388509D02*
G03X951326Y390084I-1576J0D01*
G01X952843Y387517D02*
Y388509D01*
G01X953309Y386015D02*
G02X952843Y387517I2667J1651D01*
G01X953594Y385013D02*
G03X953309Y386015I-1904J0D01*
G01X953594Y384611D02*
Y385013D01*
G01X953307Y383489D02*
G03X953594Y384611I-2040J1119D01*
G01X953270Y383427D02*
X953307Y383489D01*
G01X953282Y381872D02*
G02X953270Y383427I1289J787D01*
G01X953307Y379589D02*
G03X953282Y381872I-2040J1119D01*
G01Y379547D02*
X953307Y379589D01*
G01X953263Y379513D02*
X953282Y379547D01*
G01Y377972D02*
G02X953263Y379513I1365J787D01*
G01X953348Y377859D02*
X953282Y377972D01*
G01X954647Y374860D02*
X953348Y377859D01*
G01X937038Y402529D02*
X934846Y404721D01*
G01X939235Y402529D02*
X937038D01*
G01X942181Y399583D02*
X939235Y402529D01*
G01X942492Y399045D02*
X942181Y399583D01*
G01X944422Y397883D02*
G02X942492Y399045I85J2325D01*
G01X944578Y397883D02*
X944422D01*
G01X945872Y397096D02*
G03X944578Y397883I-1365J-787D01*
G01X947817Y395933D02*
G02X945872Y397096I70J2325D01*
G01X947958Y395933D02*
X947817D01*
G01X949252Y395146D02*
G03X947958Y395933I-1365J-787D01*
G01X951216Y393983D02*
G02X949252Y395146I51J2326D01*
G01X951326Y393983D02*
X951216D01*
G01X952632Y393196D02*
G03X951326Y393983I-1365J-788D01*
G01X954562Y392034D02*
G02X952632Y393196I85J2325D01*
G01X954695Y392034D02*
X954562D01*
G01X956011Y389673D02*
G03X954695Y392034I-1364J787D01*
G01X955976Y387407D02*
G02X956011Y389673I2050J1102D01*
G01Y387347D02*
G02X955976Y387407I843J532D01*
G01X956011Y385773D02*
G03Y387347I-1364J787D01*
G01X955976Y383507D02*
G02X956011Y385773I2050J1102D01*
G01Y383447D02*
X955976Y383507D01*
G01X956011Y381873D02*
G03Y383447I-1364J787D01*
G01X957769Y378397D02*
G02X956011Y381873I256J2312D01*
G01X958026Y378140D02*
X957769Y378397D01*
G01X958026Y376809D02*
Y378140D01*
G01X912963Y353546D02*
X912509Y354000D01*
G01X914549Y353546D02*
X912963D01*
G01X916635Y351460D02*
X914549Y353546D01*
G01X920847Y351460D02*
X916635D01*
G01X959837Y349891D02*
X961406Y351460D01*
G01X959837Y346910D02*
Y349891D01*
G01X918386Y398991D02*
X910661Y406716D01*
G01X918386Y397357D02*
Y398991D01*
G01X919811Y395932D02*
X918386Y397357D01*
G01X920852Y395932D02*
X919811D01*
G01X922212Y395146D02*
G03X920852Y395932I-1360J-784D01*
G01X924142Y393984D02*
G02X922212Y395146I85J2325D01*
G01X924298Y393984D02*
X924142D01*
G01X925592Y393197D02*
G03X924298Y393984I-1365J-787D01*
G01X927537Y392034D02*
G02X925592Y393197I70J2325D01*
G01X927678Y392034D02*
X927537D01*
G01X928972Y391247D02*
G03X927678Y392034I-1365J-787D01*
G01X930936Y390084D02*
G02X928972Y391247I51J2326D01*
G01X931046Y390084D02*
X930936D01*
G01X932352Y389297D02*
G03X931046Y390084I-1365J-788D01*
G01X934282Y388135D02*
G02X932352Y389297I85J2325D01*
G01X934411Y388135D02*
X934282D01*
G01X935732Y387347D02*
G03X934411Y388135I-1365J-787D01*
G01X937677Y386184D02*
G02X935732Y387347I70J2325D01*
G01X937806Y386184D02*
X937677D01*
G01X939112Y385397D02*
G03X937806Y386184I-1365J-788D01*
G01X941042Y384235D02*
G02X939112Y385397I85J2325D01*
G01X941171Y384235D02*
X941042D01*
G01X942492Y383447D02*
G03X941171Y384235I-1365J-787D01*
G01X944437Y382284D02*
G02X942492Y383447I70J2325D01*
G01X944566Y382284D02*
X944437D01*
G01X945891Y379956D02*
G03X944566Y382284I-1384J753D01*
G01X945872Y379922D02*
X945891Y379956D01*
G01X945847Y379880D02*
X945872Y379922D01*
G01Y377597D02*
G02X945847Y379880I2015J1164D01*
G01X945938Y377481D02*
X945872Y377597D01*
G01X947887Y374860D02*
X945938Y377481D01*
G01X913704Y358691D02*
X912844Y357831D01*
G01X923456Y358691D02*
X913704D01*
G01X923649Y358884D02*
X923456Y358691D01*
G01X924297Y358884D02*
X923649D01*
G01X926242Y360047D02*
G02X924297Y358884I-2015J1162D01*
G01X927563Y360835D02*
G03X926242Y360047I44J-1575D01*
G01X927692Y360835D02*
X927563D01*
G01X929622Y361997D02*
G02X927692Y360835I-2015J1163D01*
G01X930928Y362784D02*
G03X929622Y361997I59J-1575D01*
G01X931057Y362784D02*
X930928D01*
G01X933002Y363947D02*
G02X931057Y362784I-2015J1162D01*
G01X934323Y364735D02*
G03X933002Y363947I44J-1575D01*
G01X934452Y364735D02*
X934323D01*
G01X936382Y365897D02*
G02X934452Y364735I-2015J1163D01*
G01X937747Y369010D02*
X936382Y365897D01*
G01X913221Y364513D02*
X912107Y365627D01*
G01X913584Y364513D02*
X913221D01*
G01X914563Y363534D02*
X913584Y364513D01*
G01X924271Y363534D02*
X914563D01*
G01X925592Y364322D02*
G02X924271Y363534I-1365J787D01*
G01X927537Y365485D02*
G03X925592Y364322I70J-2325D01*
G01X927666Y365485D02*
X927537D01*
G01X928972Y366272D02*
G02X927666Y365485I-1365J788D01*
G01X929038Y366387D02*
X928972Y366272D01*
G01X930987Y369010D02*
X929038Y366387D01*
G01X944507Y379378D02*
Y380709D01*
G01X944279Y379150D02*
X944507Y379378D01*
G01X943142Y379922D02*
G03X944279Y379150I1365J787D01*
G01X941197Y381085D02*
G02X943142Y379922I-70J-2325D01*
G01X941068Y381085D02*
X941197D01*
G01X939762Y381872D02*
G03X941068Y381085I1365J788D01*
G01X937832Y383034D02*
G02X939762Y381872I-85J-2325D01*
G01X937703Y383034D02*
X937832D01*
G01X936382Y383822D02*
G03X937703Y383034I1365J787D01*
G01X934437Y384985D02*
G02X936382Y383822I-70J-2325D01*
G01X934308Y384985D02*
X934437D01*
G01X933002Y385772D02*
G03X934308Y384985I1365J788D01*
G01X931072Y386934D02*
G02X933002Y385772I-85J-2325D01*
G01X930943Y386934D02*
X931072D01*
G01X929622Y387722D02*
G03X930943Y386934I1365J787D01*
G01X927677Y388885D02*
G02X929622Y387722I-70J-2325D01*
G01X927563Y388885D02*
X927677D01*
G01X926242Y389673D02*
G03X927563Y388885I1365J787D01*
G01X924312Y390835D02*
G02X926242Y389673I-85J-2325D01*
G01X924183Y390835D02*
X924312D01*
G01X922862Y391623D02*
G03X924183Y390835I1365J787D01*
G01X920932Y392785D02*
G02X922862Y391623I-85J-2325D01*
G01X920776Y392785D02*
X920932D01*
G01X919482Y393572D02*
G03X920776Y392785I1365J787D01*
G01X919480Y393571D02*
X919482Y393572D01*
G01X919010Y394386D02*
X919480Y393571D01*
G01X918427Y394969D02*
X919010Y394386D01*
G01X917565Y394969D02*
X918427D01*
G01X912206Y400329D02*
X917565Y394969D01*
G01X911026Y400329D02*
X912206D01*
G01X964450Y400988D02*
X965276Y401814D01*
G01X964450Y396195D02*
Y400988D01*
G01X966424Y394221D02*
X964450Y396195D01*
G01X966799Y393571D02*
X966424Y394221D01*
G01X966801Y393572D02*
X966799Y393571D01*
G01X968095Y392785D02*
G02X966801Y393572I71J1574D01*
G01X968258Y392785D02*
X968095D01*
G01X970187Y389306D02*
G03X968258Y392785I-1929J1205D01*
G01X970181Y389297D02*
X970187Y389306D01*
G01X970162Y387756D02*
G02X970181Y389297I1384J754D01*
G01Y387722D02*
X970162Y387756D01*
G01X970206Y387680D02*
X970181Y387722D01*
G01Y385397D02*
G03X970206Y387680I-2015J1164D01*
G01X970162Y383856D02*
G02X970181Y385397I1384J754D01*
G01Y383822D02*
X970162Y383856D01*
G01X970206Y381539D02*
G03X970181Y383822I-2040J1119D01*
G01Y381497D02*
X970206Y381539D01*
G01X970162Y379956D02*
G02X970181Y381497I1384J754D01*
G01Y379922D02*
X970162Y379956D01*
G01X970206Y379880D02*
X970181Y379922D01*
G01Y377597D02*
G03X970206Y379880I-2015J1164D01*
G01X970162Y376056D02*
G02X970181Y377597I1384J754D01*
G01Y376022D02*
X970162Y376056D01*
G01X970206Y375980D02*
X970181Y376022D01*
G01Y373697D02*
G03X970206Y375980I-2015J1164D01*
G01X970162Y372156D02*
G02X970181Y373697I1384J754D01*
G01Y372122D02*
X970162Y372156D01*
G01X970206Y369839D02*
G03X970181Y372122I-2040J1119D01*
G01Y369797D02*
X970206Y369839D01*
G01X970181Y368223D02*
G02Y369797I1365J787D01*
G01Y365897D02*
G03Y368223I-2015J1163D01*
G01X971502Y363534D02*
G02X970181Y365897I44J1575D01*
G01X971631Y363534D02*
X971502D01*
G01X973561Y362372D02*
G03X971631Y363534I-2015J-1163D01*
G01X936017Y400053D02*
X925554Y410516D01*
G01X936382Y399421D02*
X936017Y400053D01*
G01X937703Y398634D02*
G02X936382Y399421I44J1576D01*
G01X937832Y398634D02*
X937703D01*
G01X939762Y397472D02*
G03X937832Y398634I-2015J-1163D01*
G01X941068Y396685D02*
G02X939762Y397472I59J1575D01*
G01X941178Y396685D02*
X941068D01*
G01X943142Y395522D02*
G03X941178Y396685I-2015J-1163D01*
G01X944436Y394735D02*
G02X943142Y395522I71J1574D01*
G01X944577Y394735D02*
X944436D01*
G01X946522Y393572D02*
G03X944577Y394735I-2015J-1162D01*
G01X947816Y392785D02*
G02X946522Y393572I71J1574D01*
G01X947957Y392785D02*
X947816D01*
G01X949902Y391622D02*
G03X947957Y392785I-2015J-1162D01*
G01X951223Y390836D02*
G02X949902Y391622I0J1503D01*
G01X951243Y390836D02*
X951223D01*
G01X951352Y390834D02*
G03X951243Y390836I-109J-2994D01*
G01X953594Y388509D02*
G03X951352Y390834I-2327J0D01*
G01X953594Y388131D02*
Y388509D01*
G01X953951Y386552D02*
G02X953594Y388131I3313J1579D01*
G01X954269Y385996D02*
G02X953951Y386552I3552J2400D01*
G01X954647Y384536D02*
G03X954269Y385996I-2247J197D01*
G01X954647Y382660D02*
Y384536D01*
G01X916677Y347560D02*
X914621Y349616D01*
G01X920847Y347560D02*
X916677D01*
G01X922869Y375689D02*
X912866D01*
G01X923324Y375234D02*
X922869Y375689D01*
G01X925913Y375234D02*
X923324D01*
G01X926287Y374860D02*
X925913Y375234D01*
G01X927607Y374860D02*
X926287D01*
G01X959853Y400093D02*
X960157Y400397D01*
G01X959853Y394507D02*
Y400093D01*
G01X963525Y390835D02*
X959853Y394507D01*
G01X964858Y390835D02*
X963525D01*
G01X966826Y387389D02*
G03X964858Y390835I-2040J1120D01*
G01X966801Y387347D02*
X966826Y387389D01*
G01X966782Y387313D02*
X966801Y387347D01*
G01Y385772D02*
G02X966782Y387313I1365J787D01*
G01X966826Y383489D02*
G03X966801Y385772I-2040J1119D01*
G01Y383447D02*
X966826Y383489D01*
G01X966782Y383413D02*
X966801Y383447D01*
G01Y381872D02*
G02X966782Y383413I1365J787D01*
G01X966826Y379589D02*
G03X966801Y381872I-2040J1119D01*
G01Y379547D02*
X966826Y379589D01*
G01X966782Y379513D02*
X966801Y379547D01*
G01Y377972D02*
G02X966782Y379513I1365J787D01*
G01X966826Y375689D02*
G03X966801Y377972I-2040J1119D01*
G01Y375647D02*
X966826Y375689D01*
G01X966782Y375613D02*
X966801Y375647D01*
G01Y374072D02*
G02X966782Y375613I1365J787D01*
G01X966801Y371746D02*
G03Y374072I-2015J1163D01*
G01Y370172D02*
G02Y371746I1365J787D01*
G01X966826Y370130D02*
X966801Y370172D01*
G01Y367847D02*
G03X966826Y370130I-2015J1164D01*
G01X966782Y367813D02*
X966801Y367847D01*
G01Y366272D02*
G02X966782Y367813I1365J787D01*
G01X966826Y363989D02*
G03X966801Y366272I-2040J1119D01*
G01Y363947D02*
X966826Y363989D01*
G01X966782Y363913D02*
X966801Y363947D01*
G01X968107Y361585D02*
G02X966782Y363913I59J1575D01*
G01X968236Y361585D02*
X968107D01*
G01X970181Y358097D02*
G03X968236Y361585I-2015J1163D01*
G01X971318Y355750D02*
G02X970181Y358097I228J1559D01*
G01X971546Y355978D02*
X971318Y355750D01*
G01X971546Y357309D02*
Y355978D01*
G01X911656Y380615D02*
Y385241D01*
G01X914330Y377941D02*
X911656Y380615D01*
G01X921656Y377941D02*
X914330D01*
G01X922099Y378384D02*
X921656Y377941D01*
G01X925312Y378384D02*
X922099D01*
G01X926705Y376991D02*
X925312Y378384D01*
G01X928806Y376991D02*
X926705D01*
G01X930987Y379172D02*
X928806Y376991D01*
G01X930987Y380709D02*
Y379172D01*
G01X942782Y400044D02*
X939547Y403279D01*
G01X943142Y399421D02*
X942782Y400044D01*
G01X944436Y398634D02*
G02X943142Y399421I71J1574D01*
G01X944577Y398634D02*
X944436D01*
G01X946522Y397471D02*
G03X944577Y398634I-2015J-1162D01*
G01X947816Y396684D02*
G02X946522Y397471I71J1574D01*
G01X947972Y396684D02*
X947816D01*
G01X949902Y395522D02*
G03X947972Y396684I-2015J-1163D01*
G01X951223Y394734D02*
G02X949902Y395522I44J1575D01*
G01X951318Y394734D02*
X951223D01*
G01X953282Y393571D02*
G03X951318Y394734I-2015J-1163D01*
G01X954588Y392784D02*
G02X953282Y393571I59J1575D01*
G01X954647Y392785D02*
G03X954588Y392784I0J-1741D01*
G01X954717Y392785D02*
X954647D01*
G01X956662Y389296D02*
G03X954717Y392785I-2015J1163D01*
G01X956662Y387722D02*
G02Y389296I1364J787D01*
G01X956697Y387662D02*
X956662Y387722D01*
G01Y385396D02*
G03X956697Y387662I-2015J1164D01*
G01X956662Y383822D02*
G02Y385396I1364J787D01*
G01X956697Y383762D02*
X956662Y383822D01*
G01Y381496D02*
G03X956697Y383762I-2015J1164D01*
G01X957799Y379151D02*
G02X956662Y381496I227J1558D01*
G01X958026Y379378D02*
X957799Y379151D01*
G01X958026Y380709D02*
Y379378D01*
G01X959723Y353677D02*
X961406Y355360D01*
G01X959723Y352887D02*
Y353677D01*
G01X958671Y351835D02*
X959723Y352887D01*
G01X957881Y351835D02*
X958671D01*
G01X956360Y350314D02*
X957881Y351835D01*
G01X956360Y345056D02*
Y345300D01*
G01X957381Y344035D02*
X956360Y345056D01*
G01X957927Y344035D02*
X957381D01*
G01X968036Y344040D02*
X972196D01*
G01X963217Y348859D02*
X968036Y344040D01*
G01X963217Y351840D02*
Y348859D01*
G01X964786Y353409D02*
X963217Y351840D01*
G01X912796Y363765D02*
X912107Y363076D01*
G01X913274Y363765D02*
X912796D01*
G01X914255Y362784D02*
X913274Y363765D01*
G01X924297Y362784D02*
X914255D01*
G01X926242Y363947D02*
G02X924297Y362784I-2015J1162D01*
G01X927563Y364735D02*
G03X926242Y363947I44J-1575D01*
G01X927692Y364735D02*
X927563D01*
G01X929622Y365897D02*
G02X927692Y364735I-2015J1163D01*
G01X930928Y366684D02*
G03X929622Y365897I59J-1575D01*
G01X931038Y366684D02*
X930928D01*
G01X933002Y367847D02*
G02X931038Y366684I-2015J1163D01*
G01X934296Y368634D02*
G03X933002Y367847I71J-1574D01*
G01X934437Y368634D02*
X934296D01*
G01X936382Y369797D02*
G02X934437Y368634I-2015J1162D01*
G01X936449Y369912D02*
X936382Y369797D01*
G01X937747Y372909D02*
X936449Y369912D01*
G01X911896Y399581D02*
X910716D01*
G01X917255Y394221D02*
X911896Y399581D01*
G01X918117Y394221D02*
X917255D01*
G01X918411Y393927D02*
X918117Y394221D01*
G01X918832Y393197D02*
X918411Y393927D01*
G01X920777Y392034D02*
G02X918832Y393197I70J2325D01*
G01X920918Y392034D02*
X920777D01*
G01X922212Y391247D02*
G03X920918Y392034I-1365J-787D01*
G01X924142Y390085D02*
G02X922212Y391247I85J2325D01*
G01X924271Y390085D02*
X924142D01*
G01X925592Y389297D02*
G03X924271Y390085I-1365J-787D01*
G01X927522Y388135D02*
G02X925592Y389297I85J2325D01*
G01X927651Y388135D02*
X927522D01*
G01X928972Y387347D02*
G03X927651Y388135I-1365J-787D01*
G01X930917Y386184D02*
G02X928972Y387347I70J2325D01*
G01X931046Y386184D02*
X930917D01*
G01X932352Y385397D02*
G03X931046Y386184I-1365J-788D01*
G01X934282Y384235D02*
G02X932352Y385397I85J2325D01*
G01X934411Y384235D02*
X934282D01*
G01X935732Y383447D02*
G03X934411Y384235I-1365J-787D01*
G01X937677Y382284D02*
G02X935732Y383447I70J2325D01*
G01X937806Y382284D02*
X937677D01*
G01X939112Y381497D02*
G03X937806Y382284I-1365J-788D01*
G01X941042Y380335D02*
G02X939112Y381497I85J2325D01*
G01X941171Y380335D02*
X941042D01*
G01X942492Y379547D02*
G03X941171Y380335I-1365J-787D01*
G01X944250Y378397D02*
G02X942492Y379547I257J2312D01*
G01X944507Y378140D02*
X944250Y378397D01*
G01X944507Y376809D02*
Y378140D01*
G01X911268Y407167D02*
Y408422D01*
G01X924851Y410161D02*
X923652D01*
G01X928696Y412331D02*
X928671Y412356D01*
G01X929916Y412331D02*
X928696D01*
G01X934846Y407401D02*
X929916Y412331D01*
G01X934846Y404721D02*
Y407401D01*
G01X925554Y411866D02*
X925330Y412090D01*
G01X925554Y410516D02*
Y411866D01*
G01X930449Y412856D02*
Y414135D01*
G01X935594Y407711D02*
X930449Y412856D01*
G01X935594Y405031D02*
Y407711D01*
G01X937346Y403279D02*
X935594Y405031D01*
G01X939547Y403279D02*
X937346D01*
G01X1008906Y192441D02*
Y191225D01*
G01X1009206Y192741D02*
X1008906Y192441D01*
G01X1009206Y197391D02*
Y192741D01*
G01X1006971Y199626D02*
X1009206Y197391D01*
G01X1006971Y208923D02*
Y199626D01*
G01X1006710Y209898D02*
G02X1006971Y208923I-1691J-975D01*
G01X1006710Y212224D02*
G03Y209898I2015J-1163D01*
G01Y213798D02*
G02Y212224I-1364J-787D01*
G01Y216124D02*
G03Y213798I2015J-1163D01*
G01Y217698D02*
G02Y216124I-1365J-787D01*
G01Y220024D02*
G03Y217698I2015J-1163D01*
G01X1014906Y198114D02*
Y196325D01*
G01X1010521Y202499D02*
X1014906Y198114D01*
G01X1010521Y209080D02*
Y202499D01*
G01X1010740Y209898D02*
G03X1010521Y209080I1419J-818D01*
G01X1010740Y212224D02*
G02Y209898I-2015J-1163D01*
G01Y213798D02*
G03Y212224I1365J-787D01*
G01Y216124D02*
G02Y213798I-2015J-1163D01*
G01Y217698D02*
G03Y216124I1365J-787D01*
G01Y220024D02*
G02Y217698I-2015J-1163D01*
G01X1030600Y200761D02*
X1033500Y197861D01*
G01X1030600Y207087D02*
Y200761D01*
G01X1030370Y207946D02*
G02X1030600Y207087I-1488J-859D01*
G01X1030370Y210272D02*
G03Y207946I2015J-1163D01*
G01X1030389Y211813D02*
G02X1030370Y210272I-1384J-754D01*
G01Y211847D02*
X1030389Y211813D01*
G01X1030345Y211889D02*
X1030370Y211847D01*
G01Y214172D02*
G03X1030345Y211889I2015J-1164D01*
G01X1030389Y215713D02*
G02X1030370Y214172I-1384J-754D01*
G01Y215747D02*
X1030389Y215713D01*
G01X1030345Y215789D02*
X1030370Y215747D01*
G01Y218072D02*
G03X1030345Y215789I2015J-1164D01*
G01X979671Y217698D02*
G02Y220022I2015J1162D01*
G01X981234Y214987D02*
X979671Y217698D01*
G01X981234Y202943D02*
Y214987D01*
G01X982146Y202031D02*
X981234Y202943D01*
G01X982146Y200615D02*
Y202031D01*
G01X980146Y198615D02*
X982146Y200615D01*
G01X980146Y195504D02*
Y198615D01*
G01X978828Y194186D02*
X980146Y195504D01*
G01X990881Y203694D02*
Y200481D01*
G01X990461Y204423D02*
X990881Y203694D01*
G01X990461Y205997D02*
G03Y204423I1365J-787D01*
G01X990486Y206039D02*
X990461Y205997D01*
G01Y208322D02*
G02X990486Y206039I-2015J-1164D01*
G01X990442Y208356D02*
X990461Y208322D01*
G01Y209897D02*
G03X990442Y208356I1365J-787D01*
G01X990486Y212180D02*
G02X990461Y209897I-2040J-1119D01*
G01Y212222D02*
X990486Y212180D01*
G01X990442Y212256D02*
X990461Y212222D01*
G01Y213797D02*
G03X990442Y212256I1365J-787D01*
G01X990486Y216080D02*
G02X990461Y213797I-2040J-1119D01*
G01Y216122D02*
X990486Y216080D01*
G01X990442Y216156D02*
X990461Y216122D01*
G01Y217697D02*
G03X990442Y216156I1365J-787D01*
G01X990486Y219980D02*
G02X990461Y217697I-2040J-1119D01*
G01X1032240Y197261D02*
Y190375D01*
G01X1029300Y200201D02*
X1032240Y197261D01*
G01X1029300Y204418D02*
Y200201D01*
G01X1027913Y205805D02*
X1029300Y204418D01*
G01X1027640Y206373D02*
G02X1027913Y205805I-3154J-1865D01*
G01X1027621Y206407D02*
X1027640Y206373D01*
G01Y207946D02*
G03X1027621Y206407I1365J-786D01*
G01X1027640Y210272D02*
G02Y207946I-2015J-1163D01*
G01X1027621Y211813D02*
G03X1027640Y210272I1384J-754D01*
G01Y211847D02*
X1027621Y211813D01*
G01X1027665Y211889D02*
X1027640Y211847D01*
G01Y214172D02*
G02X1027665Y211889I-2015J-1164D01*
G01X1027621Y215713D02*
G03X1027640Y214172I1384J-754D01*
G01Y215747D02*
X1027621Y215713D01*
G01X1027665Y215789D02*
X1027640Y215747D01*
G01Y218072D02*
G02X1027665Y215789I-2015J-1164D01*
G01X1004906Y201894D02*
Y190725D01*
G01X1002898Y203902D02*
X1004906Y201894D01*
G01X1002898Y209525D02*
Y203902D01*
G01X1003330Y210273D02*
X1002898Y209525D01*
G01X1003349Y211813D02*
G02X1003330Y210273I-1384J-753D01*
G01Y211847D02*
X1003349Y211813D01*
G01X1003305Y211889D02*
X1003330Y211847D01*
G01Y214172D02*
G03X1003305Y211889I2015J-1164D01*
G01X1003349Y215713D02*
G02X1003330Y214172I-1384J-754D01*
G01Y215747D02*
X1003349Y215713D01*
G01X1003305Y215789D02*
X1003330Y215747D01*
G01Y218072D02*
G03X1003305Y215789I2015J-1164D01*
G01X1002906Y202494D02*
Y200493D01*
G01X1001800Y203600D02*
X1002906Y202494D01*
G01X1001800Y206284D02*
Y203600D01*
G01X1000850Y209837D02*
G02X1001800Y206284I-6168J-3553D01*
G01X1000599Y210272D02*
X1000850Y209837D01*
G01X1000571Y211796D02*
G03X1000599Y210272I1394J-737D01*
G01X1000600Y211847D02*
G02X1000571Y211796I-2033J1122D01*
G01X1000601Y211847D02*
X1000600D01*
G01X1000636Y211907D02*
X1000601Y211847D01*
G01X1000632Y214117D02*
G02X1000636Y211907I-2046J-1109D01*
G01X1000631Y214122D02*
X1000632Y214117D01*
G01X1000601Y214174D02*
X1000631Y214122D01*
G01X1000601Y215748D02*
G03Y214174I1364J-787D01*
G01Y218074D02*
G02Y215748I-2015J-1163D01*
G01X1006906Y191791D02*
Y191175D01*
G01X1006006Y192691D02*
X1006906Y191791D01*
G01X1006006Y202094D02*
Y192691D01*
G01X1003700Y204400D02*
X1006006Y202094D01*
G01X1003700Y209412D02*
Y204400D01*
G01X1003980Y209897D02*
X1003700Y209412D01*
G01X1004005Y212180D02*
G02X1003980Y209897I-2040J-1119D01*
G01Y212222D02*
X1004005Y212180D01*
G01X1003961Y212256D02*
X1003980Y212222D01*
G01Y213797D02*
G03X1003961Y212256I1365J-787D01*
G01X1004005Y216080D02*
G02X1003980Y213797I-2040J-1119D01*
G01Y216122D02*
X1004005Y216080D01*
G01X1003961Y216156D02*
X1003980Y216122D01*
G01Y217697D02*
G03X1003961Y216156I1365J-787D01*
G01X1004005Y219980D02*
G02X1003980Y217697I-2040J-1119D01*
G01X999950Y217696D02*
G02X999915Y219962I2015J1164D01*
G01X999950Y216122D02*
G03Y217696I-1364J787D01*
G01X999915Y216062D02*
X999950Y216122D01*
G01Y213796D02*
G02X999915Y216062I2015J1164D01*
G01X999950Y212222D02*
G03Y213796I-1364J787D01*
G01X999915Y212162D02*
X999950Y212222D01*
G01Y209896D02*
G02X999915Y212162I2015J1164D01*
G01X1000700Y207099D02*
G03X999950Y209896I-5592J0D01*
G01X1000700Y201580D02*
Y207099D01*
G01X1000906Y201374D02*
X1000700Y201580D01*
G01X1000906Y200173D02*
Y201374D01*
G01X1012906Y198181D02*
Y196375D01*
G01X1009426Y201661D02*
X1012906Y198181D01*
G01X1009426Y207795D02*
Y201661D01*
G01X1010090Y210274D02*
G03X1009426Y207795I4295J-2479D01*
G01X1010090Y211848D02*
G02Y210274I-1365J-787D01*
G01Y214174D02*
G03Y211848I2015J-1163D01*
G01Y215748D02*
G02Y214174I-1365J-787D01*
G01Y218074D02*
G03Y215748I2015J-1163D01*
G01X1030238Y197259D02*
Y190273D01*
G01X1028098Y199399D02*
X1030238Y197259D01*
G01X1028098Y204347D02*
Y199399D01*
G01X1027422Y205022D02*
X1028098Y204347D01*
G01X1027337Y205108D02*
X1027422Y205022D01*
G01X1026990Y205997D02*
G02X1027337Y205108I-2504J-1490D01*
G01X1026965Y206039D02*
X1026990Y205997D01*
G01Y208322D02*
G03X1026965Y206039I2015J-1164D01*
G01X1027009Y208356D02*
X1026990Y208322D01*
G01Y209897D02*
G02X1027009Y208356I-1365J-787D01*
G01X1026965Y212180D02*
G03X1026990Y209897I2040J-1119D01*
G01Y212222D02*
X1026965Y212180D01*
G01X1027009Y212256D02*
X1026990Y212222D01*
G01Y213797D02*
G02X1027009Y212256I-1365J-787D01*
G01X1026965Y216080D02*
G03X1026990Y213797I2040J-1119D01*
G01Y216122D02*
X1026965Y216080D01*
G01X1027009Y216156D02*
X1026990Y216122D01*
G01Y217697D02*
G02X1027009Y216156I-1365J-787D01*
G01X1026965Y219980D02*
G03X1026990Y217697I2040J-1119D01*
G01X988881Y191977D02*
Y191212D01*
G01X989426Y192522D02*
X988881Y191977D01*
G01X989426Y201771D02*
Y192522D01*
G01X990031Y202376D02*
X989426Y201771D01*
G01X990031Y203666D02*
Y202376D01*
G01X989811Y204048D02*
X990031Y203666D01*
G01X989811Y206372D02*
G03Y204048I2015J-1162D01*
G01Y207946D02*
G02Y206372I-1365J-787D01*
G01Y210272D02*
G03Y207946I2015J-1163D01*
G01X989830Y211813D02*
G02X989811Y210272I-1384J-754D01*
G01Y211847D02*
X989830Y211813D01*
G01X989786Y211889D02*
X989811Y211847D01*
G01Y214172D02*
G03X989786Y211889I2015J-1164D01*
G01X989830Y215713D02*
G02X989811Y214172I-1384J-754D01*
G01Y215747D02*
X989830Y215713D01*
G01X989786Y215789D02*
X989811Y215747D01*
G01Y218072D02*
G03X989786Y215789I2015J-1164D01*
G01X981984Y215186D02*
X980321Y218073D01*
G01X981984Y203254D02*
Y215186D01*
G01X982894Y202344D02*
X981984Y203254D01*
G01X982894Y200293D02*
Y202344D01*
G01X980894Y198293D02*
X982894Y200293D01*
G01X980894Y194689D02*
Y198293D01*
G01X981397Y194186D02*
X980894Y194689D01*
G01X994906Y201319D02*
Y200336D01*
G01X993631Y202594D02*
X994906Y201319D01*
G01X993631Y203672D02*
Y202594D01*
G01X993841Y204047D02*
X993631Y203672D01*
G01X993866Y206330D02*
G02X993841Y204047I-2040J-1119D01*
G01Y206372D02*
X993866Y206330D01*
G01X993841Y207946D02*
G03Y206372I1365J-787D01*
G01Y210272D02*
G02Y207946I-2015J-1163D01*
G01X993822Y211813D02*
G03X993841Y210272I1384J-754D01*
G01Y211847D02*
X993822Y211813D01*
G01X993866Y211889D02*
X993841Y211847D01*
G01Y214172D02*
G02X993866Y211889I-2015J-1164D01*
G01X993822Y215713D02*
G03X993841Y214172I1384J-754D01*
G01Y215747D02*
X993822Y215713D01*
G01X993866Y215789D02*
X993841Y215747D01*
G01Y218072D02*
G02X993866Y215789I-2015J-1164D01*
G01X1033234Y205467D02*
X1035600Y203101D01*
G01X1033234Y207498D02*
Y205467D01*
G01X1033750Y208322D02*
X1033234Y207498D01*
G01X1031700Y205000D02*
X1034356Y202344D01*
G01X1031700Y206200D02*
Y205000D01*
G01X1031259Y207895D02*
G02X1031700Y206200I-3034J-1694D01*
G01X1031001Y208356D02*
X1031259Y207895D01*
G01X1031020Y209897D02*
G03X1031001Y208356I1365J-787D01*
G01X1031045Y212180D02*
G02X1031020Y209897I-2040J-1119D01*
G01Y212222D02*
X1031045Y212180D01*
G01X1031001Y212256D02*
X1031020Y212222D01*
G01Y213797D02*
G03X1031001Y212256I1365J-787D01*
G01X1031045Y216080D02*
G02X1031020Y213797I-2040J-1119D01*
G01Y216122D02*
X1031045Y216080D01*
G01X1031001Y216156D02*
X1031020Y216122D01*
G01Y217697D02*
G03X1031001Y216156I1365J-787D01*
G01X1031045Y219980D02*
G02X1031020Y217697I-2040J-1119D01*
G01X986881Y191814D02*
Y190678D01*
G01X988153Y193086D02*
X986881Y191814D01*
G01X988153Y201047D02*
Y193086D01*
G01X986870Y202330D02*
X988153Y201047D01*
G01X986870Y211047D02*
Y202330D01*
G01X987081Y211848D02*
G03X986870Y211047I1365J-788D01*
G01X987081Y214174D02*
G02Y211848I-2015J-1163D01*
G01Y215748D02*
G03Y214174I1365J-787D01*
G01Y218074D02*
G02Y215748I-2015J-1163D01*
G01X993191Y217697D02*
G02X993166Y219980I2015J1164D01*
G01X993210Y216156D02*
G03X993191Y217697I-1384J754D01*
G01Y216122D02*
X993210Y216156D01*
G01X993166Y216080D02*
X993191Y216122D01*
G01Y213797D02*
G02X993166Y216080I2015J1164D01*
G01X993210Y212256D02*
G03X993191Y213797I-1384J754D01*
G01Y212222D02*
X993210Y212256D01*
G01X993166Y212180D02*
X993191Y212222D01*
G01Y209897D02*
G02X993166Y212180I2015J1164D01*
G01X993210Y208356D02*
G03X993191Y209897I-1384J754D01*
G01Y208322D02*
X993210Y208356D01*
G01X993166Y206039D02*
G02X993191Y208322I2040J1119D01*
G01Y205997D02*
X993166Y206039D01*
G01X993191Y204422D02*
G03Y205997I-1365J787D01*
G01X992881Y203868D02*
X993191Y204422D01*
G01X992881Y200681D02*
Y203868D01*
G01X996906Y203468D02*
Y201105D01*
G01X996571Y204047D02*
X996906Y203468D01*
G01X996546Y206330D02*
G03X996571Y204047I2040J-1119D01*
G01Y206372D02*
X996546Y206330D01*
G01X996571Y207946D02*
G02Y206372I-1365J-787D01*
G01Y210272D02*
G03Y207946I2015J-1163D01*
G01X996590Y211813D02*
G02X996571Y210272I-1384J-754D01*
G01Y211847D02*
X996590Y211813D01*
G01X996546Y211889D02*
X996571Y211847D01*
G01Y214172D02*
G03X996546Y211889I2015J-1164D01*
G01X996590Y215713D02*
G02X996571Y214172I-1384J-754D01*
G01Y215747D02*
X996590Y215713D01*
G01X996546Y215789D02*
X996571Y215747D01*
G01Y218072D02*
G03X996546Y215789I2015J-1164D01*
G01X1007360Y215748D02*
G03Y218074I-2015J1163D01*
G01Y214174D02*
G02Y215748I1365J787D01*
G01Y211848D02*
G03Y214174I-2017J1163D01*
G01Y210274D02*
G02Y211848I1365J787D01*
G01X1008011Y207844D02*
G03X1007360Y210274I-4862J0D01*
G01X1008011Y200687D02*
Y207844D01*
G01X1010906Y197792D02*
X1008011Y200687D01*
G01X1010906Y191275D02*
Y197792D01*
G01X974646Y193141D02*
X973636Y192131D01*
G01X974646Y194861D02*
Y193141D01*
G01X977408Y197623D02*
X974646Y194861D01*
G01X977408Y200383D02*
Y197623D01*
G01X978216Y201191D02*
X977408Y200383D01*
G01X978216Y212851D02*
Y201191D01*
G01X977056Y214011D02*
X978216Y212851D01*
G01X977056Y218323D02*
Y214011D01*
G01X977806Y214322D02*
Y218522D01*
G01X978964Y213164D02*
X977806Y214322D01*
G01X978964Y200881D02*
Y213164D01*
G01X978158Y200075D02*
X978964Y200881D01*
G01X978158Y197312D02*
Y200075D01*
G01X975396Y194550D02*
X978158Y197312D01*
G01X975396Y192931D02*
Y194550D01*
G01X976186Y192141D02*
X975396Y192931D01*
G01X997221Y217697D02*
G03X997246Y219980I-2015J1164D01*
G01X997202Y216156D02*
G02X997221Y217697I1384J754D01*
G01Y216122D02*
X997202Y216156D01*
G01X997246Y216080D02*
X997221Y216122D01*
G01Y213797D02*
G03X997246Y216080I-2015J1164D01*
G01X997202Y212256D02*
G02X997221Y213797I1384J754D01*
G01Y212222D02*
X997202Y212256D01*
G01X997246Y212180D02*
X997221Y212222D01*
G01Y209897D02*
G03X997246Y212180I-2015J1164D01*
G01X997202Y208356D02*
G02X997221Y209897I1384J754D01*
G01Y208322D02*
X997202Y208356D01*
G01X997246Y206039D02*
G03X997221Y208322I-2040J1119D01*
G01Y205997D02*
X997246Y206039D01*
G01X997221Y204423D02*
G02Y205997I1365J787D01*
G01X998906Y201759D02*
X997221Y204423D01*
G01X998906Y200994D02*
Y201759D01*
G01X1006710Y221598D02*
G02Y220024I-1365J-787D01*
G01Y223924D02*
G03Y221598I2015J-1163D01*
G01Y225498D02*
G02Y223924I-1365J-787D01*
G01Y227824D02*
G03Y225498I2015J-1163D01*
G01X1006919Y228546D02*
G02X1006710Y227824I-1574J64D01*
G01X1007028Y229289D02*
G03X1006919Y228546I3470J-889D01*
G01X1007160Y230379D02*
G02X1007028Y229289I-2329J-271D01*
G01X1007360Y231348D02*
G03X1007160Y230379I1365J-787D01*
G01X1007676Y231881D02*
X1007360Y231348D01*
G01X1008725Y234460D02*
X1007676Y231881D01*
G01X1010740Y221598D02*
G03Y220024I1365J-787D01*
G01Y223924D02*
G02Y221598I-2015J-1163D01*
G01Y225498D02*
G03Y223924I1365J-787D01*
G01Y227824D02*
G02Y225498I-2015J-1163D01*
G01Y229398D02*
G03Y227824I1365J-787D01*
G01Y231724D02*
G02Y229398I-2015J-1163D01*
G01Y233298D02*
G03Y231724I1365J-787D01*
G01Y235624D02*
G02Y233298I-2015J-1163D01*
G01Y237198D02*
G03Y235624I1365J-787D01*
G01X1010805Y237310D02*
X1010740Y237198D01*
G01X1012105Y240309D02*
X1010805Y237310D01*
G01X1030389Y219613D02*
G02X1030370Y218072I-1384J-754D01*
G01Y219647D02*
X1030389Y219613D01*
G01X1030345Y219689D02*
X1030370Y219647D01*
G01Y221972D02*
G03X1030345Y219689I2015J-1164D01*
G01X1030389Y223513D02*
G02X1030370Y221972I-1384J-754D01*
G01Y223547D02*
X1030389Y223513D01*
G01X1030345Y223589D02*
X1030370Y223547D01*
G01Y225872D02*
G03X1030345Y223589I2015J-1164D01*
G01X1030389Y227413D02*
G02X1030370Y225872I-1384J-754D01*
G01X1030305Y227559D02*
X1030389Y227413D01*
G01X1029005Y230559D02*
X1030305Y227559D01*
G01X986210Y237718D02*
X985066Y240309D01*
G01X986431Y237197D02*
G02X986210Y237718I2016J1162D01*
G01X986450Y235656D02*
G03X986431Y237197I-1384J754D01*
G01Y235622D02*
X986450Y235656D01*
G01X986406Y235580D02*
X986431Y235622D01*
G01Y233297D02*
G02X986406Y235580I2015J1164D01*
G01X986450Y231756D02*
G03X986431Y233297I-1384J754D01*
G01Y231722D02*
X986450Y231756D01*
G01X986406Y229439D02*
G02X986431Y231722I2040J1119D01*
G01Y229397D02*
X986406Y229439D01*
G01X985110Y227035D02*
G03X986431Y229397I-44J1575D01*
G01X985015Y227035D02*
X985110D01*
G01X983051Y225872D02*
G02X985015Y227035I2015J-1163D01*
G01X981745Y225085D02*
G03X983051Y225872I-59J1575D01*
G01X981616Y225085D02*
X981745D01*
G01X979671Y221597D02*
G02X981616Y225085I2015J1163D01*
G01X979690Y220056D02*
G03X979671Y221597I-1384J754D01*
G01Y220022D02*
X979690Y220056D01*
G01X990461Y220022D02*
X990486Y219980D01*
G01X990442Y220056D02*
X990461Y220022D01*
G01Y221597D02*
G03X990442Y220056I1365J-787D01*
G01X990486Y223880D02*
G02X990461Y221597I-2040J-1119D01*
G01Y223922D02*
X990486Y223880D01*
G01X990442Y223956D02*
X990461Y223922D01*
G01Y225497D02*
G03X990442Y223956I1365J-787D01*
G01X990527Y225611D02*
X990461Y225497D01*
G01X991826Y228610D02*
X990527Y225611D01*
G01X1027621Y219613D02*
G03X1027640Y218072I1384J-754D01*
G01Y219647D02*
X1027621Y219613D01*
G01X1027665Y219689D02*
X1027640Y219647D01*
G01Y221972D02*
G02X1027665Y219689I-2015J-1164D01*
G01X1027621Y223513D02*
G03X1027640Y221972I1384J-754D01*
G01Y223547D02*
X1027621Y223513D01*
G01X1027665Y223589D02*
X1027640Y223547D01*
G01Y225872D02*
G02X1027665Y223589I-2015J-1164D01*
G01X1027621Y227413D02*
G03X1027640Y225872I1384J-754D01*
G01Y227447D02*
X1027621Y227413D01*
G01X1027665Y229730D02*
G02X1027640Y227447I-2040J-1119D01*
G01Y229772D02*
X1027665Y229730D01*
G01X1027430Y230599D02*
G03X1027640Y229772I1575J-40D01*
G01X1027430Y234604D02*
Y230599D01*
G01X1025625Y236409D02*
X1027430Y234604D01*
G01X1003349Y219613D02*
G02X1003330Y218072I-1384J-754D01*
G01Y219647D02*
X1003349Y219613D01*
G01X1003305Y219689D02*
X1003330Y219647D01*
G01Y221972D02*
G03X1003305Y219689I2015J-1164D01*
G01X1003349Y223513D02*
G02X1003330Y221972I-1384J-754D01*
G01Y223547D02*
X1003349Y223513D01*
G01X1003305Y223589D02*
X1003330Y223547D01*
G01Y225872D02*
G03X1003305Y223589I2015J-1164D01*
G01X1003540Y226696D02*
G02X1003330Y225872I-1575J-37D01*
G01X1003710Y228047D02*
X1003540Y226696D01*
G01X1003770Y228648D02*
X1003710Y228047D01*
G01X1003980Y229397D02*
G03X1003770Y228648I1365J-787D01*
G01X1004142Y229678D02*
X1003980Y229397D01*
G01X1004818Y230293D02*
X1004142Y229678D01*
G01X1006103Y231128D02*
X1004818Y230293D01*
G01X1006710Y233297D02*
G02X1006103Y231128I-1365J-787D01*
G01X1006644Y233410D02*
X1006710Y233297D01*
G01X1005345Y236409D02*
X1006644Y233410D01*
G01X1000601Y219648D02*
G03Y218074I1364J-787D01*
G01Y221974D02*
G02Y219648I-2015J-1163D01*
G01Y223548D02*
G03Y221974I1364J-787D01*
G01Y225874D02*
G02Y223548I-2015J-1163D01*
G01Y227448D02*
G03Y225874I1364J-787D01*
G01X1001136Y228035D02*
G03X1000601Y227448I1069J-1512D01*
G01X1002852Y229248D02*
X1001136Y228035D01*
G01X1003330Y229772D02*
G02X1002852Y229248I-1430J825D01*
G01X1003466Y230008D02*
X1003330Y229772D01*
G01X1003583Y230484D02*
X1003466Y230008D01*
G01X1003775Y232643D02*
X1003583Y230484D01*
G01X1003980Y233297D02*
G03X1003775Y232643I1365J-787D01*
G01X1004005Y235580D02*
G02X1003980Y233297I-2040J-1119D01*
G01Y235622D02*
X1004005Y235580D01*
G01X1003961Y235656D02*
X1003980Y235622D01*
G01Y237197D02*
G03X1003961Y235656I1365J-787D01*
G01X1004046Y237310D02*
X1003980Y237197D01*
G01X1005345Y240309D02*
X1004046Y237310D01*
G01X1003980Y220022D02*
X1004005Y219980D01*
G01X1003961Y220056D02*
X1003980Y220022D01*
G01Y221597D02*
G03X1003961Y220056I1365J-787D01*
G01X1004005Y223880D02*
G02X1003980Y221597I-2040J-1119D01*
G01Y223922D02*
X1004005Y223880D01*
G01X1003961Y223956D02*
X1003980Y223922D01*
G01Y225497D02*
G03X1003961Y223956I1365J-787D01*
G01X1004546Y226475D02*
X1003980Y225497D01*
G01X1005345Y228610D02*
X1004546Y226475D01*
G01X1003262Y239264D02*
X1001965Y242260D01*
G01X1003349Y239113D02*
X1003262Y239264D01*
G01X1003330Y237572D02*
G03X1003349Y239113I-1365J787D01*
G01X1003305Y235289D02*
G02X1003330Y237572I2040J1119D01*
G01Y235247D02*
X1003305Y235289D01*
G01X1003349Y235213D02*
X1003330Y235247D01*
G01Y233672D02*
G03X1003349Y235213I-1365J787D01*
G01X1003151Y233362D02*
X1003330Y233672D01*
G01X1001389Y232025D02*
X1003151Y233362D01*
G01X1000390Y230566D02*
G02X1001389Y232025I1575J-7D01*
G01X1000172Y228364D02*
X1000390Y230566D01*
G01X1000063Y228063D02*
X1000172Y228364D01*
G01X999950Y227823D02*
G03X1000063Y228063I-1363J788D01*
G01X999925Y227781D02*
X999950Y227823D01*
G01Y225496D02*
G02X999925Y227781I2015J1165D01*
G01X999950Y223922D02*
G03Y225496I-1364J787D01*
G01X999915Y223862D02*
X999950Y223922D01*
G01Y221596D02*
G02X999915Y223862I2015J1164D01*
G01X999950Y220022D02*
G03Y221596I-1364J787D01*
G01X999915Y219962D02*
X999950Y220022D01*
G01X1010090Y219648D02*
G02Y218074I-1365J-787D01*
G01Y221974D02*
G03Y219648I2015J-1163D01*
G01Y223548D02*
G02Y221974I-1365J-787D01*
G01Y225874D02*
G03Y223548I2015J-1163D01*
G01Y227448D02*
G02Y225874I-1365J-787D01*
G01Y229774D02*
G03Y227448I2015J-1163D01*
G01Y231348D02*
G02Y229774I-1365J-787D01*
G01Y233674D02*
G03Y231348I2015J-1163D01*
G01Y235248D02*
G02Y233674I-1365J-787D01*
G01Y237574D02*
G03Y235248I2015J-1163D01*
G01Y239148D02*
G02Y237574I-1365J-787D01*
G01X1010025Y239260D02*
X1010090Y239148D01*
G01X1008725Y242260D02*
X1010025Y239260D01*
G01X1026990Y220022D02*
X1026965Y219980D01*
G01X1027009Y220056D02*
X1026990Y220022D01*
G01Y221597D02*
G02X1027009Y220056I-1365J-787D01*
G01X1026965Y223880D02*
G03X1026990Y221597I2040J-1119D01*
G01Y223922D02*
X1026965Y223880D01*
G01X1027009Y223956D02*
X1026990Y223922D01*
G01Y225497D02*
G02X1027009Y223956I-1365J-787D01*
G01X1026924Y225611D02*
X1026990Y225497D01*
G01X1025625Y228610D02*
X1026924Y225611D01*
G01X989830Y219613D02*
G02X989811Y218072I-1384J-754D01*
G01Y219647D02*
X989830Y219613D01*
G01X989786Y219689D02*
X989811Y219647D01*
G01Y221972D02*
G03X989786Y219689I2015J-1164D01*
G01X989830Y223513D02*
G02X989811Y221972I-1384J-754D01*
G01Y223547D02*
X989830Y223513D01*
G01X989786Y223589D02*
X989811Y223547D01*
G01X989499Y224730D02*
G03X989786Y223589I2327J-21D01*
G01X989499Y225899D02*
Y224730D01*
G01X990061Y226461D02*
X989499Y225899D01*
G01X990061Y228703D02*
Y226461D01*
G01X990515Y229488D02*
X990061Y228703D01*
G01X990530Y231599D02*
G02X990515Y229488I-1865J-1042D01*
G01X990442Y231756D02*
X990530Y231599D01*
G01X990461Y233297D02*
G03X990442Y231756I1365J-787D01*
G01X990527Y233410D02*
X990461Y233297D01*
G01X991826Y236409D02*
X990527Y233410D01*
G01X985066Y245820D02*
Y244209D01*
G01X985456Y246210D02*
X985066Y245820D01*
G01X986040Y246210D02*
X985456D01*
G01X987526Y244724D02*
X986040Y246210D01*
G01X987526Y243744D02*
Y244724D01*
G01X986580Y242798D02*
X987526Y243744D01*
G01X986580Y242076D02*
Y242798D01*
G01X987106Y239189D02*
G03X986580Y242076I-2040J1120D01*
G01X987081Y239147D02*
X987106Y239189D01*
G01X987062Y239113D02*
X987081Y239147D01*
G01Y237572D02*
G02X987062Y239113I1365J787D01*
G01X987106Y235289D02*
G03X987081Y237572I-2040J1119D01*
G01Y235247D02*
X987106Y235289D01*
G01X987062Y235213D02*
X987081Y235247D01*
G01Y233672D02*
G02X987062Y235213I1365J787D01*
G01X987081Y231346D02*
G03Y233672I-2015J1163D01*
G01Y229772D02*
G02Y231346I1365J787D01*
G01X987106Y229730D02*
X987081Y229772D01*
G01X985117Y226284D02*
G03X987106Y229730I-51J2326D01*
G01X985007Y226284D02*
X985117D01*
G01X983701Y225497D02*
G02X985007Y226284I1365J-788D01*
G01X981771Y224335D02*
G03X983701Y225497I-85J2325D01*
G01X981642Y224335D02*
X981771D01*
G01X980321Y221972D02*
G02X981642Y224335I1365J788D01*
G01X980346Y219689D02*
G03X980321Y221972I-2040J1119D01*
G01Y219647D02*
X980346Y219689D01*
G01X980321Y218073D02*
G02Y219647I1365J787D01*
G01X973615Y238360D02*
X974926D01*
G01X973323Y238068D02*
X973615Y238360D01*
G01X973323Y237574D02*
Y238068D01*
G01X973545Y237352D02*
X973323Y237574D01*
G01X973545Y236812D02*
Y237352D01*
G01X973444Y236482D02*
G03X973545Y236812I-498J333D01*
G01X972927Y235650D02*
G02X973444Y236482I13165J-7604D01*
G01X972911Y235622D02*
X972927Y235650D01*
G01X993822Y219613D02*
G03X993841Y218072I1384J-754D01*
G01Y219647D02*
X993822Y219613D01*
G01X993866Y219689D02*
X993841Y219647D01*
G01Y221972D02*
G02X993866Y219689I-2015J-1164D01*
G01X993822Y223513D02*
G03X993841Y221972I1384J-754D01*
G01Y223547D02*
X993822Y223513D01*
G01X993866Y223589D02*
X993841Y223547D01*
G01Y225872D02*
G02X993866Y223589I-2015J-1164D01*
G01X993822Y227413D02*
G03X993841Y225872I1384J-754D01*
G01Y227447D02*
X993822Y227413D01*
G01X993866Y229730D02*
G02X993841Y227447I-2040J-1119D01*
G01Y229772D02*
X993866Y229730D01*
G01X993841Y231346D02*
G03Y229772I1365J-787D01*
G01X994006Y231632D02*
X993841Y231346D01*
G01X995496Y232803D02*
X994006Y231632D01*
G01X996035Y233120D02*
X995496Y232803D01*
G01X996571Y233672D02*
G02X996035Y233120I-1364J789D01*
G01X996637Y233788D02*
X996571Y233672D01*
G01X996800Y234404D02*
G02X996637Y233788I-1246J0D01*
G01X996800Y235801D02*
Y234404D01*
G01X997408Y236409D02*
X996800Y235801D01*
G01X998586Y236409D02*
X997408D01*
G01X1032357Y228540D02*
X1033453Y226009D01*
G01X1032385Y228610D02*
X1032357Y228540D01*
G01X1031020Y220022D02*
X1031045Y219980D01*
G01X1031001Y220056D02*
X1031020Y220022D01*
G01Y221597D02*
G03X1031001Y220056I1365J-787D01*
G01X1031045Y223880D02*
G02X1031020Y221597I-2040J-1119D01*
G01Y223922D02*
X1031045Y223880D01*
G01X1031001Y223956D02*
X1031020Y223922D01*
G01Y225497D02*
G03X1031001Y223956I1365J-787D01*
G01X1031020Y227823D02*
G02Y225497I-2015J-1163D01*
G01X1030809Y228599D02*
G03X1031020Y227823I1576J12D01*
G01X1030809Y232656D02*
Y228599D01*
G01X1029005Y234460D02*
X1030809Y232656D01*
G01X1032385Y236409D02*
X1034334Y233788D01*
G01X987081Y219648D02*
G03Y218074I1365J-787D01*
G01Y221974D02*
G02Y219648I-2015J-1163D01*
G01Y223548D02*
G03Y221974I1365J-787D01*
G01X987393Y224700D02*
G02X987081Y223548I-2327J12D01*
G01X987393Y225093D02*
Y224700D01*
G01X989200Y226900D02*
X987393Y225093D01*
G01X989200Y228712D02*
Y226900D01*
G01X989831Y229807D02*
X989200Y228712D01*
G01X990021Y230520D02*
G02X989831Y229807I-1576J38D01*
G01X990021Y230681D02*
Y230520D01*
G01X990017Y230685D02*
X990021Y230681D01*
G01X989811Y231346D02*
G02X990017Y230685I-1365J-788D01*
G01X989811Y233672D02*
G03Y231346I2015J-1163D01*
G01X989830Y235213D02*
G02X989811Y233672I-1384J-754D01*
G01Y235247D02*
X989830Y235213D01*
G01X989811Y236071D02*
G03Y235247I714J-412D01*
G01X990527Y237310D02*
X989811Y236071D01*
G01X991826Y240309D02*
X990527Y237310D01*
G01X995166Y234454D02*
X995206Y234460D01*
G01X993378Y232048D02*
X995166Y234454D01*
G01X993191Y231722D02*
X993378Y232048D01*
G01X993166Y229439D02*
G02X993191Y231722I2040J1119D01*
G01Y229397D02*
X993166Y229439D01*
G01X993191Y227823D02*
G03Y229397I-1365J787D01*
G01Y225497D02*
G02Y227823I2015J1163D01*
G01X993210Y223956D02*
G03X993191Y225497I-1384J754D01*
G01Y223922D02*
X993210Y223956D01*
G01X993166Y223880D02*
X993191Y223922D01*
G01Y221597D02*
G02X993166Y223880I2015J1164D01*
G01X993210Y220056D02*
G03X993191Y221597I-1384J754D01*
G01Y220022D02*
X993210Y220056D01*
G01X993166Y219980D02*
X993191Y220022D01*
G01X972698Y241550D02*
Y241558D01*
G01X972845Y241210D02*
X972698Y241550D01*
G01X972911Y241097D02*
X972845Y241210D01*
G01X972922Y239517D02*
G03X972911Y241097I-1397J780D01*
G01X972733Y239189D02*
X972922Y239517D01*
G01X971873Y238510D02*
X972733Y239189D01*
G01X996590Y219613D02*
G02X996571Y218072I-1384J-754D01*
G01Y219647D02*
X996590Y219613D01*
G01X996546Y219689D02*
X996571Y219647D01*
G01Y221972D02*
G03X996546Y219689I2015J-1164D01*
G01X996590Y223513D02*
G02X996571Y221972I-1384J-754D01*
G01Y223547D02*
X996590Y223513D01*
G01X996546Y223589D02*
X996571Y223547D01*
G01Y225872D02*
G03X996546Y223589I2015J-1164D01*
G01X996590Y227413D02*
G02X996571Y225872I-1384J-754D01*
G01Y227447D02*
X996590Y227413D01*
G01X996546Y229730D02*
G03X996571Y227447I2040J-1119D01*
G01X996740Y230066D02*
X996546Y229730D01*
G01X996955Y231591D02*
X996740Y230066D01*
G01X997011Y232463D02*
X996955Y231591D01*
G01X998163Y234027D02*
G03X997011Y232463I423J-1518D01*
G01X998636Y234500D02*
X998163Y234027D01*
G01X999500Y234500D02*
X998636D01*
G01X1000500Y235500D02*
X999500Y234500D01*
G01X1000500Y237499D02*
Y235500D01*
G01X998586Y239413D02*
X1000500Y237499D01*
G01X998586Y240309D02*
Y239413D01*
G01X1007425Y227560D02*
X1008725Y230559D01*
G01X1007360Y227448D02*
X1007425Y227560D01*
G01X1007360Y225874D02*
G02Y227448I1365J787D01*
G01Y223548D02*
G03Y225874I-2015J1163D01*
G01Y221974D02*
G02Y223548I1365J787D01*
G01Y219648D02*
G03Y221974I-2015J1163D01*
G01Y218074D02*
G02Y219648I1365J787D01*
G01X976266Y219689D02*
X977056Y218323D01*
G01X976291Y221972D02*
G03X976266Y219689I2015J-1164D01*
G01X976310Y223513D02*
G02X976291Y221972I-1384J-754D01*
G01Y223547D02*
X976310Y223513D01*
G01X976266Y223589D02*
X976291Y223547D01*
G01X978255Y227035D02*
G03X976266Y223589I51J-2326D01*
G01X978350Y227035D02*
X978255D01*
G01X979671Y227823D02*
G02X978350Y227035I-1365J787D01*
G01X981601Y228985D02*
G03X979671Y227823I85J-2325D01*
G01X981757Y228985D02*
X981601D01*
G01X983051Y231346D02*
G02X981757Y228985I-1365J-787D01*
G01X983051Y233672D02*
G03Y231346I2015J-1163D01*
G01X983070Y235213D02*
G02X983051Y233672I-1384J-754D01*
G01X982983Y235364D02*
X983070Y235213D01*
G01X981686Y238360D02*
X982983Y235364D01*
G01X974926Y247961D02*
Y246160D01*
G01X974426Y248461D02*
X974926Y247961D01*
G01X973556Y248461D02*
X974426D01*
G01X973351Y248256D02*
X973556Y248461D01*
G01X973351Y245096D02*
Y248256D01*
G01X973946Y244501D02*
X973351Y245096D01*
G01X973946Y243666D02*
Y244501D01*
G01X973351Y243071D02*
X973946Y243666D01*
G01X973351Y242279D02*
Y243071D01*
G01X974322Y240804D02*
G02X973351Y242279I604J1455D01*
G01X976176Y239318D02*
G03X974322Y240804I-3490J-2454D01*
G01X975500Y236892D02*
G03X976176Y239318I-574J1467D01*
G01X973561Y235246D02*
G02X975500Y236892I3267J-1884D01*
G01X983665Y242153D02*
X981686Y246160D01*
G01X983701Y241097D02*
X983665Y242153D01*
G01X983682Y239556D02*
G02X983701Y241097I1384J754D01*
G01Y239522D02*
X983682Y239556D01*
G01X983726Y239480D02*
X983701Y239522D01*
G01Y237197D02*
G03X983726Y239480I-2015J1164D01*
G01X983682Y235656D02*
G02X983701Y237197I1384J754D01*
G01Y235622D02*
X983682Y235656D01*
G01X983726Y235580D02*
X983701Y235622D01*
G01Y233297D02*
G03X983726Y235580I-2015J1164D01*
G01X983682Y231756D02*
G02X983701Y233297I1384J754D01*
G01Y231722D02*
X983682Y231756D01*
G01X981756Y228234D02*
G03X983701Y231722I-70J2325D01*
G01X981615Y228234D02*
X981756D01*
G01X980321Y227447D02*
G02X981615Y228234I1365J-787D01*
G01X978357Y226284D02*
G03X980321Y227447I-51J2326D01*
G01X978247Y226284D02*
X978357D01*
G01X976922Y223956D02*
G02X978247Y226284I1384J753D01*
G01X976941Y223922D02*
X976922Y223956D01*
G01X976966Y223880D02*
X976941Y223922D01*
G01Y221597D02*
G03X976966Y223880I-2015J1164D01*
G01X976922Y220056D02*
G02X976941Y221597I1384J754D01*
G01X977806Y218522D02*
X976922Y220056D01*
G01X1000013Y231832D02*
X1001965Y234460D01*
G01X999950Y231722D02*
X1000013Y231832D01*
G01X999408Y231166D02*
G03X999950Y231722I-822J1343D01*
G01X998421Y230516D02*
X999408Y231166D01*
G01X997383Y229678D02*
X998421Y230516D01*
G01X997221Y229397D02*
X997383Y229678D01*
G01X997221Y227823D02*
G02Y229397I1365J787D01*
G01Y225497D02*
G03Y227823I-2015J1163D01*
G01X997202Y223956D02*
G02X997221Y225497I1384J754D01*
G01Y223922D02*
X997202Y223956D01*
G01X997246Y223880D02*
X997221Y223922D01*
G01Y221597D02*
G03X997246Y223880I-2015J1164D01*
G01X997202Y220056D02*
G02X997221Y221597I1384J754D01*
G01Y220022D02*
X997202Y220056D01*
G01X997246Y219980D02*
X997221Y220022D01*
G01X973385Y341329D02*
X972196Y340140D01*
G01X977656D02*
X976467Y341329D01*
G01X979847Y340140D02*
X977656D01*
G01X981036Y341329D02*
X979847Y340140D01*
G01X984416D02*
X983227Y341329D01*
G01X986607Y340140D02*
X984416D01*
G01X987796Y341329D02*
X986607Y340140D01*
G01X991176D02*
X989987Y341329D01*
G01X993367Y340140D02*
X991176D01*
G01X994556Y341329D02*
X993367Y340140D01*
G01X997936D02*
X996747Y341329D01*
G01X1000003Y340140D02*
X997936D01*
G01X1001198Y341335D02*
X1000003Y340140D01*
G01X974276Y338191D02*
X973077Y339390D01*
G01X975970Y338191D02*
X974276D01*
G01X977157Y339378D02*
X975970Y338191D01*
G01X979725Y339378D02*
X977157D01*
G01X980912Y338191D02*
X979725Y339378D01*
G01X982460Y338191D02*
X980912D01*
G01X983647Y339378D02*
X982460Y338191D01*
G01X986609Y339378D02*
X983647D01*
G01X987796Y338191D02*
X986609Y339378D01*
G01X989989Y338191D02*
X987796D01*
G01X991176Y339378D02*
X989989Y338191D01*
G01X993369Y339378D02*
X991176D01*
G01X994556Y338191D02*
X993369Y339378D01*
G01X996186Y338191D02*
X994556D01*
G01X997373Y339378D02*
X996186Y338191D01*
G01X999678Y339378D02*
X997373D01*
G01X1000865Y338191D02*
X999678Y339378D01*
G01X1003236Y338191D02*
X1000865D01*
G01X1004919Y339874D02*
X1003236Y338191D01*
G01X1005885Y339874D02*
X1004919D01*
G01X1008096Y342085D02*
X1005885Y339874D01*
G01X977386Y399459D02*
Y405869D01*
G01X980117Y396728D02*
X977386Y399459D01*
G01X980117Y396729D02*
Y396728D01*
G01X980336Y396510D02*
X980117Y396729D01*
G01X980336Y380099D02*
Y396510D01*
G01X979857Y379620D02*
X980336Y380099D01*
G01X979857Y378774D02*
Y379620D01*
G01X980321Y377972D02*
X979857Y378774D01*
G01X980346Y375689D02*
G03X980321Y377972I-2040J1119D01*
G01Y375647D02*
X980346Y375689D01*
G01X980302Y375613D02*
X980321Y375647D01*
G01Y374072D02*
G02X980302Y375613I1365J787D01*
G01X980321Y371746D02*
G03Y374072I-2015J1163D01*
G01X981615Y369385D02*
G02X980321Y371746I71J1574D01*
G01X981771Y369385D02*
X981615D01*
G01X983701Y365897D02*
G03X981771Y369385I-2015J1163D01*
G01X983682Y364356D02*
G02X983701Y365897I1384J754D01*
G01Y364322D02*
X983682Y364356D01*
G01X983726Y364280D02*
X983701Y364322D01*
G01Y361997D02*
G03X983726Y364280I-2015J1164D01*
G01X981686Y359260D02*
G03X983701Y361997I-11295J10426D01*
G01X972911Y360422D02*
X972930Y360456D01*
G01X972886Y360380D02*
X972911Y360422D01*
G01Y358097D02*
G02X972886Y360380I2015J1164D01*
G01X972930Y356556D02*
G03X972911Y358097I-1384J754D01*
G01Y356522D02*
X972930Y356556D01*
G01X972886Y356480D02*
X972911Y356522D01*
G01Y354197D02*
G02X972886Y356480I2015J1164D01*
G01X972977Y354081D02*
X972911Y354197D01*
G01X974926Y351460D02*
X972977Y354081D01*
G01X987400Y398800D02*
Y399687D01*
G01X989100Y397100D02*
X987400Y398800D01*
G01X989100Y390600D02*
Y397100D01*
G01X989300Y390400D02*
X989100Y390600D01*
G01X989300Y387957D02*
Y390400D01*
G01X989479Y387778D02*
X989300Y387957D01*
G01X989811Y387347D02*
G03X989479Y387778I-1630J-912D01*
G01X989830Y387313D02*
X989811Y387347D01*
G01Y385772D02*
G03X989830Y387313I-1365J787D01*
G01X989786Y383489D02*
G02X989811Y385772I2040J1119D01*
G01Y383447D02*
X989786Y383489D01*
G01X989830Y383413D02*
X989811Y383447D01*
G01Y381872D02*
G03X989830Y383413I-1365J787D01*
G01X989786Y379589D02*
G02X989811Y381872I2040J1119D01*
G01Y379547D02*
X989786Y379589D01*
G01X989830Y379513D02*
X989811Y379547D01*
G01Y377972D02*
G03X989830Y379513I-1365J787D01*
G01X989786Y375689D02*
G02X989811Y377972I2040J1119D01*
G01Y375647D02*
X989786Y375689D01*
G01X989830Y375613D02*
X989811Y375647D01*
G01Y374072D02*
G03X989830Y375613I-1365J787D01*
G01X989811Y371746D02*
G02Y374072I2015J1163D01*
G01Y370172D02*
G03Y371746I-1365J787D01*
G01X989786Y370130D02*
X989811Y370172D01*
G01Y367847D02*
G02X989786Y370130I2015J1164D01*
G01X989830Y367813D02*
X989811Y367847D01*
G01Y366272D02*
G03X989830Y367813I-1365J787D01*
G01X989786Y363989D02*
G02X989811Y366272I2040J1119D01*
G01Y363947D02*
X989786Y363989D01*
G01X989830Y363913D02*
X989811Y363947D01*
G01Y362372D02*
G03X989830Y363913I-1365J787D01*
G01X989554Y361710D02*
G02X989811Y362372I2272J-501D01*
G01X989554Y360946D02*
Y361710D01*
G01X991826Y358674D02*
X989554Y360946D01*
G01X991826Y357309D02*
Y358674D01*
G01X1010516Y358951D02*
X1008725Y355360D01*
G01X1010516Y365060D02*
Y358951D01*
G01X1010740Y365897D02*
G03X1010516Y365060I1453J-837D01*
G01X1010740Y368223D02*
G02Y365897I-2015J-1163D01*
G01Y369797D02*
G03Y368223I1365J-787D01*
G01X1010765Y369839D02*
X1010740Y369797D01*
G01Y372122D02*
G02X1010765Y369839I-2015J-1164D01*
G01X1010721Y372156D02*
X1010740Y372122D01*
G01Y373697D02*
G03X1010721Y372156I1365J-787D01*
G01X1010765Y375980D02*
G02X1010740Y373697I-2040J-1119D01*
G01Y376022D02*
X1010765Y375980D01*
G01X1010721Y376056D02*
X1010740Y376022D01*
G01Y377597D02*
G03X1010721Y376056I1365J-787D01*
G01X1010765Y379880D02*
G02X1010740Y377597I-2040J-1119D01*
G01Y379922D02*
X1010765Y379880D01*
G01X1010721Y379956D02*
X1010740Y379922D01*
G01Y381497D02*
G03X1010721Y379956I1365J-787D01*
G01X1010765Y383780D02*
G02X1010740Y381497I-2040J-1119D01*
G01Y383822D02*
X1010765Y383780D01*
G01X1010721Y383856D02*
X1010740Y383822D01*
G01Y385397D02*
G03X1010721Y383856I1365J-787D01*
G01X1010765Y387680D02*
G02X1010740Y385397I-2040J-1119D01*
G01Y387722D02*
X1010765Y387680D01*
G01X1010526Y388115D02*
X1010740Y387722D01*
G01X1010526Y399125D02*
Y388115D01*
G01X1012140Y400739D02*
X1010526Y399125D01*
G01X1012140Y401713D02*
Y400739D01*
G01X982404Y401451D02*
Y405787D01*
G01X983436Y400419D02*
X982404Y401451D01*
G01X983436Y380396D02*
Y400419D01*
G01X983726Y379880D02*
X983436Y380396D01*
G01X983701Y377597D02*
G03X983726Y379880I-2015J1164D01*
G01X983682Y376056D02*
G02X983701Y377597I1384J754D01*
G01Y376022D02*
X983682Y376056D01*
G01X983726Y375980D02*
X983701Y376022D01*
G01Y373697D02*
G03X983726Y375980I-2015J1164D01*
G01X984995Y371335D02*
G02X983701Y373697I71J1574D01*
G01X985136Y371335D02*
X984995D01*
G01X987081Y367847D02*
G03X985136Y371335I-2015J1163D01*
G01X987062Y367813D02*
X987081Y367847D01*
G01Y366272D02*
G02X987062Y367813I1365J787D01*
G01X987106Y363989D02*
G03X987081Y366272I-2040J1119D01*
G01Y363947D02*
X987106Y363989D01*
G01X987062Y363913D02*
X987081Y363947D01*
G01Y362372D02*
G02X987062Y363913I1365J787D01*
G01X987106Y360089D02*
G03X987081Y362372I-2040J1119D01*
G01Y360047D02*
X987106Y360089D01*
G01X987015Y359931D02*
X987081Y360047D01*
G01X986870Y359736D02*
X987015Y359931D01*
G01X986870Y358315D02*
Y359736D01*
G01X986162Y357607D02*
X986870Y358315D01*
G01X985364Y357607D02*
X986162D01*
G01X985066Y357309D02*
X985364Y357607D01*
G01X1006645Y372010D02*
X1005345Y369010D01*
G01X1006729Y372156D02*
X1006645Y372010D01*
G01X1006710Y373697D02*
G02X1006729Y372156I-1365J-787D01*
G01X1006685Y375980D02*
G03X1006710Y373697I2040J-1119D01*
G01Y376022D02*
X1006685Y375980D01*
G01X1006729Y376056D02*
X1006710Y376022D01*
G01Y377597D02*
G02X1006729Y376056I-1365J-787D01*
G01X1006685Y379880D02*
G03X1006710Y377597I2040J-1119D01*
G01Y379922D02*
X1006685Y379880D01*
G01X1006729Y379956D02*
X1006710Y379922D01*
G01Y381497D02*
G02X1006729Y379956I-1365J-787D01*
G01X1006685Y383780D02*
G03X1006710Y381497I2040J-1119D01*
G01Y383822D02*
X1006685Y383780D01*
G01X1006729Y383856D02*
X1006710Y383822D01*
G01Y385397D02*
G02X1006729Y383856I-1365J-787D01*
G01X1006685Y387680D02*
G03X1006710Y385397I2040J-1119D01*
G01Y387722D02*
X1006685Y387680D01*
G01X1006921Y388501D02*
G02X1006710Y387722I-1576J9D01*
G01X1006921Y391495D02*
Y388501D01*
G01X1006926Y391500D02*
X1006921Y391495D01*
G01X1006926Y394460D02*
Y391500D01*
G01X1005800Y395586D02*
X1006926Y394460D01*
G01X1005800Y403300D02*
Y395586D01*
G01X1033006Y396070D02*
X1036800Y399864D01*
G01X1033006Y391906D02*
Y396070D01*
G01X1033000Y391900D02*
X1033006Y391906D01*
G01X1033750Y389297D02*
G02X1033000Y391900I4887J2818D01*
G01X1032385Y369010D02*
X1033685Y372010D01*
G01X1032429Y355734D02*
G03X1033750Y356522I-44J1575D01*
G01X1032300Y355734D02*
X1032429D01*
G01X1030370Y354572D02*
G02X1032300Y355734I2015J-1163D01*
G01X1029064Y353785D02*
G03X1030370Y354572I-59J1575D01*
G01X1028946Y353785D02*
X1029064D01*
G01X1027640Y354572D02*
G03X1028946Y353785I1365J788D01*
G01X1025710Y355734D02*
G02X1027640Y354572I-85J-2325D01*
G01X1025540Y355734D02*
X1025710D01*
G01X1023610Y354572D02*
G02X1025540Y355734I2015J-1163D01*
G01X1020880Y354572D02*
G03X1023610I1365J788D01*
G01X1018950Y355734D02*
G02X1020880Y354572I-85J-2325D01*
G01X1018780Y355734D02*
X1018950D01*
G01X1016850Y354572D02*
G02X1018780Y355734I2015J-1163D01*
G01X1015544Y353785D02*
G03X1016850Y354572I-59J1575D01*
G01X1015415Y353785D02*
X1015544D01*
G01X1013470Y352622D02*
G02X1015415Y353785I2015J-1162D01*
G01X1012149Y351834D02*
G03X1013470Y352622I-44J1575D01*
G01X1012020Y351834D02*
X1012149D01*
G01X1010090Y350672D02*
G02X1012020Y351834I2015J-1163D01*
G01X1008784Y349885D02*
G03X1010090Y350672I-59J1575D01*
G01X1008655Y349885D02*
X1008784D01*
G01X1006710Y348722D02*
G02X1008655Y349885I2015J-1162D01*
G01X1005389Y347934D02*
G03X1006710Y348722I-44J1575D01*
G01X1005260Y347934D02*
X1005389D01*
G01X1003330Y346772D02*
G02X1005260Y347934I2015J-1163D01*
G01X1002024Y345985D02*
G03X1003330Y346772I-59J1575D01*
G01X1001017Y345985D02*
X1002024D01*
G01X999824Y347178D02*
X1001017Y345985D01*
G01X997043Y347178D02*
X999824D01*
G01X995856Y345991D02*
X997043Y347178D01*
G01X994556Y345991D02*
X995856D01*
G01X993369Y347178D02*
X994556Y345991D01*
G01X990283Y347178D02*
X993369D01*
G01X989096Y345991D02*
X990283Y347178D01*
G01X987796Y345991D02*
X989096D01*
G01X986609Y347178D02*
X987796Y345991D01*
G01X983646Y347178D02*
X986609D01*
G01X982459Y345991D02*
X983646Y347178D01*
G01X981036Y345991D02*
X982459D01*
G01X979849Y347178D02*
X981036Y345991D01*
G01X976886Y347178D02*
X979849D01*
G01X975699Y345991D02*
X976886Y347178D01*
G01X974276Y345991D02*
X975699D01*
G01X972328Y347939D02*
X974276Y345991D01*
G01X991400Y398900D02*
Y399889D01*
G01X993300Y397000D02*
X991400Y398900D01*
G01X993300Y392100D02*
Y397000D01*
G01X993081Y391571D02*
G02X993300Y392100I748J0D01*
G01X993081Y391409D02*
Y391571D01*
G01X993191Y389297D02*
G02X993081Y391409I2015J1164D01*
G01X993210Y387756D02*
G03X993191Y389297I-1384J754D01*
G01Y387722D02*
X993210Y387756D01*
G01X993166Y387680D02*
X993191Y387722D01*
G01Y385397D02*
G02X993166Y387680I2015J1164D01*
G01X993210Y383856D02*
G03X993191Y385397I-1384J754D01*
G01Y383822D02*
X993210Y383856D01*
G01X993166Y383780D02*
X993191Y383822D01*
G01Y381497D02*
G02X993166Y383780I2015J1164D01*
G01X993210Y379956D02*
G03X993191Y381497I-1384J754D01*
G01Y379922D02*
X993210Y379956D01*
G01X993166Y379880D02*
X993191Y379922D01*
G01Y377597D02*
G02X993166Y379880I2015J1164D01*
G01X993210Y376056D02*
G03X993191Y377597I-1384J754D01*
G01Y376022D02*
X993210Y376056D01*
G01X993166Y375980D02*
X993191Y376022D01*
G01Y373697D02*
G02X993166Y375980I2015J1164D01*
G01X993210Y372156D02*
G03X993191Y373697I-1384J754D01*
G01Y372122D02*
X993210Y372156D01*
G01X992300Y370800D02*
G03X993191Y372122I-7456J5987D01*
G01X991826Y369010D02*
G02X992300Y370800I2254J361D01*
G01X974276Y342091D02*
X973077Y343290D01*
G01X975700Y342091D02*
X974276D01*
G01X976887Y343278D02*
X975700Y342091D01*
G01X978956Y343278D02*
X976887D01*
G01X980143Y342091D02*
X978956Y343278D01*
G01X983229Y342091D02*
X980143D01*
G01X984416Y343278D02*
X983229Y342091D01*
G01X986341Y343278D02*
X984416D01*
G01X987528Y342091D02*
X986341Y343278D01*
G01X989219Y342091D02*
X987528D01*
G01X990406Y343278D02*
X989219Y342091D01*
G01X993369Y343278D02*
X990406D01*
G01X994556Y342091D02*
X993369Y343278D01*
G01X995980Y342091D02*
X994556D01*
G01X997167Y343278D02*
X995980Y342091D01*
G01X1000128Y343278D02*
X997167D01*
G01X1001321Y342085D02*
X1000128Y343278D01*
G01X1002024Y342085D02*
X1001321D01*
G01X1003330Y342872D02*
G02X1002024Y342085I-1365J788D01*
G01X1005260Y344034D02*
G03X1003330Y342872I85J-2325D01*
G01X1005389Y344034D02*
X1005260D01*
G01X1006710Y344822D02*
G02X1005389Y344034I-1365J787D01*
G01X1008655Y345985D02*
G03X1006710Y344822I70J-2325D01*
G01X1008784Y345985D02*
X1008655D01*
G01X1010090Y346772D02*
G02X1008784Y345985I-1365J788D01*
G01X1012020Y347934D02*
G03X1010090Y346772I85J-2325D01*
G01X1012149Y347934D02*
X1012020D01*
G01X1013470Y348722D02*
G02X1012149Y347934I-1365J787D01*
G01X1015415Y349885D02*
G03X1013470Y348722I70J-2325D01*
G01X1015544Y349885D02*
X1015415D01*
G01X1016850Y350672D02*
G02X1015544Y349885I-1365J788D01*
G01X1018780Y351834D02*
G03X1016850Y350672I85J-2325D01*
G01X1018950Y351834D02*
X1018780D01*
G01X1020880Y350672D02*
G03X1018950Y351834I-2015J-1163D01*
G01X1022186Y349885D02*
G02X1020880Y350672I59J1575D01*
G01X1022304Y349885D02*
X1022186D01*
G01X1023610Y350672D02*
G02X1022304Y349885I-1365J788D01*
G01X1025540Y351834D02*
G03X1023610Y350672I85J-2325D01*
G01X1025710Y351834D02*
X1025540D01*
G01X1027640Y350672D02*
G03X1025710Y351834I-2015J-1163D01*
G01X1028946Y349885D02*
G02X1027640Y350672I59J1575D01*
G01X1029064Y349885D02*
X1028946D01*
G01X1030370Y350672D02*
G02X1029064Y349885I-1365J788D01*
G01X1032300Y351834D02*
G03X1030370Y350672I85J-2325D01*
G01X1032429Y351834D02*
X1032300D01*
G01X1033750Y352622D02*
G02X1032429Y351834I-1365J787D01*
G01X1007294Y363831D02*
X1005345Y361209D01*
G01X1007360Y363947D02*
X1007294Y363831D01*
G01X1007385Y363989D02*
X1007360Y363947D01*
G01Y366272D02*
G02X1007385Y363989I-2015J-1164D01*
G01X1007341Y367813D02*
G03X1007360Y366272I1384J-754D01*
G01Y367847D02*
X1007341Y367813D01*
G01X1007385Y370130D02*
G02X1007360Y367847I-2040J-1119D01*
G01Y370172D02*
X1007385Y370130D01*
G01X1007360Y371746D02*
G03Y370172I1365J-787D01*
G01Y374072D02*
G02Y371746I-2015J-1163D01*
G01X1007341Y375613D02*
G03X1007360Y374072I1384J-754D01*
G01Y375647D02*
X1007341Y375613D01*
G01X1007385Y375689D02*
X1007360Y375647D01*
G01Y377972D02*
G02X1007385Y375689I-2015J-1164D01*
G01X1007341Y379513D02*
G03X1007360Y377972I1384J-754D01*
G01Y379547D02*
X1007341Y379513D01*
G01X1007385Y379589D02*
X1007360Y379547D01*
G01Y381872D02*
G02X1007385Y379589I-2015J-1164D01*
G01X1007341Y383413D02*
G03X1007360Y381872I1384J-754D01*
G01Y383447D02*
X1007341Y383413D01*
G01X1007385Y383489D02*
X1007360Y383447D01*
G01Y385772D02*
G02X1007385Y383489I-2015J-1164D01*
G01X1007341Y387313D02*
G03X1007360Y385772I1384J-754D01*
G01Y387347D02*
X1007341Y387313D01*
G01X1008126Y390209D02*
G02X1007360Y387347I-5729J0D01*
G01X1008126Y400826D02*
Y390209D01*
G01X1009300Y402000D02*
X1008126Y400826D01*
G01X1009300Y403348D02*
Y402000D01*
G01X1004500Y394104D02*
Y403728D01*
G01X1003726Y393330D02*
X1004500Y394104D01*
G01X1003726Y388694D02*
Y393330D01*
G01X1004005Y387680D02*
G02X1003726Y388694I1703J1014D01*
G01X1003980Y385397D02*
G03X1004005Y387680I-2015J1164D01*
G01X1003961Y383856D02*
G02X1003980Y385397I1384J754D01*
G01Y383822D02*
X1003961Y383856D01*
G01X1004005Y383780D02*
X1003980Y383822D01*
G01Y381497D02*
G03X1004005Y383780I-2015J1164D01*
G01X1003961Y379956D02*
G02X1003980Y381497I1384J754D01*
G01Y379922D02*
X1003961Y379956D01*
G01X1004005Y379880D02*
X1003980Y379922D01*
G01Y377597D02*
G03X1004005Y379880I-2015J1164D01*
G01X1003961Y376056D02*
G02X1003980Y377597I1384J754D01*
G01Y376022D02*
X1003961Y376056D01*
G01X1004005Y375980D02*
X1003980Y376022D01*
G01Y373697D02*
G03X1004005Y375980I-2015J1164D01*
G01X1003961Y372156D02*
G02X1003980Y373697I1384J754D01*
G01Y372122D02*
X1003961Y372156D01*
G01X1004005Y369839D02*
G03X1003980Y372122I-2040J1119D01*
G01Y369797D02*
X1004005Y369839D01*
G01X1003980Y368223D02*
G02Y369797I1365J787D01*
G01Y365897D02*
G03Y368223I-2015J1163D01*
G01X1003961Y364356D02*
G02X1003980Y365897I1384J754D01*
G01Y364322D02*
X1003961Y364356D01*
G01X1004005Y364280D02*
X1003980Y364322D01*
G01Y361997D02*
G03X1004005Y364280I-2015J1164D01*
G01X1003961Y360456D02*
G02X1003980Y361997I1384J754D01*
G01X1004048Y360305D02*
X1003961Y360456D01*
G01X1005345Y357309D02*
X1004048Y360305D01*
G01X989400Y398654D02*
Y399607D01*
G01X989900Y398154D02*
X989400Y398654D01*
G01X989900Y390900D02*
Y398154D01*
G01X990153Y390647D02*
X989900Y390900D01*
G01X990153Y388797D02*
Y390647D01*
G01X990461Y387722D02*
G02X990153Y388797I1886J1122D01*
G01X990486Y387680D02*
X990461Y387722D01*
G01Y385397D02*
G03X990486Y387680I-2015J1164D01*
G01X990442Y383856D02*
G02X990461Y385397I1384J754D01*
G01Y383822D02*
X990442Y383856D01*
G01X990486Y383780D02*
X990461Y383822D01*
G01Y381497D02*
G03X990486Y383780I-2015J1164D01*
G01X990442Y379956D02*
G02X990461Y381497I1384J754D01*
G01Y379922D02*
X990442Y379956D01*
G01X990486Y379880D02*
X990461Y379922D01*
G01Y377597D02*
G03X990486Y379880I-2015J1164D01*
G01X990442Y376056D02*
G02X990461Y377597I1384J754D01*
G01Y376022D02*
X990442Y376056D01*
G01X990486Y375980D02*
X990461Y376022D01*
G01Y373697D02*
G03X990486Y375980I-2015J1164D01*
G01X990442Y372156D02*
G02X990461Y373697I1384J754D01*
G01Y372122D02*
X990442Y372156D01*
G01X990486Y369839D02*
G03X990461Y372122I-2040J1119D01*
G01Y369797D02*
X990486Y369839D01*
G01X990461Y368223D02*
G02Y369797I1365J787D01*
G01Y365897D02*
G03Y368223I-2015J1163D01*
G01X990442Y364356D02*
G02X990461Y365897I1384J754D01*
G01X990529Y364205D02*
X990442Y364356D01*
G01X991826Y361209D02*
X990529Y364205D01*
G01X976467Y341329D02*
X973385D01*
G01X983227D02*
X981036D01*
G01X989987D02*
X987796D01*
G01X996747D02*
X994556D01*
G01X1002050Y341335D02*
X1001198D01*
G01X1003980Y342497D02*
G02X1002050Y341335I-2015J1163D01*
G01X1005286Y343284D02*
G03X1003980Y342497I59J-1575D01*
G01X1005415Y343284D02*
X1005286D01*
G01X1007360Y344447D02*
G02X1005415Y343284I-2015J1162D01*
G01X1008681Y345235D02*
G03X1007360Y344447I44J-1575D01*
G01X1008810Y345235D02*
X1008681D01*
G01X1010740Y346397D02*
G02X1008810Y345235I-2015J1163D01*
G01X1012046Y347184D02*
G03X1010740Y346397I59J-1575D01*
G01X1012175Y347184D02*
X1012046D01*
G01X1014120Y348347D02*
G02X1012175Y347184I-2015J1162D01*
G01X1015441Y349135D02*
G03X1014120Y348347I44J-1575D01*
G01X1015570Y349135D02*
X1015441D01*
G01X1017500Y350297D02*
G02X1015570Y349135I-2015J1163D01*
G01X1018806Y351084D02*
G03X1017500Y350297I59J-1575D01*
G01X1018924Y351084D02*
X1018806D01*
G01X1020230Y350297D02*
G03X1018924Y351084I-1365J-788D01*
G01X1022160Y349135D02*
G02X1020230Y350297I85J2325D01*
G01X1022330Y349135D02*
X1022160D01*
G01X1024260Y350297D02*
G02X1022330Y349135I-2015J1163D01*
G01X1025566Y351084D02*
G03X1024260Y350297I59J-1575D01*
G01X1025684Y351084D02*
X1025566D01*
G01X1026990Y350297D02*
G03X1025684Y351084I-1365J-788D01*
G01X1028920Y349135D02*
G02X1026990Y350297I85J2325D01*
G01X1029090Y349135D02*
X1028920D01*
G01X1031020Y350297D02*
G02X1029090Y349135I-2015J1163D01*
G01X1032326Y351084D02*
G03X1031020Y350297I59J-1575D01*
G01X1032455Y351084D02*
X1032326D01*
G01X1034400Y352247D02*
G02X1032455Y351084I-2015J1162D01*
G01X996314Y357811D02*
X995206Y355360D01*
G01X996571Y358472D02*
G03X996314Y357811I2015J-1164D01*
G01X996590Y360013D02*
G02X996571Y358472I-1384J-754D01*
G01Y360047D02*
X996590Y360013D01*
G01X996546Y360089D02*
X996571Y360047D01*
G01Y362372D02*
G03X996546Y360089I2015J-1164D01*
G01X996590Y363913D02*
G02X996571Y362372I-1384J-754D01*
G01Y363947D02*
X996590Y363913D01*
G01X996546Y363989D02*
X996571Y363947D01*
G01Y366272D02*
G03X996546Y363989I2015J-1164D01*
G01X996590Y367813D02*
G02X996571Y366272I-1384J-754D01*
G01Y367847D02*
X996590Y367813D01*
G01X996546Y370130D02*
G03X996571Y367847I2040J-1119D01*
G01Y370172D02*
X996546Y370130D01*
G01X996571Y371746D02*
G02Y370172I-1365J-787D01*
G01Y374072D02*
G03Y371746I2015J-1163D01*
G01X996590Y375613D02*
G02X996571Y374072I-1384J-754D01*
G01Y375647D02*
X996590Y375613D01*
G01X996546Y375689D02*
X996571Y375647D01*
G01Y377972D02*
G03X996546Y375689I2015J-1164D01*
G01X996590Y379513D02*
G02X996571Y377972I-1384J-754D01*
G01Y379547D02*
X996590Y379513D01*
G01X996546Y379589D02*
X996571Y379547D01*
G01Y381872D02*
G03X996546Y379589I2015J-1164D01*
G01X996590Y383413D02*
G02X996571Y381872I-1384J-754D01*
G01Y383447D02*
X996590Y383413D01*
G01X996546Y383489D02*
X996571Y383447D01*
G01Y385772D02*
G03X996546Y383489I2015J-1164D01*
G01X996590Y387313D02*
G02X996571Y385772I-1384J-754D01*
G01Y387347D02*
X996590Y387313D01*
G01X996546Y387389D02*
X996571Y387347D01*
G01Y389672D02*
G03X996546Y387389I2015J-1164D01*
G01X996590Y391213D02*
G02X996571Y389672I-1384J-754D01*
G01X995400Y393264D02*
X996590Y391213D01*
G01X995400Y398948D02*
Y393264D01*
G01X1010140Y400840D02*
Y404760D01*
G01X1009326Y400026D02*
X1010140Y400840D01*
G01X1009326Y388703D02*
Y400026D01*
G01X1009340Y388689D02*
X1009326Y388703D01*
G01X1010109Y387313D02*
X1009340Y388689D01*
G01X1010090Y385772D02*
G03X1010109Y387313I-1365J787D01*
G01X1010065Y383489D02*
G02X1010090Y385772I2040J1119D01*
G01Y383447D02*
X1010065Y383489D01*
G01X1010109Y383413D02*
X1010090Y383447D01*
G01Y381872D02*
G03X1010109Y383413I-1365J787D01*
G01X1010065Y379589D02*
G02X1010090Y381872I2040J1119D01*
G01Y379547D02*
X1010065Y379589D01*
G01X1010109Y379513D02*
X1010090Y379547D01*
G01Y377972D02*
G03X1010109Y379513I-1365J787D01*
G01X1010065Y375689D02*
G02X1010090Y377972I2040J1119D01*
G01Y375647D02*
X1010065Y375689D01*
G01X1010109Y375613D02*
X1010090Y375647D01*
G01Y374072D02*
G03X1010109Y375613I-1365J787D01*
G01X1010090Y371746D02*
G02Y374072I2015J1163D01*
G01Y370172D02*
G03Y371746I-1365J787D01*
G01X1010065Y370130D02*
X1010090Y370172D01*
G01Y367847D02*
G02X1010065Y370130I2015J1164D01*
G01X1010109Y367813D02*
X1010090Y367847D01*
G01Y366272D02*
G03X1010109Y367813I-1365J787D01*
G01X1010024Y366159D02*
X1010090Y366272D01*
G01X1008725Y363160D02*
X1010024Y366159D01*
G01X993400Y398760D02*
Y399647D01*
G01X994200Y397960D02*
X993400Y398760D01*
G01X994200Y391881D02*
Y397960D01*
G01X993822Y391213D02*
X994200Y391881D01*
G01X993841Y389672D02*
G02X993822Y391213I1365J787D01*
G01X993866Y387389D02*
G03X993841Y389672I-2040J1119D01*
G01Y387347D02*
X993866Y387389D01*
G01X993822Y387313D02*
X993841Y387347D01*
G01Y385772D02*
G02X993822Y387313I1365J787D01*
G01X993866Y383489D02*
G03X993841Y385772I-2040J1119D01*
G01Y383447D02*
X993866Y383489D01*
G01X993822Y383413D02*
X993841Y383447D01*
G01Y381872D02*
G02X993822Y383413I1365J787D01*
G01X993866Y379589D02*
G03X993841Y381872I-2040J1119D01*
G01Y379547D02*
X993866Y379589D01*
G01X993822Y379513D02*
X993841Y379547D01*
G01Y377972D02*
G02X993822Y379513I1365J787D01*
G01X993866Y375689D02*
G03X993841Y377972I-2040J1119D01*
G01Y375647D02*
X993866Y375689D01*
G01X993822Y375613D02*
X993841Y375647D01*
G01Y374072D02*
G02X993822Y375613I1365J787D01*
G01X993841Y371746D02*
G03Y374072I-2015J1163D01*
G01Y370172D02*
G02Y371746I1365J787D01*
G01X993866Y370130D02*
X993841Y370172D01*
G01Y367847D02*
G03X993866Y370130I-2015J1164D01*
G01X993500Y367506D02*
X993841Y367847D01*
G01X993500Y364866D02*
Y367506D01*
G01X995206Y363160D02*
X993500Y364866D01*
G01X1029476Y401770D02*
Y403624D01*
G01X1027200Y399494D02*
X1029476Y401770D01*
G01X1027200Y392407D02*
Y399494D01*
G01X1026990Y391623D02*
G03X1027200Y392407I-1358J784D01*
G01X1026990Y389297D02*
G02Y391623I2015J1163D01*
G01X1027009Y387756D02*
G03X1026990Y389297I-1384J754D01*
G01Y387722D02*
X1027009Y387756D01*
G01X1026965Y387680D02*
X1026990Y387722D01*
G01Y385397D02*
G02X1026965Y387680I2015J1164D01*
G01X1027009Y383856D02*
G03X1026990Y385397I-1384J754D01*
G01Y383822D02*
X1027009Y383856D01*
G01X1026965Y383780D02*
X1026990Y383822D01*
G01Y381497D02*
G02X1026965Y383780I2015J1164D01*
G01X1027009Y379956D02*
G03X1026990Y381497I-1384J754D01*
G01Y379922D02*
X1027009Y379956D01*
G01X1026965Y379880D02*
X1026990Y379922D01*
G01Y377597D02*
G02X1026965Y379880I2015J1164D01*
G01X1027009Y376056D02*
G03X1026990Y377597I-1384J754D01*
G01Y376022D02*
X1027009Y376056D01*
G01X1026965Y375980D02*
X1026990Y376022D01*
G01Y373697D02*
G02X1026965Y375980I2015J1164D01*
G01X1027009Y372156D02*
G03X1026990Y373697I-1384J754D01*
G01X1026925Y372010D02*
X1027009Y372156D01*
G01X1025625Y369010D02*
X1026925Y372010D01*
G01X1032385Y362685D02*
X1034213Y364513D01*
G01X1032385Y361209D02*
Y362685D01*
G01X1000390Y354245D02*
X1001965Y351460D01*
G01X1000390Y363179D02*
Y354245D01*
G01X1000601Y363947D02*
G03X1000390Y363179I1364J-788D01*
G01X1000636Y364007D02*
X1000601Y363947D01*
G01Y366273D02*
G02X1000636Y364007I-2015J-1164D01*
G01X1000601Y367847D02*
G03Y366273I1364J-787D01*
G01X1000626Y370130D02*
G02X1000601Y367847I-2040J-1119D01*
G01Y370172D02*
X1000626Y370130D01*
G01X1000601Y371746D02*
G03Y370172I1364J-787D01*
G01X1000626Y371788D02*
X1000601Y371746D01*
G01Y374073D02*
G02X1000626Y371788I-2015J-1165D01*
G01X1000601Y375647D02*
G03Y374073I1364J-787D01*
G01X1000636Y375707D02*
X1000601Y375647D01*
G01Y377973D02*
G02X1000636Y375707I-2015J-1164D01*
G01X1000601Y379547D02*
G03Y377973I1364J-787D01*
G01X1000636Y379607D02*
X1000601Y379547D01*
G01Y381873D02*
G02X1000636Y379607I-2015J-1164D01*
G01X1000601Y383447D02*
G03Y381873I1364J-787D01*
G01X1000636Y383507D02*
X1000601Y383447D01*
G01Y385773D02*
G02X1000636Y383507I-2015J-1164D01*
G01X1000601Y387347D02*
G03Y385773I1364J-787D01*
G01X1001094Y387908D02*
G03X1000601Y387347I1159J-1516D01*
G01X1001376Y388190D02*
X1001094Y387908D01*
G01X1001376Y397977D02*
Y388190D01*
G01X1002400Y399001D02*
X1001376Y397977D01*
G01X1002400Y403600D02*
Y399001D01*
G01X976638Y399149D02*
Y405711D01*
G01X979588Y396199D02*
X976638Y399149D01*
G01X979588Y380409D02*
Y396199D01*
G01X979109Y379930D02*
X979588Y380409D01*
G01X979109Y378570D02*
Y379930D01*
G01X979671Y377597D02*
X979109Y378570D01*
G01X979690Y376056D02*
G03X979671Y377597I-1384J754D01*
G01Y376022D02*
X979690Y376056D01*
G01X979646Y375980D02*
X979671Y376022D01*
G01Y373697D02*
G02X979646Y375980I2015J1164D01*
G01X979690Y372156D02*
G03X979671Y373697I-1384J754D01*
G01Y372122D02*
X979690Y372156D01*
G01X981616Y368634D02*
G02X979671Y372122I70J2325D01*
G01X981757Y368634D02*
X981616D01*
G01X983051Y366272D02*
G03X981757Y368634I-1365J788D01*
G01X983026Y363989D02*
G02X983051Y366272I2040J1119D01*
G01Y363947D02*
X983026Y363989D01*
G01X983070Y363913D02*
X983051Y363947D01*
G01Y362372D02*
G03X983070Y363913I-1365J787D01*
G01X982420Y361767D02*
G03X983051Y362372I-723J1386D01*
G01X980606Y360408D02*
G02X982420Y361767I5140J-4970D01*
G01X980112Y359184D02*
G02X980606Y360408I1574J77D01*
G01X980114Y355474D02*
X980112Y359184D01*
G01X980235Y354747D02*
G02X980114Y355474I1451J615D01*
G01X981686Y351460D02*
X980235Y354747D01*
G01X1031700Y397174D02*
X1034800Y400274D01*
G01X1031700Y391838D02*
Y397174D01*
G01X1031020Y389297D02*
G03X1031700Y391838I-4407J2541D01*
G01X1031001Y387756D02*
G02X1031020Y389297I1384J754D01*
G01Y387722D02*
X1031001Y387756D01*
G01X1031045Y387680D02*
X1031020Y387722D01*
G01Y385397D02*
G03X1031045Y387680I-2015J1164D01*
G01X1031001Y383856D02*
G02X1031020Y385397I1384J754D01*
G01Y383822D02*
X1031001Y383856D01*
G01X1031045Y383780D02*
X1031020Y383822D01*
G01Y381497D02*
G03X1031045Y383780I-2015J1164D01*
G01X1031001Y379956D02*
G02X1031020Y381497I1384J754D01*
G01Y379922D02*
X1031001Y379956D01*
G01X1031045Y379880D02*
X1031020Y379922D01*
G01Y377597D02*
G03X1031045Y379880I-2015J1164D01*
G01X1031001Y376056D02*
G02X1031020Y377597I1384J754D01*
G01Y376022D02*
X1031001Y376056D01*
G01X1031045Y375980D02*
X1031020Y376022D01*
G01Y373697D02*
G03X1031045Y375980I-2015J1164D01*
G01X1031001Y372156D02*
G02X1031020Y373697I1384J754D01*
G01Y372122D02*
X1031001Y372156D01*
G01X1031045Y369839D02*
G03X1031020Y372122I-2040J1119D01*
G01Y369797D02*
X1031045Y369839D01*
G01X1031020Y368223D02*
G02Y369797I1365J787D01*
G01X1030993Y365850D02*
G03X1031020Y368223I-1988J1209D01*
G01X1029005Y363160D02*
X1030993Y365850D01*
G01X973627Y362259D02*
X973561Y362372D01*
G01X974926Y359260D02*
X973627Y362259D01*
G01X997400Y394360D02*
Y395781D01*
G01X997000Y393960D02*
X997400Y394360D01*
G01X997000Y392015D02*
Y393960D01*
G01X997221Y391623D02*
X997000Y392015D01*
G01X997221Y389297D02*
G03Y391623I-2015J1163D01*
G01X997202Y387756D02*
G02X997221Y389297I1384J754D01*
G01Y387722D02*
X997202Y387756D01*
G01X997221Y387723D02*
Y387722D01*
G01Y385397D02*
G03Y387723I-2015J1163D01*
G01X997202Y383856D02*
G02X997221Y385397I1384J754D01*
G01Y383822D02*
X997202Y383856D01*
G01X997246Y383780D02*
X997221Y383822D01*
G01Y381497D02*
G03X997246Y383780I-2015J1164D01*
G01X997202Y379956D02*
G02X997221Y381497I1384J754D01*
G01Y379922D02*
X997202Y379956D01*
G01X997246Y379880D02*
X997221Y379922D01*
G01Y377597D02*
G03X997246Y379880I-2015J1164D01*
G01X997202Y376056D02*
G02X997221Y377597I1384J754D01*
G01Y376022D02*
X997202Y376056D01*
G01X997246Y375980D02*
X997221Y376022D01*
G01Y373697D02*
G03X997246Y375980I-2015J1164D01*
G01X997202Y372156D02*
G02X997221Y373697I1384J754D01*
G01Y372122D02*
X997202Y372156D01*
G01X997246Y369839D02*
G03X997221Y372122I-2040J1119D01*
G01Y369797D02*
X997246Y369839D01*
G01X997221Y368223D02*
G02Y369797I1365J787D01*
G01Y365897D02*
G03Y368223I-2015J1163D01*
G01X997202Y364356D02*
G02X997221Y365897I1384J754D01*
G01Y364322D02*
X997202Y364356D01*
G01X997246Y364280D02*
X997221Y364322D01*
G01Y361997D02*
G03X997246Y364280I-2015J1164D01*
G01X997202Y360456D02*
G02X997221Y361997I1384J754D01*
G01Y360422D02*
X997202Y360456D01*
G01X997246Y360380D02*
X997221Y360422D01*
G01Y358097D02*
G03X997246Y360380I-2015J1164D01*
G01X997202Y356556D02*
G02X997221Y358097I1384J754D01*
G01Y356522D02*
X997202Y356556D01*
G01X997246Y356480D02*
X997221Y356522D01*
G01X997060Y353954D02*
G03X997246Y356480I-1854J1406D01*
G01X995206Y351460D02*
X997060Y353954D01*
G01X999884Y364208D02*
X998586Y361209D01*
G01X999950Y364322D02*
X999884Y364208D01*
G01X999950Y365896D02*
G02Y364322I-1364J-787D01*
G01X999925Y368181D02*
G03X999950Y365896I2040J-1120D01*
G01Y368223D02*
X999925Y368181D01*
G01X999950Y369797D02*
G02Y368223I-1364J-787D01*
G01X999925Y369839D02*
X999950Y369797D01*
G01Y372122D02*
G03X999925Y369839I2015J-1164D01*
G01X999950Y373696D02*
G02Y372122I-1364J-787D01*
G01X999915Y375962D02*
G03X999950Y373696I2050J-1102D01*
G01Y376022D02*
X999915Y375962D01*
G01X999950Y377596D02*
G02Y376022I-1364J-787D01*
G01X999915Y379862D02*
G03X999950Y377596I2050J-1102D01*
G01Y379922D02*
X999915Y379862D01*
G01X999950Y381496D02*
G02Y379922I-1364J-787D01*
G01X999915Y383762D02*
G03X999950Y381496I2050J-1102D01*
G01Y383822D02*
X999915Y383762D01*
G01X999950Y385396D02*
G02Y383822I-1364J-787D01*
G01X999915Y387662D02*
G03X999950Y385396I2050J-1102D01*
G01Y387722D02*
X999915Y387662D01*
G01X1000300Y389017D02*
G02X999950Y387722I-2569J0D01*
G01X1000300Y398000D02*
Y389017D01*
G01X999226Y399074D02*
X1000300Y398000D01*
G01X999226Y404226D02*
Y399074D01*
G01X1003400Y394254D02*
Y405714D01*
G01X1002700Y393554D02*
X1003400Y394254D01*
G01X1002700Y389766D02*
Y393554D01*
G01X1003330Y387347D02*
G02X1002700Y389766I4328J2419D01*
G01X1003349Y387313D02*
X1003330Y387347D01*
G01Y385772D02*
G03X1003349Y387313I-1365J787D01*
G01X1003305Y383489D02*
G02X1003330Y385772I2040J1119D01*
G01Y383447D02*
X1003305Y383489D01*
G01X1003349Y383413D02*
X1003330Y383447D01*
G01Y381872D02*
G03X1003349Y383413I-1365J787D01*
G01X1003305Y379589D02*
G02X1003330Y381872I2040J1119D01*
G01Y379547D02*
X1003305Y379589D01*
G01X1003349Y379513D02*
X1003330Y379547D01*
G01Y377972D02*
G03X1003349Y379513I-1365J787D01*
G01X1003305Y375689D02*
G02X1003330Y377972I2040J1119D01*
G01Y375647D02*
X1003305Y375689D01*
G01X1003349Y375613D02*
X1003330Y375647D01*
G01Y374072D02*
G03X1003349Y375613I-1365J787D01*
G01X1003330Y371746D02*
G02Y374072I2015J1163D01*
G01Y370172D02*
G03Y371746I-1365J787D01*
G01X1003305Y370130D02*
X1003330Y370172D01*
G01Y367847D02*
G02X1003305Y370130I2015J1164D01*
G01X1003349Y367813D02*
X1003330Y367847D01*
G01Y366272D02*
G03X1003349Y367813I-1365J787D01*
G01X1003305Y363989D02*
G02X1003330Y366272I2040J1119D01*
G01Y363947D02*
X1003305Y363989D01*
G01X1003349Y363913D02*
X1003330Y363947D01*
G01Y362372D02*
G03X1003349Y363913I-1365J787D01*
G01X1003305Y360089D02*
G02X1003330Y362372I2040J1119D01*
G01Y360047D02*
X1003305Y360089D01*
G01X1003349Y360013D02*
X1003330Y360047D01*
G01Y358472D02*
G03X1003349Y360013I-1365J787D01*
G01X1003264Y358359D02*
X1003330Y358472D01*
G01X1001965Y355360D02*
X1003264Y358359D01*
G01X1030800Y400904D02*
Y405204D01*
G01X1028452Y398556D02*
X1030800Y400904D01*
G01X1028452Y392166D02*
Y398556D01*
G01X1027640Y391247D02*
G02X1028452Y392166I2517J-1405D01*
G01X1027621Y391213D02*
X1027640Y391247D01*
G01Y389672D02*
G02X1027621Y391213I1365J787D01*
G01X1027665Y387389D02*
G03X1027640Y389672I-2040J1119D01*
G01Y387347D02*
X1027665Y387389D01*
G01X1027621Y387313D02*
X1027640Y387347D01*
G01Y385772D02*
G02X1027621Y387313I1365J787D01*
G01X1027665Y383489D02*
G03X1027640Y385772I-2040J1119D01*
G01Y383447D02*
X1027665Y383489D01*
G01X1027621Y383413D02*
X1027640Y383447D01*
G01Y381872D02*
G02X1027621Y383413I1365J787D01*
G01X1027665Y379589D02*
G03X1027640Y381872I-2040J1119D01*
G01Y379547D02*
X1027665Y379589D01*
G01X1027621Y379513D02*
X1027640Y379547D01*
G01Y377972D02*
G02X1027621Y379513I1365J787D01*
G01X1027665Y375689D02*
G03X1027640Y377972I-2040J1119D01*
G01Y375647D02*
X1027665Y375689D01*
G01X1027621Y375613D02*
X1027640Y375647D01*
G01Y374072D02*
G02X1027621Y375613I1365J787D01*
G01X1027640Y371746D02*
G03Y374072I-2015J1163D01*
G01Y370172D02*
G02Y371746I1365J787D01*
G01X1027665Y370130D02*
X1027640Y370172D01*
G01Y367847D02*
G03X1027665Y370130I-2015J1164D01*
G01X1027621Y367813D02*
X1027640Y367847D01*
G01Y366272D02*
G02X1027621Y367813I1365J787D01*
G01X1027687Y366097D02*
G03X1027640Y366272I-351J0D01*
G01X1027687Y364787D02*
Y366097D01*
G01X1025625Y362725D02*
X1027687Y364787D01*
G01X1025625Y361209D02*
Y362725D01*
G01X1032800Y400744D02*
Y402828D01*
G01X1030585Y398529D02*
X1032800Y400744D01*
G01X1030585Y391215D02*
Y398529D01*
G01X1030600Y391200D02*
X1030585Y391215D01*
G01X1030370Y389672D02*
G03X1030600Y391200I-1829J1057D01*
G01X1030345Y387389D02*
G02X1030370Y389672I2040J1119D01*
G01Y387347D02*
X1030345Y387389D01*
G01X1030389Y387313D02*
X1030370Y387347D01*
G01Y385772D02*
G03X1030389Y387313I-1365J787D01*
G01X1030345Y383489D02*
G02X1030370Y385772I2040J1119D01*
G01Y383447D02*
X1030345Y383489D01*
G01X1030389Y383413D02*
X1030370Y383447D01*
G01Y381872D02*
G03X1030389Y383413I-1365J787D01*
G01X1030345Y379589D02*
G02X1030370Y381872I2040J1119D01*
G01Y379547D02*
X1030345Y379589D01*
G01X1030389Y379513D02*
X1030370Y379547D01*
G01Y377972D02*
G03X1030389Y379513I-1365J787D01*
G01X1030345Y375689D02*
G02X1030370Y377972I2040J1119D01*
G01Y375647D02*
X1030345Y375689D01*
G01X1030389Y375613D02*
X1030370Y375647D01*
G01Y374072D02*
G03X1030389Y375613I-1365J787D01*
G01X1030370Y371746D02*
G02Y374072I2015J1163D01*
G01Y370172D02*
G03Y371746I-1365J787D01*
G01X1030345Y370130D02*
X1030370Y370172D01*
G01X1030193Y369792D02*
G02X1030345Y370130I2191J-782D01*
G01X1029005Y367060D02*
X1030193Y369792D01*
G01X1009461Y342085D02*
X1008096D01*
G01X1011134Y343758D02*
X1009461Y342085D01*
G01X1012569Y343758D02*
X1011134D01*
G01X1014734Y345923D02*
X1012569Y343758D01*
G01X1016074Y345923D02*
X1014734D01*
G01X1017404Y347253D02*
X1016074Y345923D01*
G01X1019607Y347253D02*
X1017404D01*
G01X1020991Y345869D02*
X1019607Y347253D01*
G01X1023387Y345869D02*
X1020991D01*
G01X1024931Y347413D02*
X1023387Y345869D01*
G01X1026479Y347413D02*
X1024931D01*
G01X1027919Y345973D02*
X1026479Y347413D01*
G01X1029916Y345973D02*
X1027919D01*
G01X1031723Y347780D02*
X1029916Y345973D01*
G01X1032991Y347780D02*
X1031723D01*
G01X1035024Y349813D02*
X1032991Y347780D01*
G01X1032455Y354984D02*
G03X1034400Y356147I-70J2325D01*
G01X1032326Y354984D02*
X1032455D01*
G01X1031020Y354197D02*
G02X1032326Y354984I1365J-788D01*
G01X1029090Y353035D02*
G03X1031020Y354197I-85J2325D01*
G01X1028920Y353035D02*
X1029090D01*
G01X1026990Y354197D02*
G03X1028920Y353035I2015J1163D01*
G01X1025684Y354984D02*
G02X1026990Y354197I-59J-1575D01*
G01X1025566Y354984D02*
X1025684D01*
G01X1024260Y354197D02*
G02X1025566Y354984I1365J-788D01*
G01X1020230Y354197D02*
G03X1024260I2015J1163D01*
G01X1018924Y354984D02*
G02X1020230Y354197I-59J-1575D01*
G01X1018806Y354984D02*
X1018924D01*
G01X1017500Y354197D02*
G02X1018806Y354984I1365J-788D01*
G01X1015570Y353035D02*
G03X1017500Y354197I-85J2325D01*
G01X1015441Y353035D02*
X1015570D01*
G01X1014120Y352247D02*
G02X1015441Y353035I1365J-787D01*
G01X1012175Y351084D02*
G03X1014120Y352247I-70J2325D01*
G01X1012046Y351084D02*
X1012175D01*
G01X1010740Y350297D02*
G02X1012046Y351084I1365J-788D01*
G01X1008810Y349135D02*
G03X1010740Y350297I-85J2325D01*
G01X1008681Y349135D02*
X1008810D01*
G01X1007360Y348347D02*
G02X1008681Y349135I1365J-787D01*
G01X1005415Y347184D02*
G03X1007360Y348347I-70J2325D01*
G01X1005286Y347184D02*
X1005415D01*
G01X1003980Y346397D02*
G02X1005286Y347184I1365J-788D01*
G01X1002050Y345235D02*
G03X1003980Y346397I-85J2325D01*
G01X1000431Y345235D02*
X1002050D01*
G01X999236Y344040D02*
X1000431Y345235D01*
G01X997936Y344040D02*
X999236D01*
G01X996747Y345229D02*
X997936Y344040D01*
G01X993665Y345229D02*
X996747D01*
G01X992476Y344040D02*
X993665Y345229D01*
G01X991176Y344040D02*
X992476D01*
G01X989987Y345229D02*
X991176Y344040D01*
G01X986905Y345229D02*
X989987D01*
G01X985716Y344040D02*
X986905Y345229D01*
G01X984195Y344040D02*
X985716D01*
G01X983006Y345229D02*
X984195Y344040D01*
G01X980145Y345229D02*
X983006D01*
G01X978956Y344040D02*
X980145Y345229D01*
G01X977656Y344040D02*
X978956D01*
G01X976467Y345229D02*
X977656Y344040D01*
G01X973385Y345229D02*
X976467D01*
G01X972196Y344040D02*
X973385Y345229D01*
G01X981656Y401141D02*
Y405793D01*
G01X982688Y400109D02*
X981656Y401141D01*
G01X982688Y380197D02*
Y400109D01*
G01X983070Y379513D02*
X982688Y380197D01*
G01X983051Y377972D02*
G03X983070Y379513I-1365J787D01*
G01X983026Y375689D02*
G02X983051Y377972I2040J1119D01*
G01Y375647D02*
X983026Y375689D01*
G01X983070Y375613D02*
X983051Y375647D01*
G01Y374072D02*
G03X983070Y375613I-1365J787D01*
G01X984981Y370584D02*
G02X983051Y374072I85J2325D01*
G01X985137Y370584D02*
X984981D01*
G01X986431Y368223D02*
G03X985137Y370584I-1365J787D01*
G01X986431Y365897D02*
G02Y368223I2015J1163D01*
G01X986450Y364356D02*
G03X986431Y365897I-1384J754D01*
G01Y364322D02*
X986450Y364356D01*
G01X986406Y364280D02*
X986431Y364322D01*
G01Y361997D02*
G02X986406Y364280I2015J1164D01*
G01X986450Y360456D02*
G03X986431Y361997I-1384J754D01*
G01X986380Y360334D02*
X986450Y360456D01*
G01X985894Y359680D02*
X986380Y360334D01*
G01X985894Y359491D02*
Y359680D01*
G01X985812Y359349D02*
X985894Y359491D01*
G01X985008Y358884D02*
G03X985812Y359349I0J928D01*
G01X985007Y358884D02*
X985008D01*
G01X983701Y358097D02*
G02X985007Y358884I1365J-788D01*
G01X983346Y357742D02*
X983701Y358097D01*
G01X983346Y356621D02*
Y357742D01*
G01X984196Y355771D02*
X983346Y356621D01*
G01X984196Y355161D02*
Y355771D01*
G01X983116Y354081D02*
X984196Y355161D01*
G01X983116Y352171D02*
Y354081D01*
G01X983798Y351489D02*
X983116Y352171D01*
G01X984346Y351489D02*
X983798D01*
G01X985066Y352209D02*
X984346Y351489D01*
G01X985066Y353409D02*
Y352209D01*
G01X977386Y405869D02*
X978208Y406691D01*
G01X982404Y405787D02*
X983308Y406691D01*
G01X1006320Y403820D02*
X1005800Y403300D01*
G01X1006320Y411679D02*
Y403820D01*
G01X1007400Y412759D02*
X1006320Y411679D01*
G01X1007400Y413816D02*
Y412759D01*
G01X1008109Y404539D02*
X1009300Y403348D01*
G01X1008109Y405305D02*
Y404539D01*
G01X1005400Y404628D02*
Y413600D01*
G01X1004500Y403728D02*
X1005400Y404628D01*
G01X1028800Y404300D02*
Y405271D01*
G01X1029476Y403624D02*
X1028800Y404300D01*
G01X1001400Y404600D02*
X1002400Y403600D01*
G01X1001400Y406100D02*
Y404600D01*
G01X976638Y405711D02*
X975658Y406691D01*
G01X999400Y404400D02*
X999226Y404226D01*
G01X999400Y405706D02*
Y404400D01*
G01X981656Y405793D02*
X980758Y406691D01*
G01X1062348Y189852D02*
Y188712D01*
G01X1056400Y195800D02*
X1062348Y189852D01*
G01X1056400Y203501D02*
Y195800D01*
G01X1055700Y204201D02*
X1056400Y203501D01*
G01X1055700Y221500D02*
Y204201D01*
G01X1048240Y192796D02*
Y191296D01*
G01X1044098Y196938D02*
X1048240Y192796D01*
G01X1044098Y205181D02*
Y196938D01*
G01X1041160Y210273D02*
X1044098Y205181D01*
G01X1041160Y211847D02*
G03Y210273I1364J-787D01*
G01X1041195Y211907D02*
X1041160Y211847D01*
G01Y214173D02*
G02X1041195Y211907I-2015J-1164D01*
G01X1041160Y215747D02*
G03Y214173I1364J-787D01*
G01X1041195Y215807D02*
X1041160Y215747D01*
G01Y218073D02*
G02X1041195Y215807I-2015J-1164D01*
G01X1094496Y217360D02*
G02X1094807Y216241I-2015J-1163D01*
G01X1094496Y218934D02*
G03Y217360I1365J-787D01*
G01X1086118Y187882D02*
X1087800Y186200D01*
G01X1086118Y192879D02*
Y187882D01*
G01X1089776Y196537D02*
X1086118Y192879D01*
G01X1089776Y203267D02*
Y196537D01*
G01X1094807Y208298D02*
X1089776Y203267D01*
G01X1094807Y216241D02*
Y208298D01*
G01X1051076Y196024D02*
Y228767D01*
G01X1056240Y190860D02*
X1051076Y196024D01*
G01X1056240Y189743D02*
Y190860D01*
G01X1046240Y193584D02*
Y191585D01*
G01X1042300Y197524D02*
X1046240Y193584D01*
G01X1042300Y201199D02*
Y197524D01*
G01X1040906Y202593D02*
X1042300Y201199D01*
G01X1040906Y209209D02*
Y202593D01*
G01X1040509Y209896D02*
X1040906Y209209D01*
G01X1040474Y212162D02*
G03X1040509Y209896I2050J-1102D01*
G01Y212222D02*
X1040474Y212162D01*
G01X1040509Y213796D02*
G02Y212222I-1364J-787D01*
G01X1040474Y216062D02*
G03X1040509Y213796I2050J-1102D01*
G01Y216122D02*
X1040474Y216062D01*
G01X1040509Y217696D02*
G02Y216122I-1364J-787D01*
G01X1040474Y219962D02*
G03X1040509Y217696I2050J-1102D01*
G01X1034240Y190912D02*
Y190071D01*
G01X1033500Y191652D02*
X1034240Y190912D01*
G01X1033500Y197861D02*
Y191652D01*
G01X1085368Y186432D02*
X1085900Y185900D01*
G01X1085368Y193190D02*
Y186432D01*
G01X1089026Y196848D02*
X1085368Y193190D01*
G01X1089026Y203583D02*
Y196848D01*
G01X1094057Y208614D02*
X1089026Y203583D01*
G01X1094057Y216196D02*
Y208614D01*
G01X1093846Y216984D02*
G02X1094057Y216196I-1365J-788D01*
G01X1093696Y217296D02*
G03X1093846Y216984I2166J849D01*
G01X1092481Y220096D02*
X1093696Y217296D01*
G01X1058240Y190360D02*
Y189343D01*
G01X1052000Y196600D02*
X1058240Y190360D01*
G01X1052000Y202900D02*
Y196600D01*
G01X1052800Y203700D02*
X1052000Y202900D01*
G01X1052800Y230944D02*
Y203700D01*
G01X1075756Y186756D02*
X1074300Y185300D01*
G01X1075756Y188941D02*
Y186756D01*
G01X1076084Y189269D02*
X1075756Y188941D01*
G01X1076084Y198418D02*
Y189269D01*
G01X1080477Y202811D02*
X1076084Y198418D01*
G01X1080477Y207182D02*
Y202811D01*
G01X1083254Y209959D02*
X1080477Y207182D01*
G01X1083254Y212676D02*
Y209959D01*
G01X1083706Y213459D02*
X1083254Y212676D01*
G01X1083706Y215034D02*
G02Y213459I-1364J-788D01*
G01Y217360D02*
G03Y215034I2015J-1163D01*
G01X1083722Y217388D02*
X1083706Y217360D01*
G01X1085555Y219920D02*
G03X1083722Y217388I11333J-10134D01*
G01X1052240Y191760D02*
Y190520D01*
G01X1048700Y195300D02*
X1052240Y191760D01*
G01X1048700Y198000D02*
Y195300D01*
G01X1046206Y200494D02*
X1048700Y198000D01*
G01X1046206Y206542D02*
Y200494D01*
G01X1044695Y208053D02*
X1046206Y206542D01*
G01X1044539Y208324D02*
X1044695Y208053D01*
G01X1044539Y209898D02*
G03Y208324I1365J-787D01*
G01Y212224D02*
G02Y209898I-2015J-1163D01*
G01Y213798D02*
G03Y212224I1364J-787D01*
G01Y216124D02*
G02Y213798I-2015J-1163D01*
G01Y217698D02*
G03Y216124I1365J-787D01*
G01Y220024D02*
G02Y217698I-2015J-1163D01*
G01X1089376Y189321D02*
X1091600Y187097D01*
G01X1089376Y192106D02*
Y189321D01*
G01X1094315Y197045D02*
X1089376Y192106D01*
G01X1094315Y201566D02*
Y197045D01*
G01X1098186Y205437D02*
X1094315Y201566D01*
G01X1073134Y189469D02*
X1069200Y185535D01*
G01X1073134Y199499D02*
Y189469D01*
G01X1077627Y203992D02*
X1073134Y199499D01*
G01X1077627Y208362D02*
Y203992D01*
G01X1080576Y211311D02*
X1077627Y208362D01*
G01X1080576Y212652D02*
Y211311D01*
G01X1080326Y213082D02*
X1080576Y212652D01*
G01X1080284Y215336D02*
G03X1080326Y213082I2057J-1089D01*
G01Y215409D02*
X1080284Y215336D01*
G01X1080326Y216983D02*
G02Y215409I-1364J-787D01*
G01X1080209Y219081D02*
G03X1080326Y216983I2132J-933D01*
G01X1050240Y192060D02*
Y190799D01*
G01X1047770Y194530D02*
X1050240Y192060D01*
G01X1047770Y197770D02*
Y194530D01*
G01X1045100Y200440D02*
X1047770Y197770D01*
G01X1045100Y205852D02*
Y200440D01*
G01X1043889Y207948D02*
X1045100Y205852D01*
G01X1043889Y210274D02*
G03Y207948I2015J-1163D01*
G01Y211848D02*
G02Y210274I-1365J-787D01*
G01Y214174D02*
G03Y211848I2017J-1163D01*
G01Y215748D02*
G02Y214174I-1365J-787D01*
G01Y218074D02*
G03Y215748I2015J-1163D01*
G01X1088626Y187674D02*
X1089700Y186600D01*
G01X1088626Y192417D02*
Y187674D01*
G01X1093565Y197356D02*
X1088626Y192417D01*
G01X1093565Y201880D02*
Y197356D01*
G01X1097436Y205751D02*
X1093565Y201880D01*
G01X1054240Y191500D02*
Y190277D01*
G01X1050000Y195740D02*
X1054240Y191500D01*
G01X1050000Y197800D02*
Y195740D01*
G01X1047556Y200244D02*
X1050000Y197800D01*
G01X1047556Y234741D02*
Y200244D01*
G01X1060240Y190159D02*
Y188943D01*
G01X1055600Y194799D02*
X1060240Y190159D01*
G01X1055600Y202601D02*
Y194799D01*
G01X1054256Y203945D02*
X1055600Y202601D01*
G01X1054256Y221651D02*
Y203945D01*
G01X1038240Y191060D02*
Y190084D01*
G01X1036556Y192744D02*
X1038240Y191060D01*
G01X1036556Y199645D02*
Y192744D01*
G01X1035600Y200601D02*
X1036556Y199645D01*
G01X1035600Y203101D02*
Y200601D01*
G01X1033769Y208356D02*
X1033750Y208322D01*
G01Y209897D02*
G02X1033769Y208356I-1365J-787D01*
G01X1033725Y212180D02*
G03X1033750Y209897I2040J-1119D01*
G01Y212222D02*
X1033725Y212180D01*
G01X1033769Y212256D02*
X1033750Y212222D01*
G01Y213797D02*
G02X1033769Y212256I-1365J-787D01*
G01X1033725Y216080D02*
G03X1033750Y213797I2040J-1119D01*
G01Y216122D02*
X1033725Y216080D01*
G01X1033769Y216156D02*
X1033750Y216122D01*
G01Y217697D02*
G02X1033769Y216156I-1365J-787D01*
G01X1033725Y219980D02*
G03X1033750Y217697I2040J-1119D01*
G01X1042240Y191060D02*
Y190218D01*
G01X1039656Y193644D02*
X1042240Y191060D01*
G01X1039656Y200145D02*
Y193644D01*
G01X1037956Y201845D02*
X1039656Y200145D01*
G01X1037956Y205691D02*
Y201845D01*
G01X1037449Y207375D02*
X1037956Y205691D01*
G01X1037130Y207946D02*
X1037449Y207375D01*
G01X1037130Y210272D02*
G03Y207946I2015J-1163D01*
G01X1037149Y211813D02*
G02X1037130Y210272I-1384J-754D01*
G01Y211847D02*
X1037149Y211813D01*
G01X1037105Y211889D02*
X1037130Y211847D01*
G01Y214172D02*
G03X1037105Y211889I2015J-1164D01*
G01X1037149Y215713D02*
G02X1037130Y214172I-1384J-754D01*
G01Y215747D02*
X1037149Y215713D01*
G01X1037105Y215789D02*
X1037130Y215747D01*
G01Y218072D02*
G03X1037105Y215789I2015J-1164D01*
G01X1036240Y191046D02*
Y190168D01*
G01X1035100Y192186D02*
X1036240Y191046D01*
G01X1035100Y199300D02*
Y192186D01*
G01X1034356Y200044D02*
X1035100Y199300D01*
G01X1034356Y202344D02*
Y200044D01*
G01X1040240Y191061D02*
Y190240D01*
G01X1038106Y193195D02*
X1040240Y191061D01*
G01X1038106Y199994D02*
Y193195D01*
G01X1036900Y201200D02*
X1038106Y199994D01*
G01X1036900Y203705D02*
Y201200D01*
G01X1034076Y206529D02*
X1036900Y203705D01*
G01X1034076Y207377D02*
Y206529D01*
G01X1034400Y207946D02*
X1034076Y207377D01*
G01X1034400Y210272D02*
G02Y207946I-2015J-1163D01*
G01X1034381Y211813D02*
G03X1034400Y210272I1384J-754D01*
G01Y211847D02*
X1034381Y211813D01*
G01X1034425Y211889D02*
X1034400Y211847D01*
G01Y214172D02*
G02X1034425Y211889I-2015J-1164D01*
G01X1034381Y215713D02*
G03X1034400Y214172I1384J-754D01*
G01Y215747D02*
X1034381Y215713D01*
G01X1034425Y215789D02*
X1034400Y215747D01*
G01Y218072D02*
G02X1034425Y215789I-2015J-1164D01*
G01X1044240Y191025D02*
Y190266D01*
G01X1040900Y194365D02*
X1044240Y191025D01*
G01X1040900Y200699D02*
Y194365D01*
G01X1039306Y202293D02*
X1040900Y200699D01*
G01X1039306Y205677D02*
Y202293D01*
G01X1037761Y208356D02*
X1039306Y205677D01*
G01X1037780Y209897D02*
G03X1037761Y208356I1365J-787D01*
G01X1037805Y212180D02*
G02X1037780Y209897I-2040J-1119D01*
G01Y212222D02*
X1037805Y212180D01*
G01X1037761Y212256D02*
X1037780Y212222D01*
G01Y213797D02*
G03X1037761Y212256I1365J-787D01*
G01X1037805Y216080D02*
G02X1037780Y213797I-2040J-1119D01*
G01Y216122D02*
X1037805Y216080D01*
G01X1037761Y216156D02*
X1037780Y216122D01*
G01Y217697D02*
G03X1037761Y216156I1365J-787D01*
G01X1037805Y219980D02*
G02X1037780Y217697I-2040J-1119D01*
G01X1076834Y185633D02*
X1076200Y184999D01*
G01X1076834Y198107D02*
Y185633D01*
G01X1081227Y202500D02*
X1076834Y198107D01*
G01X1081227Y206871D02*
Y202500D01*
G01X1084004Y209648D02*
X1081227Y206871D01*
G01X1084004Y212478D02*
Y209648D01*
G01X1084354Y213085D02*
X1084004Y212478D01*
G01X1084356Y213084D02*
X1084354Y213085D01*
G01X1084356Y215410D02*
G02Y213084I-2017J-1163D01*
G01Y216984D02*
G03Y215410I1365J-787D01*
G01X1086295Y218630D02*
G03X1084356Y216984I1328J-3530D01*
G01X1073884Y187284D02*
X1071300Y184700D01*
G01X1073884Y199188D02*
Y187284D01*
G01X1078377Y203681D02*
X1073884Y199188D01*
G01X1078377Y208051D02*
Y203681D01*
G01X1081326Y211000D02*
X1078377Y208051D01*
G01X1081326Y212858D02*
Y211000D01*
G01X1080977Y213459D02*
X1081326Y212858D01*
G01X1080958Y215000D02*
G03X1080977Y213459I1383J-754D01*
G01Y215034D02*
X1080958Y215000D01*
G01X1081012Y215094D02*
X1080977Y215034D01*
G01Y217360D02*
G02X1081012Y215094I-2015J-1164D01*
G01X1080878Y218728D02*
G03X1080977Y217360I1463J-582D01*
G01X1057000Y222800D02*
X1055700Y221500D01*
G01X1057700Y222800D02*
X1057000D01*
G01X1058900Y224000D02*
X1057700Y222800D01*
G01X1058900Y227024D02*
Y224000D01*
G01X1057314Y228610D02*
X1058900Y227024D01*
G01X1041160Y219647D02*
G03Y218073I1364J-787D01*
G01X1041195Y219707D02*
X1041160Y219647D01*
G01Y221973D02*
G02X1041195Y219707I-2015J-1164D01*
G01X1041160Y223547D02*
G03Y221973I1364J-787D01*
G01X1041195Y223607D02*
X1041160Y223547D01*
G01Y225873D02*
G02X1041195Y223607I-2015J-1164D01*
G01X1041160Y227447D02*
G03Y225873I1364J-787D01*
G01X1041185Y229730D02*
G02X1041160Y227447I-2040J-1119D01*
G01Y229772D02*
X1041185Y229730D01*
G01X1041160Y231346D02*
G03Y229772I1364J-787D01*
G01X1041185Y231388D02*
X1041160Y231346D01*
G01Y233673D02*
G02X1041185Y231388I-2015J-1165D01*
G01X1041099Y233781D02*
X1041160Y233673D01*
G01X1039145Y236409D02*
X1041099Y233781D01*
G01X1094496Y221260D02*
G02Y218934I-2015J-1163D01*
G01X1094033Y223727D02*
G03X1094496Y221260I3741J-575D01*
G01X1093846Y224784D02*
G02X1094033Y223727I-1365J-787D01*
G01X1093714Y226050D02*
G03X1093846Y224784I1487J-485D01*
G01X1094187Y226523D02*
X1093714Y226050D01*
G01X1094187Y227648D02*
Y226523D01*
G01X1093939Y227896D02*
X1094187Y227648D01*
G01X1092481Y227896D02*
X1093939D01*
G01X1051076Y228767D02*
X1049284Y230559D01*
G01X1040509Y220022D02*
X1040474Y219962D01*
G01X1040509Y221596D02*
G02Y220022I-1364J-787D01*
G01X1040474Y223862D02*
G03X1040509Y221596I2050J-1102D01*
G01Y223922D02*
X1040474Y223862D01*
G01X1040509Y225496D02*
G02Y223922I-1364J-787D01*
G01X1040446Y225603D02*
X1040509Y225496D01*
G01X1039145Y228610D02*
X1040446Y225603D01*
G01X1049284Y234460D02*
X1052800Y230944D01*
G01X1085721Y220096D02*
X1085555Y219920D01*
G01X1044539Y221598D02*
G03Y220024I1365J-787D01*
G01Y223924D02*
G02Y221598I-2015J-1163D01*
G01Y225498D02*
G03Y223924I1365J-787D01*
G01Y227824D02*
G02Y225498I-2015J-1163D01*
G01Y229398D02*
G03Y227824I1365J-787D01*
G01X1044243Y232129D02*
G02X1044539Y229398I-1719J-1568D01*
G01X1042524Y234460D02*
X1044243Y232129D01*
G01X1080326Y219309D02*
G03X1080209Y219081I1790J-1062D01*
G01X1080390Y219422D02*
X1080326Y219309D01*
G01X1082341Y222047D02*
X1080390Y219422D01*
G01X1043889Y219648D02*
G02Y218074I-1365J-787D01*
G01Y221974D02*
G03Y219648I2015J-1163D01*
G01Y223548D02*
G02Y221974I-1365J-787D01*
G01Y225874D02*
G03Y223548I2015J-1163D01*
G01Y227448D02*
G02Y225874I-1365J-787D01*
G01X1043724Y227798D02*
G03X1043889Y227448I2180J814D01*
G01X1042524Y230559D02*
X1043724Y227798D01*
G01X1045904Y236393D02*
X1047556Y234741D01*
G01X1045904Y236409D02*
Y236393D01*
G01X1057314Y224709D02*
X1054256Y221651D01*
G01X1033750Y220022D02*
X1033725Y219980D01*
G01X1033769Y220056D02*
X1033750Y220022D01*
G01Y221597D02*
G02X1033769Y220056I-1365J-787D01*
G01X1033725Y223880D02*
G03X1033750Y221597I2040J-1119D01*
G01Y223922D02*
X1033725Y223880D01*
G01X1033769Y223956D02*
X1033750Y223922D01*
G01Y225497D02*
G02X1033769Y223956I-1365J-787D01*
G01X1033453Y226009D02*
X1033750Y225497D01*
G01X1037149Y219613D02*
G02X1037130Y218072I-1384J-754D01*
G01Y219647D02*
X1037149Y219613D01*
G01X1037105Y219689D02*
X1037130Y219647D01*
G01Y221972D02*
G03X1037105Y219689I2015J-1164D01*
G01X1037149Y223513D02*
G02X1037130Y221972I-1384J-754D01*
G01Y223547D02*
X1037149Y223513D01*
G01X1037105Y223589D02*
X1037130Y223547D01*
G01Y225872D02*
G03X1037105Y223589I2015J-1164D01*
G01X1037149Y227413D02*
G02X1037130Y225872I-1384J-754D01*
G01X1037065Y227559D02*
X1037149Y227413D01*
G01X1035765Y230559D02*
X1037065Y227559D01*
G01X1034381Y219613D02*
G03X1034400Y218072I1384J-754D01*
G01Y219647D02*
X1034381Y219613D01*
G01X1034425Y219689D02*
X1034400Y219647D01*
G01Y221972D02*
G02X1034425Y219689I-2015J-1164D01*
G01X1034381Y223513D02*
G03X1034400Y221972I1384J-754D01*
G01Y223547D02*
X1034381Y223513D01*
G01X1034425Y223589D02*
X1034400Y223547D01*
G01Y225872D02*
G02X1034425Y223589I-2015J-1164D01*
G01X1034381Y227413D02*
G03X1034400Y225872I1384J-754D01*
G01Y227447D02*
X1034381Y227413D01*
G01X1034425Y229730D02*
G02X1034400Y227447I-2040J-1119D01*
G01Y229772D02*
X1034425Y229730D01*
G01X1034400Y231346D02*
G03Y229772I1365J-787D01*
G01Y233672D02*
G02Y231346I-2015J-1163D01*
G01X1034334Y233788D02*
X1034400Y233672D01*
G01X1037780Y220022D02*
X1037805Y219980D01*
G01X1037761Y220056D02*
X1037780Y220022D01*
G01Y221597D02*
G03X1037761Y220056I1365J-787D01*
G01X1037805Y223880D02*
G02X1037780Y221597I-2040J-1119D01*
G01Y223922D02*
X1037805Y223880D01*
G01X1037761Y223956D02*
X1037780Y223922D01*
G01Y225497D02*
G03X1037761Y223956I1365J-787D01*
G01X1037780Y227823D02*
G02Y225497I-2015J-1163D01*
G01Y229397D02*
G03Y227823I1365J-787D01*
G01X1037805Y229439D02*
X1037780Y229397D01*
G01Y231722D02*
G02X1037805Y229439I-2015J-1164D01*
G01X1037715Y231835D02*
X1037780Y231722D01*
G01X1035765Y234460D02*
X1037715Y231835D01*
G01X1086971Y221056D02*
G02X1086295Y218630I-1250J-959D01*
G01X1085117Y222542D02*
G02X1086971Y221056I-1636J-3940D01*
G01X1084356Y224784D02*
G03X1085117Y222542I1365J-787D01*
G01X1085721Y227896D02*
X1084356Y224784D01*
G01X1081105Y219122D02*
G03X1080878Y218728I1244J-979D01*
G01X1081948Y219672D02*
G03X1081105Y219122I394J-1525D01*
G01X1083594Y221064D02*
G02X1081948Y219672I-2267J1011D01*
G01X1083706Y221259D02*
X1083594Y221064D01*
G01X1083725Y222800D02*
G02X1083706Y221259I-1384J-754D01*
G01X1083638Y222951D02*
X1083725Y222800D01*
G01X1082341Y225947D02*
X1083638Y222951D01*
G01X1036800Y399864D02*
Y405200D01*
G01X1033769Y387756D02*
G03X1033750Y389297I-1384J754D01*
G01Y387722D02*
X1033769Y387756D01*
G01X1033725Y387680D02*
X1033750Y387722D01*
G01Y385397D02*
G02X1033725Y387680I2015J1164D01*
G01X1033769Y383856D02*
G03X1033750Y385397I-1384J754D01*
G01Y383822D02*
X1033769Y383856D01*
G01X1033725Y383780D02*
X1033750Y383822D01*
G01Y381497D02*
G02X1033725Y383780I2015J1164D01*
G01X1033769Y379956D02*
G03X1033750Y381497I-1384J754D01*
G01Y379922D02*
X1033769Y379956D01*
G01X1033725Y379880D02*
X1033750Y379922D01*
G01Y377597D02*
G02X1033725Y379880I2015J1164D01*
G01X1033769Y376056D02*
G03X1033750Y377597I-1384J754D01*
G01Y376022D02*
X1033769Y376056D01*
G01X1033725Y375980D02*
X1033750Y376022D01*
G01Y373697D02*
G02X1033725Y375980I2015J1164D01*
G01X1033769Y372156D02*
G03X1033750Y373697I-1384J754D01*
G01X1033685Y372010D02*
X1033769Y372156D01*
G01X1094966Y357759D02*
G02X1098996I2015J-1163D01*
G01X1092236D02*
G03X1094966I1365J788D01*
G01X1088206D02*
G02X1092236I2015J-1163D01*
G01X1085509Y357704D02*
G03X1088206Y357759I1332J843D01*
G01X1085477Y357760D02*
X1085509Y357704D01*
G01X1081472Y357801D02*
G02X1085477Y357760I1990J-1205D01*
G01X1081447Y357759D02*
X1081472Y357801D01*
G01X1078717Y357759D02*
G03X1081447I1365J788D01*
G01X1076787Y358921D02*
G02X1078717Y357759I-85J-2325D01*
G01X1076658Y358921D02*
X1076787D01*
G01X1075182Y359557D02*
G03X1076658Y358921I1537J1536D01*
G01X1074623Y360116D02*
X1075182Y359557D01*
G01X1070124Y360116D02*
X1074623D01*
G01X1067729Y357721D02*
X1070124Y360116D01*
G01X1058121Y357721D02*
X1067729D01*
G01X1056134Y355734D02*
X1058121Y357721D01*
G01X1052620Y355734D02*
X1056134D01*
G01X1051299Y356522D02*
G03X1052620Y355734I1365J787D01*
G01X1049354Y357685D02*
G02X1051299Y356522I-70J-2325D01*
G01X1049214Y357685D02*
X1049354D01*
G01X1047269Y356522D02*
G02X1049214Y357685I2015J-1162D01*
G01X1044539Y356522D02*
G03X1047269I1365J787D01*
G01X1042594Y357685D02*
G02X1044539Y356522I-70J-2325D01*
G01X1042454Y357685D02*
X1042594D01*
G01X1040509Y356522D02*
G02X1042454Y357685I2015J-1162D01*
G01X1040496Y356499D02*
X1040509Y356522D01*
G01X1037780D02*
G03X1040496Y356499I1365J787D01*
G01X1035835Y357685D02*
G02X1037780Y356522I-70J-2325D01*
G01X1035695Y357685D02*
X1035835D01*
G01X1033750Y356522D02*
G02X1035695Y357685I2015J-1162D01*
G01Y353785D02*
G03X1033750Y352622I70J-2325D01*
G01X1035835Y353785D02*
X1035695D01*
G01X1037780Y352622D02*
G03X1035835Y353785I-2015J-1162D01*
G01X1040496Y352599D02*
G02X1037780Y352622I-1351J810D01*
G01X1040509D02*
X1040496Y352599D01*
G01X1042454Y353785D02*
G03X1040509Y352622I70J-2325D01*
G01X1042594Y353785D02*
X1042454D01*
G01X1044539Y352622D02*
G03X1042594Y353785I-2015J-1162D01*
G01X1047269Y352622D02*
G02X1044539I-1365J787D01*
G01X1049214Y353785D02*
G03X1047269Y352622I70J-2325D01*
G01X1049354Y353785D02*
X1049214D01*
G01X1051299Y352622D02*
G03X1049354Y353785I-2015J-1162D01*
G01X1052620Y351834D02*
G02X1051299Y352622I44J1575D01*
G01X1052663Y351834D02*
X1052620D01*
G01X1052664Y351835D02*
X1052663Y351834D01*
G01X1057183Y351835D02*
X1052664D01*
G01X1059131Y353783D02*
X1057183Y351835D01*
G01X1062785Y353783D02*
X1059131D01*
G01X1062786Y353782D02*
X1062785Y353783D01*
G01X1066974Y353782D02*
X1062786D01*
G01X1067759Y352997D02*
X1066974Y353782D01*
G01X1073745Y352997D02*
X1067759D01*
G01X1074412Y353383D02*
X1073745Y352997D01*
G01X1074687Y353859D02*
X1074412Y353383D01*
G01X1078717Y353859D02*
G03X1074687I-2015J-1163D01*
G01X1081447D02*
G02X1078717I-1365J788D01*
G01X1081472Y353901D02*
X1081447Y353859D01*
G01X1085477Y353860D02*
G03X1081472Y353901I-2015J-1164D01*
G01X1085509Y353804D02*
X1085477Y353860D01*
G01X1088206Y353859D02*
G02X1085509Y353804I-1365J788D01*
G01X1092236Y353859D02*
G03X1088206I-2015J-1163D01*
G01X1094966D02*
G02X1092236I-1365J788D01*
G01X1096896Y355021D02*
G03X1094966Y353859I85J-2325D01*
G01X1043800Y395400D02*
Y404000D01*
G01X1042300Y393900D02*
X1043800Y395400D01*
G01X1040466Y391546D02*
G02X1042300Y393900I7524J-3970D01*
G01X1040509Y389296D02*
G02X1040466Y391546I2015J1164D01*
G01X1040509Y387722D02*
G03Y389296I-1364J787D01*
G01X1040474Y387662D02*
X1040509Y387722D01*
G01Y385396D02*
G02X1040474Y387662I2015J1164D01*
G01X1040509Y383822D02*
G03Y385396I-1364J787D01*
G01X1040474Y383762D02*
X1040509Y383822D01*
G01Y381496D02*
G02X1040474Y383762I2015J1164D01*
G01X1040509Y379922D02*
G03Y381496I-1364J787D01*
G01X1040474Y379862D02*
X1040509Y379922D01*
G01Y377596D02*
G02X1040474Y379862I2015J1164D01*
G01X1040509Y376022D02*
G03Y377596I-1364J787D01*
G01X1040474Y375962D02*
X1040509Y376022D01*
G01Y373696D02*
G02X1040474Y375962I2015J1164D01*
G01X1040509Y372122D02*
G03Y373696I-1364J787D01*
G01X1040446Y372014D02*
X1040509Y372122D01*
G01X1039145Y369010D02*
X1040446Y372014D01*
G01X1049900Y402400D02*
Y405128D01*
G01X1047700Y400200D02*
X1049900Y402400D01*
G01X1047700Y387854D02*
Y400200D01*
G01X1046636Y386790D02*
X1047700Y387854D01*
G01X1045767Y386790D02*
X1046636D01*
G01X1044692Y385715D02*
X1045767Y386790D01*
G01X1044539Y385397D02*
G03X1044692Y385715I-2014J1165D01*
G01X1044520Y383856D02*
G02X1044539Y385397I1384J754D01*
G01Y383822D02*
X1044520Y383856D01*
G01X1044564Y383780D02*
X1044539Y383822D01*
G01Y381497D02*
G03X1044564Y383780I-2015J1164D01*
G01X1044520Y379956D02*
G02X1044539Y381497I1384J754D01*
G01Y379922D02*
X1044520Y379956D01*
G01X1044564Y379880D02*
X1044539Y379922D01*
G01Y377597D02*
G03X1044564Y379880I-2015J1164D01*
G01X1044520Y376056D02*
G02X1044539Y377597I1384J754D01*
G01Y376022D02*
X1044520Y376056D01*
G01X1044564Y375980D02*
X1044539Y376022D01*
G01Y373697D02*
G03X1044564Y375980I-2015J1164D01*
G01X1044520Y372156D02*
G02X1044539Y373697I1384J754D01*
G01Y372122D02*
X1044520Y372156D01*
G01X1044564Y369839D02*
G03X1044539Y372122I-2040J1119D01*
G01Y369797D02*
X1044564Y369839D01*
G01X1044539Y368223D02*
G02Y369797I1365J787D01*
G01X1044438Y365737D02*
G03X1044539Y368223I-1914J1323D01*
G01X1042524Y363160D02*
X1044438Y365737D01*
G01X1082105Y400638D02*
X1072624Y410119D01*
G01X1082105Y398693D02*
Y400638D01*
G01X1082121Y398666D02*
X1082105Y398693D01*
G01X1085490Y392837D02*
X1082121Y398666D01*
G01X1086841Y392072D02*
G02X1085490Y392837I0J1575D01*
G01X1086911Y392072D02*
X1086841D01*
G01X1088856Y388584D02*
G03X1086911Y392072I-2015J1163D01*
G01X1089993Y386237D02*
G02X1088856Y388584I228J1559D01*
G01X1090221Y386465D02*
X1089993Y386237D01*
G01X1090221Y387796D02*
Y386465D01*
G01X1037130Y352247D02*
G03X1034400I-1365J-787D01*
G01X1039075Y351084D02*
G02X1037130Y352247I70J2325D01*
G01X1039215Y351084D02*
X1039075D01*
G01X1041160Y352247D02*
G02X1039215Y351084I-2015J1162D01*
G01X1041173Y352270D02*
X1041160Y352247D01*
G01X1043889D02*
G03X1041173Y352270I-1365J-787D01*
G01X1045834Y351084D02*
G02X1043889Y352247I70J2325D01*
G01X1045974Y351084D02*
X1045834D01*
G01X1047919Y352247D02*
G02X1045974Y351084I-2015J1162D01*
G01X1050649Y352247D02*
G03X1047919I-1365J-787D01*
G01X1052662Y351084D02*
G02X1050649Y352247I0J2324D01*
G01X1057495Y351084D02*
X1052662D01*
G01X1059443Y353032D02*
X1057495Y351084D01*
G01X1066663Y353032D02*
X1059443D01*
G01X1067448Y352247D02*
X1066663Y353032D01*
G01X1073947Y352247D02*
X1067448D01*
G01X1074962Y352834D02*
X1073947Y352247D01*
G01X1075337Y353484D02*
X1074962Y352834D01*
G01X1078067Y353484D02*
G03X1075337I-1365J-788D01*
G01X1082097D02*
G02X1078067I-2015J1163D01*
G01X1084794Y353539D02*
G03X1082097Y353484I-1332J-843D01*
G01X1084826Y353483D02*
X1084794Y353539D01*
G01X1088831Y353442D02*
G02X1084826Y353483I-1990J1205D01*
G01X1088856Y353484D02*
X1088831Y353442D01*
G01X1091586Y353484D02*
G03X1088856I-1365J-788D01*
G01X1095616D02*
G02X1091586I-2015J1163D01*
G01X1085523Y400229D02*
Y405792D01*
G01X1086426Y398666D02*
X1085523Y400229D01*
G01X1087875Y396160D02*
X1086426Y398666D01*
G01X1089074Y394516D02*
G02X1087875Y396160I5957J5604D01*
G01X1090162Y394021D02*
G02X1089074Y394516I59J1574D01*
G01X1090291Y394021D02*
X1090162D01*
G01X1092236Y392858D02*
G03X1090291Y394021I-2015J-1162D01*
G01X1092302Y392745D02*
X1092236Y392858D01*
G01X1093601Y389747D02*
X1092302Y392745D01*
G01X1044800Y394528D02*
Y403301D01*
G01X1042694Y392422D02*
X1044800Y394528D01*
G01X1041159Y391248D02*
G02X1042694Y392422I2178J-1257D01*
G01X1041128Y389729D02*
G02X1041159Y391248I1396J731D01*
G01X1041160Y389673D02*
X1041128Y389729D01*
G01X1041195Y387407D02*
G03X1041160Y389673I-2050J1102D01*
G01Y387347D02*
X1041195Y387407D01*
G01X1041160Y385773D02*
G02Y387347I1364J787D01*
G01X1041195Y383507D02*
G03X1041160Y385773I-2050J1102D01*
G01Y383447D02*
X1041195Y383507D01*
G01X1041160Y381873D02*
G02Y383447I1364J787D01*
G01X1041195Y379607D02*
G03X1041160Y381873I-2050J1102D01*
G01Y379547D02*
X1041195Y379607D01*
G01X1041160Y377973D02*
G02Y379547I1364J787D01*
G01X1041195Y375707D02*
G03X1041160Y377973I-2050J1102D01*
G01Y375647D02*
X1041195Y375707D01*
G01X1041160Y374073D02*
G02Y375647I1364J787D01*
G01X1041185Y371788D02*
G03X1041160Y374073I-2040J1120D01*
G01Y371746D02*
X1041185Y371788D01*
G01X1041160Y370172D02*
G02Y371746I1364J787D01*
G01X1041185Y370130D02*
X1041160Y370172D01*
G01Y367847D02*
G03X1041185Y370130I-2015J1164D01*
G01X1041160Y366273D02*
G02Y367847I1364J787D01*
G01X1041195Y364007D02*
G03X1041160Y366273I-2050J1102D01*
G01X1041096Y363834D02*
X1041195Y364007D01*
G01X1039145Y361209D02*
X1041096Y363834D01*
G01X1038100Y399044D02*
Y404266D01*
G01X1034096Y395040D02*
X1038100Y399044D01*
G01X1034096Y392104D02*
Y395040D01*
G01X1034100Y392100D02*
X1034096Y392104D01*
G01X1034400Y389672D02*
G02X1034100Y392100I2714J1568D01*
G01X1034425Y387389D02*
G03X1034400Y389672I-2040J1119D01*
G01Y387347D02*
X1034425Y387389D01*
G01X1034381Y387313D02*
X1034400Y387347D01*
G01Y385772D02*
G02X1034381Y387313I1365J787D01*
G01X1034425Y383489D02*
G03X1034400Y385772I-2040J1119D01*
G01Y383447D02*
X1034425Y383489D01*
G01X1034381Y383413D02*
X1034400Y383447D01*
G01Y381872D02*
G02X1034381Y383413I1365J787D01*
G01X1034425Y379589D02*
G03X1034400Y381872I-2040J1119D01*
G01Y379547D02*
X1034425Y379589D01*
G01X1034381Y379513D02*
X1034400Y379547D01*
G01Y377972D02*
G02X1034381Y379513I1365J787D01*
G01X1034425Y375689D02*
G03X1034400Y377972I-2040J1119D01*
G01Y375647D02*
X1034425Y375689D01*
G01X1034381Y375613D02*
X1034400Y375647D01*
G01Y374072D02*
G02X1034381Y375613I1365J787D01*
G01X1034400Y371746D02*
G03Y374072I-2015J1163D01*
G01Y370172D02*
G02Y371746I1365J787D01*
G01X1034425Y370130D02*
X1034400Y370172D01*
G01Y367847D02*
G03X1034425Y370130I-2015J1164D01*
G01X1034381Y367813D02*
X1034400Y367847D01*
G01X1034213Y366785D02*
G02X1034381Y367813I1552J274D01*
G01X1034213Y364513D02*
Y366785D01*
G01X1034800Y400274D02*
Y405100D01*
G01X1035765Y364465D02*
Y363160D01*
G01X1037629Y366329D02*
X1035765Y364465D01*
G01X1037629Y368580D02*
Y366329D01*
G01X1037780Y369797D02*
G03X1037629Y368580I1365J-787D01*
G01X1037805Y369839D02*
X1037780Y369797D01*
G01Y372122D02*
G02X1037805Y369839I-2015J-1164D01*
G01X1037761Y372156D02*
X1037780Y372122D01*
G01Y373697D02*
G03X1037761Y372156I1365J-787D01*
G01X1037805Y375980D02*
G02X1037780Y373697I-2040J-1119D01*
G01Y376022D02*
X1037805Y375980D01*
G01X1037761Y376056D02*
X1037780Y376022D01*
G01Y377597D02*
G03X1037761Y376056I1365J-787D01*
G01X1037805Y379880D02*
G02X1037780Y377597I-2040J-1119D01*
G01Y379922D02*
X1037805Y379880D01*
G01X1037761Y379956D02*
X1037780Y379922D01*
G01Y381497D02*
G03X1037761Y379956I1365J-787D01*
G01X1037805Y383780D02*
G02X1037780Y381497I-2040J-1119D01*
G01Y383822D02*
X1037805Y383780D01*
G01X1037761Y383856D02*
X1037780Y383822D01*
G01Y385397D02*
G03X1037761Y383856I1365J-787D01*
G01X1037805Y387680D02*
G02X1037780Y385397I-2040J-1119D01*
G01Y387722D02*
X1037805Y387680D01*
G01X1037761Y387756D02*
X1037780Y387722D01*
G01Y389297D02*
G03X1037761Y387756I1365J-787D01*
G01X1038200Y392300D02*
G02X1037780Y389297I-3926J-982D01*
G01X1038100Y392400D02*
X1038200Y392300D01*
G01X1038100Y394684D02*
Y392400D01*
G01X1043000Y399584D02*
X1038100Y394684D01*
G01X1043000Y404200D02*
Y399584D01*
G01X1084775Y400019D02*
Y405482D01*
G01X1087724Y394916D02*
X1084775Y400019D01*
G01X1087737Y394896D02*
X1087724Y394916D01*
G01X1088871Y393701D02*
G02X1087737Y394896I2503J3511D01*
G01X1090151Y393270D02*
G02X1088871Y393701I70J2325D01*
G01X1090292Y393270D02*
X1090151D01*
G01X1091586Y390909D02*
G03X1090292Y393270I-1365J787D01*
G01X1091561Y390867D02*
X1091586Y390909D01*
G01Y388584D02*
G02X1091561Y390867I2015J1164D01*
G01X1091605Y387043D02*
G03X1091586Y388584I-1384J754D01*
G01Y387009D02*
X1091605Y387043D01*
G01X1091561Y386967D02*
X1091586Y387009D01*
G01Y384684D02*
G02X1091561Y386967I2015J1164D01*
G01X1091652Y384568D02*
X1091586Y384684D01*
G01X1093601Y381947D02*
X1091652Y384568D01*
G01X1081355Y400330D02*
X1071876Y409809D01*
G01X1081355Y398486D02*
Y400330D01*
G01X1084824Y392485D02*
X1081355Y398486D01*
G01X1084826Y392483D02*
X1084824Y392485D01*
G01X1086743Y391322D02*
G02X1084826Y392483I98J2325D01*
G01X1086885Y391322D02*
X1086743D01*
G01X1088206Y388959D02*
G03X1086885Y391322I-1365J788D01*
G01X1089964Y385484D02*
G02X1088206Y388959I257J2312D01*
G01X1090221Y385227D02*
X1089964Y385484D01*
G01X1090221Y383896D02*
Y385227D01*
G01X1068646Y349813D02*
X1035024D01*
G01X1069822Y350989D02*
X1068646Y349813D01*
G01X1072799Y350989D02*
X1069822D01*
G01X1091586Y357384D02*
G03X1095616I2015J1163D01*
G01X1088856D02*
G02X1091586I1365J-788D01*
G01X1088831Y357342D02*
X1088856Y357384D01*
G01X1084826Y357383D02*
G03X1088831Y357342I2015J1164D01*
G01X1084794Y357439D02*
X1084826Y357383D01*
G01X1082097Y357384D02*
G02X1084794Y357439I1365J-788D01*
G01X1078067Y357384D02*
G03X1082097I2015J1163D01*
G01X1076761Y358171D02*
G02X1078067Y357384I-59J-1575D01*
G01X1075784Y358171D02*
X1076761D01*
G01X1074584Y356971D02*
X1075784Y358171D01*
G01X1058432Y356971D02*
X1074584D01*
G01X1056445Y354984D02*
X1058432Y356971D01*
G01X1052594Y354984D02*
X1056445D01*
G01X1050649Y356147D02*
G03X1052594Y354984I2015J1162D01*
G01X1047919Y356147D02*
G02X1050649I1365J-787D01*
G01X1045974Y354984D02*
G03X1047919Y356147I-70J2325D01*
G01X1045834Y354984D02*
X1045974D01*
G01X1043889Y356147D02*
G03X1045834Y354984I2015J1162D01*
G01X1041173Y356170D02*
G02X1043889Y356147I1351J-810D01*
G01X1041160D02*
X1041173Y356170D01*
G01X1039215Y354984D02*
G03X1041160Y356147I-70J2325D01*
G01X1039075Y354984D02*
X1039215D01*
G01X1037130Y356147D02*
G03X1039075Y354984I2015J1162D01*
G01X1034400Y356147D02*
G02X1037130I1365J-787D01*
G01X1045700Y402672D02*
X1048900Y405872D01*
G01X1045700Y391893D02*
Y402672D01*
G01X1044449Y390642D02*
X1045700Y391893D01*
G01X1043889Y389672D02*
X1044449Y390642D01*
G01X1043864Y387389D02*
G02X1043889Y389672I2040J1119D01*
G01Y387347D02*
X1043864Y387389D01*
G01X1043908Y387313D02*
X1043889Y387347D01*
G01Y385772D02*
G03X1043908Y387313I-1365J787D01*
G01X1043864Y383489D02*
G02X1043889Y385772I2040J1119D01*
G01Y383447D02*
X1043864Y383489D01*
G01X1043908Y383413D02*
X1043889Y383447D01*
G01Y381872D02*
G03X1043908Y383413I-1365J787D01*
G01X1043864Y379589D02*
G02X1043889Y381872I2040J1119D01*
G01Y379547D02*
X1043864Y379589D01*
G01X1043908Y379513D02*
X1043889Y379547D01*
G01Y377972D02*
G03X1043908Y379513I-1365J787D01*
G01X1043864Y375689D02*
G02X1043889Y377972I2040J1119D01*
G01Y375647D02*
X1043864Y375689D01*
G01X1043908Y375613D02*
X1043889Y375647D01*
G01Y374072D02*
G03X1043908Y375613I-1365J787D01*
G01X1043889Y371746D02*
G02Y374072I2015J1163D01*
G01Y370172D02*
G03Y371746I-1365J787D01*
G01X1043864Y370130D02*
X1043889Y370172D01*
G01X1043719Y369810D02*
G02X1043864Y370130I2186J-798D01*
G01X1042524Y367060D02*
X1043719Y369810D01*
G01X1039700Y398500D02*
Y403719D01*
G01X1036286Y395086D02*
X1039700Y398500D01*
G01X1036286Y392414D02*
Y395086D01*
G01X1036900Y391800D02*
X1036286Y392414D01*
G01X1037130Y389672D02*
G03X1036900Y391800I-1570J907D01*
G01X1037105Y387389D02*
G02X1037130Y389672I2040J1119D01*
G01Y387347D02*
X1037105Y387389D01*
G01X1037149Y387313D02*
X1037130Y387347D01*
G01Y385772D02*
G03X1037149Y387313I-1365J787D01*
G01X1037105Y383489D02*
G02X1037130Y385772I2040J1119D01*
G01Y383447D02*
X1037105Y383489D01*
G01X1037149Y383413D02*
X1037130Y383447D01*
G01Y381872D02*
G03X1037149Y383413I-1365J787D01*
G01X1037105Y379589D02*
G02X1037130Y381872I2040J1119D01*
G01Y379547D02*
X1037105Y379589D01*
G01X1037149Y379513D02*
X1037130Y379547D01*
G01Y377972D02*
G03X1037149Y379513I-1365J787D01*
G01X1037105Y375689D02*
G02X1037130Y377972I2040J1119D01*
G01Y375647D02*
X1037105Y375689D01*
G01X1037149Y375613D02*
X1037130Y375647D01*
G01Y374072D02*
G03X1037149Y375613I-1365J787D01*
G01X1037130Y371746D02*
G02Y374072I2015J1163D01*
G01Y370172D02*
G03Y371746I-1365J787D01*
G01X1037063Y370057D02*
X1037130Y370172D01*
G01X1035765Y367060D02*
X1037063Y370057D01*
G01X1094052Y416423D02*
X1095036Y417407D01*
G01X1094052Y413799D02*
Y416423D01*
G01X1099356Y408495D02*
X1094052Y413799D01*
G01X1044900Y405100D02*
Y406265D01*
G01X1043800Y404000D02*
X1044900Y405100D01*
G01X1050900Y406128D02*
Y407111D01*
G01X1049900Y405128D02*
X1050900Y406128D01*
G01X1072624Y416255D02*
X1073556Y417187D01*
G01X1072624Y410119D02*
Y416255D01*
G01X1077738Y416369D02*
X1078656Y417287D01*
G01X1077738Y413577D02*
Y416369D01*
G01X1085523Y405792D02*
X1077738Y413577D01*
G01X1093304Y416269D02*
X1092106Y417467D01*
G01X1093304Y413489D02*
Y416269D01*
G01X1098608Y408185D02*
X1093304Y413489D01*
G01X1046900Y405401D02*
Y406829D01*
G01X1044800Y403301D02*
X1046900Y405401D01*
G01X1038800Y404966D02*
Y405821D01*
G01X1038100Y404266D02*
X1038800Y404966D01*
G01X1042900Y404300D02*
X1043000Y404200D01*
G01X1042900Y405741D02*
Y404300D01*
G01X1076990Y416403D02*
X1076106Y417287D01*
G01X1076990Y413267D02*
Y416403D01*
G01X1084775Y405482D02*
X1076990Y413267D01*
G01X1071876Y415968D02*
X1070657Y417187D01*
G01X1071876Y409809D02*
Y415968D01*
G01X1048900Y405872D02*
Y407111D01*
G01X1040866Y404885D02*
Y405606D01*
G01X1039700Y403719D02*
X1040866Y404885D01*
G01X1133000Y199497D02*
Y197701D01*
G01X1127323Y205174D02*
X1133000Y199497D01*
G01X1127323Y207890D02*
Y205174D01*
G01X1123900Y211313D02*
X1127323Y207890D01*
G01X1123900Y212752D02*
Y211313D01*
G01X1124265Y213459D02*
X1123900Y212752D01*
G01X1124284Y215000D02*
G02X1124265Y213459I-1384J-754D01*
G01Y215034D02*
X1124284Y215000D01*
G01X1124240Y215076D02*
X1124265Y215034D01*
G01Y217359D02*
G03X1124240Y215076I2015J-1164D01*
G01X1124508Y217786D02*
X1124265Y217359D01*
G01X1126219Y220087D02*
X1124508Y217786D01*
G01X1097764Y194374D02*
X1096826Y193436D01*
G01X1097764Y195593D02*
Y194374D01*
G01X1099384Y197213D02*
X1097764Y195593D01*
G01X1099384Y200889D02*
Y197213D01*
G01X1100154Y201659D02*
X1099384Y200889D01*
G01X1100154Y204299D02*
Y201659D01*
G01X1100860Y205005D02*
X1100154Y204299D01*
G01X1100860Y212644D02*
Y205005D01*
G01X1100606Y213084D02*
X1100860Y212644D01*
G01X1100581Y215367D02*
G03X1100606Y213084I2040J-1119D01*
G01Y215409D02*
X1100581Y215367D01*
G01X1100625Y215443D02*
X1100606Y215409D01*
G01Y216984D02*
G02X1100625Y215443I-1365J-787D01*
G01X1100581Y219267D02*
G03X1100606Y216984I2040J-1119D01*
G01X1103456Y189956D02*
X1104476Y188936D01*
G01X1103456Y196611D02*
Y189956D01*
G01X1103163Y196904D02*
X1103456Y196611D01*
G01X1103163Y199578D02*
Y196904D01*
G01X1103752Y200167D02*
X1103163Y199578D01*
G01X1103752Y202805D02*
Y200167D01*
G01X1104630Y203683D02*
X1103752Y202805D01*
G01X1104630Y211370D02*
Y203683D01*
G01X1104425Y211575D02*
X1104630Y211370D01*
G01X1104425Y212296D02*
Y211575D01*
G01X1104636Y213084D02*
G03X1104425Y212296I1365J-788D01*
G01X1104661Y215367D02*
G02X1104636Y213084I-2040J-1119D01*
G01Y215409D02*
X1104661Y215367D01*
G01X1104617Y215443D02*
X1104636Y215409D01*
G01X1105171Y217536D02*
G03X1104617Y215443I830J-1340D01*
G01X1107122Y218887D02*
X1105171Y217536D01*
G01X1098514Y194298D02*
X1099376Y193436D01*
G01X1098514Y195281D02*
Y194298D01*
G01X1100134Y196901D02*
X1098514Y195281D01*
G01X1100134Y200577D02*
Y196901D01*
G01X1100904Y201347D02*
X1100134Y200577D01*
G01X1100904Y203988D02*
Y201347D01*
G01X1101610Y204694D02*
X1100904Y203988D01*
G01X1101610Y212901D02*
Y204694D01*
G01X1101256Y213459D02*
X1101610Y212901D01*
G01X1101237Y215000D02*
G03X1101256Y213459I1384J-754D01*
G01Y215034D02*
X1101237Y215000D01*
G01X1101281Y215076D02*
X1101256Y215034D01*
G01Y217359D02*
G02X1101281Y215076I-2015J-1164D01*
G01X1101237Y218900D02*
G03X1101256Y217359I1384J-754D01*
G01X1149899Y206100D02*
X1150705Y205294D01*
G01X1147094Y206100D02*
X1149899D01*
G01X1141066Y212128D02*
X1147094Y206100D01*
G01X1141066Y221201D02*
Y212128D01*
G01X1117193Y191569D02*
X1118166Y190596D01*
G01X1117193Y200770D02*
Y191569D01*
G01X1114566Y203397D02*
X1117193Y200770D01*
G01X1114566Y210113D02*
Y203397D01*
G01X1115088Y210635D02*
X1114566Y210113D01*
G01X1115088Y216196D02*
Y210635D01*
G01X1114850Y217219D02*
G02X1115088Y216196I-2097J-1027D01*
G01X1114776Y217360D02*
G02X1114850Y217219I-1738J-1002D01*
G01X1114776Y218934D02*
G03Y217360I1365J-787D01*
G01X1121466Y194346D02*
X1120716Y193596D01*
G01X1121466Y195481D02*
Y194346D01*
G01X1119463Y197484D02*
X1121466Y195481D01*
G01X1119463Y201710D02*
Y197484D01*
G01X1117806Y203367D02*
X1119463Y201710D01*
G01X1117806Y210421D02*
Y203367D01*
G01X1117152Y211075D02*
X1117806Y210421D01*
G01X1117152Y216745D02*
Y211075D01*
G01X1117506Y217359D02*
X1117152Y216745D01*
G01X1117525Y218900D02*
G02X1117506Y217359I-1384J-754D01*
G01X1129300Y195403D02*
Y194501D01*
G01X1128203Y196500D02*
X1129300Y195403D01*
G01X1128203Y199934D02*
Y196500D01*
G01X1124469Y203668D02*
X1128203Y199934D01*
G01X1124469Y206787D02*
Y203668D01*
G01X1121100Y210156D02*
X1124469Y206787D01*
G01X1121100Y212712D02*
Y210156D01*
G01X1120885Y213084D02*
X1121100Y212712D01*
G01X1120860Y215367D02*
G03X1120885Y213084I2040J-1119D01*
G01Y215409D02*
X1120860Y215367D01*
G01X1120904Y215443D02*
X1120885Y215409D01*
G01Y216984D02*
G02X1120904Y215443I-1365J-787D01*
G01X1120860Y219267D02*
G03X1120885Y216984I2040J-1119D01*
G01X1098186Y208153D02*
Y205437D01*
G01X1097666Y208673D02*
X1098186Y208153D01*
G01X1097666Y216609D02*
Y208673D01*
G01X1097876Y216984D02*
X1097666Y216609D01*
G01X1097901Y219267D02*
G02X1097876Y216984I-2040J-1119D01*
G01X1102706Y189716D02*
X1101926Y188936D01*
G01X1102706Y196299D02*
Y189716D01*
G01X1102413Y196592D02*
X1102706Y196299D01*
G01X1102413Y199890D02*
Y196592D01*
G01X1103002Y200479D02*
X1102413Y199890D01*
G01X1103002Y203116D02*
Y200479D01*
G01X1103880Y203994D02*
X1103002Y203116D01*
G01X1103880Y211057D02*
Y203994D01*
G01X1103674Y211263D02*
X1103880Y211057D01*
G01X1103674Y212296D02*
Y211263D01*
G01X1103986Y213459D02*
G03X1103674Y212296I2015J-1164D01*
G01X1104005Y215000D02*
G02X1103986Y213459I-1384J-754D01*
G01Y215034D02*
X1104005Y215000D01*
G01X1103961Y215076D02*
X1103986Y215034D01*
G01Y217359D02*
G03X1103961Y215076I2015J-1164D01*
G01X1104052Y217475D02*
X1103986Y217359D01*
G01X1106001Y220096D02*
X1104052Y217475D01*
G01X1097436Y207841D02*
Y205751D01*
G01X1096916Y208361D02*
X1097436Y207841D01*
G01X1096916Y216822D02*
Y208361D01*
G01X1097226Y217359D02*
X1096916Y216822D01*
G01X1097245Y218900D02*
G02X1097226Y217359I-1384J-754D01*
G01X1122216Y194646D02*
X1123266Y193596D01*
G01X1122216Y195793D02*
Y194646D01*
G01X1120213Y197796D02*
X1122216Y195793D01*
G01X1120213Y202022D02*
Y197796D01*
G01X1118556Y203679D02*
X1120213Y202022D01*
G01X1118556Y210732D02*
Y203679D01*
G01X1117902Y211386D02*
X1118556Y210732D01*
G01X1117902Y216544D02*
Y211386D01*
G01X1118156Y216984D02*
X1117902Y216544D01*
G01X1118181Y219267D02*
G02X1118156Y216984I-2040J-1119D01*
G01X1138796Y211192D02*
Y219081D01*
G01X1146088Y203900D02*
X1138796Y211192D01*
G01X1147000Y203900D02*
X1146088D01*
G01X1128073Y205489D02*
X1134600Y198962D01*
G01X1128073Y208202D02*
Y205489D01*
G01X1124650Y211625D02*
X1128073Y208202D01*
G01X1124650Y212570D02*
Y211625D01*
G01X1124915Y213084D02*
X1124650Y212570D01*
G01X1124940Y215367D02*
G02X1124915Y213084I-2040J-1119D01*
G01Y215409D02*
X1124940Y215367D01*
G01X1124896Y215443D02*
X1124915Y215409D01*
G01Y216984D02*
G03X1124896Y215443I1365J-787D01*
G01X1125099Y217303D02*
X1124915Y216984D01*
G01X1125644Y217889D02*
X1125099Y217303D01*
G01X1126366Y218423D02*
X1125644Y217889D01*
G01X1145200Y203727D02*
Y202900D01*
G01X1138046Y210881D02*
X1145200Y203727D01*
G01X1138046Y218771D02*
Y210881D01*
G01X1133297Y217784D02*
G03X1135055Y218934I-257J2312D01*
G01X1133040Y217527D02*
X1133297Y217784D01*
G01X1133040Y216196D02*
Y217527D01*
G01X1130000Y196301D02*
X1130800D01*
G01X1129000Y197301D02*
X1130000Y196301D01*
G01X1129000Y200200D02*
Y197301D01*
G01X1125219Y203981D02*
X1129000Y200200D01*
G01X1125219Y207098D02*
Y203981D01*
G01X1121850Y210467D02*
X1125219Y207098D01*
G01X1121850Y212963D02*
Y210467D01*
G01X1121535Y213459D02*
X1121850Y212963D01*
G01X1121516Y215000D02*
G03X1121535Y213459I1384J-754D01*
G01Y215034D02*
X1121516Y215000D01*
G01X1121560Y215076D02*
X1121535Y215034D01*
G01Y217359D02*
G02X1121560Y215076I-2015J-1164D01*
G01X1121516Y218900D02*
G03X1121535Y217359I1384J-754D01*
G01X1116443Y191423D02*
X1115616Y190596D01*
G01X1116443Y200428D02*
Y191423D01*
G01X1113815Y203056D02*
X1116443Y200428D01*
G01X1113815Y210516D02*
Y203056D01*
G01X1114337Y211038D02*
X1113815Y210516D01*
G01X1114337Y216196D02*
Y211038D01*
G01X1114126Y216984D02*
G02X1114337Y216196I-1365J-788D01*
G01X1113999Y217238D02*
G03X1114126Y216984I2141J912D01*
G01X1112761Y220096D02*
X1113999Y217238D01*
G01X1141816Y212440D02*
Y221512D01*
G01X1147356Y206900D02*
X1141816Y212440D01*
G01X1151900Y206900D02*
X1147356D01*
G01X1126280Y220096D02*
X1126219Y220087D01*
G01X1100606Y219309D02*
X1100581Y219267D01*
G01X1100919Y219860D02*
X1100606Y219309D01*
G01X1102536Y222034D02*
X1100919Y219860D01*
G01X1102621Y222047D02*
X1102536Y222034D01*
G01X1106476Y221774D02*
X1107200Y221172D01*
G01X1105071Y222724D02*
X1106476Y221774D01*
G01X1104636Y224784D02*
G03X1105071Y222724I1365J-788D01*
G01X1104702Y224897D02*
X1104636Y224784D01*
G01X1106001Y227896D02*
X1104702Y224897D01*
G01X1107385Y219343D02*
X1107122Y218887D01*
G01X1107366Y220884D02*
G02X1107385Y219343I-1365J-787D01*
G01X1107200Y221172D02*
X1107366Y220884D01*
G01X1101418Y219215D02*
X1101237Y218900D01*
G01X1101833Y219724D02*
X1101418Y219215D01*
G01X1102448Y220278D02*
X1101833Y219724D01*
G01X1103264Y220608D02*
X1102448Y220278D01*
G01X1104005Y222800D02*
G02X1103264Y220608I-1384J-753D01*
G01X1103918Y222951D02*
X1104005Y222800D01*
G01X1102621Y225947D02*
X1103918Y222951D01*
G01X1145665Y279384D02*
G03X1144359Y280171I-1365J-788D01*
G01X1147629Y278221D02*
G02X1145665Y279384I51J2326D01*
G01X1147724Y278221D02*
X1147629D01*
G01X1149045Y277433D02*
G03X1147724Y278221I-1365J-787D01*
G01X1149451Y277027D02*
X1149045Y277433D01*
G01X1152566Y277027D02*
X1149451D01*
G01X1153839Y278300D02*
X1152566Y277027D01*
G01X1155041Y278300D02*
X1153839D01*
G01X1157051Y276290D02*
X1155041Y278300D01*
G01X1154058Y276265D02*
X1154440Y276647D01*
G01X1150410Y276265D02*
X1154058D01*
G01X1149217Y275072D02*
X1150410Y276265D01*
G01X1147609Y275072D02*
X1149217D01*
G01X1146315Y275859D02*
G03X1147609Y275072I1365J787D01*
G01X1144385Y277021D02*
G02X1146315Y275859I-85J-2325D01*
G01X1144256Y277021D02*
X1144385D01*
G01X1142935Y277809D02*
G03X1144256Y277021I1365J787D01*
G01X1140971Y278972D02*
G02X1142935Y277809I-51J-2326D01*
G01X1140869Y278972D02*
X1140971D01*
G01X1138905Y277809D02*
G02X1140869Y278972I2015J-1163D01*
G01X1137584Y277021D02*
G03X1138905Y277809I-44J1575D01*
G01X1137496Y277021D02*
X1137584D01*
G01X1136175Y277809D02*
G03X1137496Y277021I1365J787D01*
G01X1134211Y278972D02*
G02X1136175Y277809I-51J-2326D01*
G01X1134109Y278972D02*
X1134211D01*
G01X1132145Y277809D02*
G02X1134109Y278972I2015J-1163D01*
G01X1130824Y277021D02*
G03X1132145Y277809I-44J1575D01*
G01X1130736Y277021D02*
X1130824D01*
G01X1129415Y277809D02*
G03X1130736Y277021I1365J787D01*
G01X1127451Y278972D02*
G02X1129415Y277809I-51J-2326D01*
G01X1124311Y278972D02*
X1127451D01*
G01X1138645Y223622D02*
X1141066Y221201D01*
G01X1136335Y223622D02*
X1138645D01*
G01X1134109Y225679D02*
G03X1136335Y223622I2311J268D01*
G01X1133040Y227896D02*
X1134109Y225679D01*
G01X1114776Y221260D02*
G02Y218934I-2015J-1163D01*
G01X1114313Y223727D02*
G03X1114776Y221260I3741J-575D01*
G01X1114126Y224784D02*
G02X1114313Y223727I-1365J-787D01*
G01X1112761Y227896D02*
X1114126Y224784D01*
G01X1117506Y218934D02*
X1117525Y218900D01*
G01X1117481Y218976D02*
X1117506Y218934D01*
G01X1117328Y219317D02*
G03X1117481Y218976I2193J779D01*
G01X1116141Y222047D02*
X1117328Y219317D01*
G01X1120885Y219309D02*
X1120860Y219267D01*
G01X1121198Y219860D02*
X1120885Y219309D01*
G01X1121281Y220171D02*
G02X1121198Y219860I-636J3D01*
G01X1121281Y221836D02*
Y220171D01*
G01X1121492Y222047D02*
X1121281Y221836D01*
G01X1122900Y222047D02*
X1121492D01*
G01X1097876Y219309D02*
X1097901Y219267D01*
G01X1097857Y219343D02*
X1097876Y219309D01*
G01Y220884D02*
G03X1097857Y219343I1365J-787D01*
G01X1097901Y223167D02*
G02X1097876Y220884I-2040J-1119D01*
G01Y223209D02*
X1097901Y223167D01*
G01X1096118Y224359D02*
G02X1097876Y223209I-257J-2312D01*
G01X1095861Y224616D02*
X1096118Y224359D01*
G01X1095861Y225947D02*
Y224616D01*
G01X1097201Y218976D02*
G03X1097245Y218900I1668J915D01*
G01X1097226Y221259D02*
G03X1097201Y218976I2015J-1164D01*
G01X1096089Y223606D02*
G02X1097226Y221259I-228J-1559D01*
G01X1095861Y223378D02*
X1096089Y223606D01*
G01X1095861Y222047D02*
Y223378D01*
G01X1118156Y219309D02*
X1118181Y219267D01*
G01X1118137Y219343D02*
X1118156Y219309D01*
G01Y220884D02*
G03X1118137Y219343I1365J-787D01*
G01X1117843Y223633D02*
G02X1118156Y220884I-1702J-1586D01*
G01X1116141Y225947D02*
X1117843Y223633D01*
G01X1133040Y218765D02*
Y220096D01*
G01X1133268Y218537D02*
X1133040Y218765D01*
G01X1134224Y219057D02*
G02X1133268Y218537I-1184J1039D01*
G01X1134405Y219309D02*
G02X1134224Y219057I-1380J800D01*
G01X1136350Y220472D02*
G03X1134405Y219309I70J-2325D01*
G01X1136420Y220472D02*
X1136350D01*
G01X1136422Y220470D02*
X1136420Y220472D01*
G01X1137407Y220470D02*
X1136422D01*
G01X1138796Y219081D02*
X1137407Y220470D01*
G01X1126853Y218628D02*
X1126366Y218423D01*
G01X1127645Y220884D02*
G02X1126853Y218628I-1365J-788D01*
G01X1127620Y223167D02*
G03X1127645Y220884I2040J-1119D01*
G01Y223209D02*
X1127620Y223167D01*
G01X1127664Y223243D02*
X1127645Y223209D01*
G01Y224784D02*
G02X1127664Y223243I-1365J-787D01*
G01X1127579Y224897D02*
X1127645Y224784D01*
G01X1126280Y227896D02*
X1127579Y224897D01*
G01X1155317Y259472D02*
G02X1157830Y258431I-1J-3556D01*
G01X1154381Y259472D02*
X1155317D01*
G01X1153075Y260259D02*
G03X1154381Y259472I1365J788D01*
G01X1151145Y261421D02*
G02X1153075Y260259I-85J-2325D01*
G01X1151016Y261421D02*
X1151145D01*
G01X1149695Y262209D02*
G03X1151016Y261421I1365J787D01*
G01X1149497Y264673D02*
G03X1149695Y262209I2697J-1023D01*
G01X1148652Y266700D02*
G02X1149497Y264673I-649J-1460D01*
G01X1137095Y219722D02*
X1138046Y218771D01*
G01X1136376Y219722D02*
X1137095D01*
G01X1135055Y218934D02*
G02X1136376Y219722I1365J-787D01*
G01X1154584Y274321D02*
X1157820Y274696D01*
G01X1154369Y274321D02*
X1154584D01*
G01X1153075Y273534D02*
G02X1154369Y274321I1365J-787D01*
G01X1151130Y272371D02*
G03X1153075Y273534I-70J2325D01*
G01X1149045D02*
G03X1150990Y272371I2015J1162D01*
G01X1147751Y274321D02*
G02X1149045Y273534I-71J-1574D01*
G01X1147595Y274321D02*
X1147751D01*
G01X1145665Y275483D02*
G03X1147595Y274321I2015J1163D01*
G01X1144344Y276271D02*
G02X1145665Y275483I-44J-1575D01*
G01X1144215Y276271D02*
X1144344D01*
G01X1142285Y277433D02*
G03X1144215Y276271I2015J1163D01*
G01X1140964Y278221D02*
G02X1142285Y277433I-44J-1575D01*
G01X1140876Y278221D02*
X1140964D01*
G01X1139555Y277433D02*
G02X1140876Y278221I1365J-787D01*
G01X1137625Y276271D02*
G03X1139555Y277433I-85J2325D01*
G01X1137455Y276271D02*
X1137625D01*
G01X1135525Y277433D02*
G03X1137455Y276271I2015J1163D01*
G01X1134204Y278221D02*
G02X1135525Y277433I-44J-1575D01*
G01X1134116Y278221D02*
X1134204D01*
G01X1132795Y277433D02*
G02X1134116Y278221I1365J-787D01*
G01X1130865Y276271D02*
G03X1132795Y277433I-85J2325D01*
G01X1130695Y276271D02*
X1130865D01*
G01X1128765Y277433D02*
G03X1130695Y276271I2015J1163D01*
G01X1127444Y278221D02*
G02X1128765Y277433I-44J-1575D01*
G01X1127400Y278221D02*
X1127444D01*
G01X1121697Y219215D02*
X1121516Y218900D01*
G01X1122112Y219724D02*
X1121697Y219215D01*
G01X1122727Y220278D02*
X1122112Y219724D01*
G01X1123543Y220608D02*
X1122727Y220278D01*
G01X1124284Y222800D02*
G02X1123543Y220608I-1384J-753D01*
G01X1124197Y222951D02*
X1124284Y222800D01*
G01X1122900Y225947D02*
X1124197Y222951D01*
G01X1150684Y278972D02*
X1151060Y278596D01*
G01X1147621Y278972D02*
X1150684D01*
G01X1146315Y279759D02*
G03X1147621Y278972I1365J788D01*
G01X1155316Y258722D02*
G02X1157300Y257900I0J-2806D01*
G01X1154355Y258722D02*
X1155316D01*
G01X1152425Y259884D02*
G03X1154355Y258722I2015J1163D01*
G01X1151119Y260671D02*
G02X1152425Y259884I-59J-1575D01*
G01X1150990Y260671D02*
X1151119D01*
G01X1149045Y261834D02*
G03X1150990Y260671I2015J1162D01*
G01X1146240Y261848D02*
G02X1149045Y261834I1398J-825D01*
G01X1145207Y261207D02*
G03X1146240Y261848I-96J1307D01*
G01X1133040Y230466D02*
Y231797D01*
G01X1133297Y230209D02*
X1133040Y230466D01*
G01X1135055Y229059D02*
G03X1133297Y230209I-2015J-1162D01*
G01X1135080Y226776D02*
G03X1135055Y229059I-2040J1119D01*
G01Y226734D02*
X1135080Y226776D01*
G01X1135036Y226700D02*
X1135055Y226734D01*
G01X1136361Y224372D02*
G02X1135036Y226700I59J1575D01*
G01X1138956Y224372D02*
X1136361D01*
G01X1141816Y221512D02*
X1138956Y224372D01*
G01X1114701Y291877D02*
X1114702Y291878D01*
G01X1114701Y291052D02*
Y291877D01*
G01X1114630Y290981D02*
X1114701Y291052D01*
G01X1114630Y290871D02*
Y290981D01*
G01X1113661Y289902D02*
X1114630Y290871D01*
G01X1113661Y289831D02*
Y289902D01*
G01X1113240Y289410D02*
X1113661Y289831D01*
G01X1113240Y287340D02*
Y289410D01*
G01X1115760Y284820D02*
X1113240Y287340D01*
G01X1121820Y284820D02*
X1115760D01*
G01X1123280Y283360D02*
X1121820Y284820D01*
G01X1125049Y283360D02*
X1123280D01*
G01X1125493Y282916D02*
X1125049Y283360D01*
G01X1127315Y282122D02*
G02X1125493Y282916I99J2715D01*
G01X1127444Y282122D02*
X1127315D01*
G01X1128765Y281334D02*
G03X1127444Y282122I-1365J-787D01*
G01X1130710Y280171D02*
G02X1128765Y281334I70J2325D01*
G01X1130850Y280171D02*
X1130710D01*
G01X1132795Y281334D02*
G02X1130850Y280171I-2015J1162D01*
G01X1134116Y282122D02*
G03X1132795Y281334I44J-1575D01*
G01X1134204Y282122D02*
X1134116D01*
G01X1135525Y281334D02*
G03X1134204Y282122I-1365J-787D01*
G01X1137470Y280171D02*
G02X1135525Y281334I70J2325D01*
G01X1137610Y280171D02*
X1137470D01*
G01X1139555Y281334D02*
G02X1137610Y280171I-2015J1162D01*
G01X1140876Y282122D02*
G03X1139555Y281334I44J-1575D01*
G01X1140964Y282122D02*
X1140876D01*
G01X1142285Y281334D02*
G03X1140964Y282122I-1365J-787D01*
G01X1144230Y280171D02*
G02X1142285Y281334I70J2325D01*
G01X1144359Y280171D02*
X1144230D01*
G01X1115950Y336520D02*
X1108773Y343697D01*
G01X1115950Y328803D02*
Y336520D01*
G01X1122910Y321833D02*
X1115950Y328803D01*
G01X1122910Y320711D02*
Y321833D01*
G01X1126398Y317223D02*
X1122910Y320711D01*
G01X1127457Y317223D02*
X1126398D01*
G01X1128765Y316434D02*
G03X1127457Y317223I-1366J-786D01*
G01X1130710Y315271D02*
G02X1128765Y316434I70J2325D01*
G01X1130839Y315271D02*
X1130710D01*
G01X1132145Y314484D02*
G03X1130839Y315271I-1365J-788D01*
G01X1132164Y312943D02*
G03X1132145Y314484I-1384J754D01*
G01Y312909D02*
X1132164Y312943D01*
G01X1132120Y312867D02*
X1132145Y312909D01*
G01Y310584D02*
G02X1132120Y312867I2015J1164D01*
G01X1132145Y309010D02*
G03Y310584I-1365J787D01*
G01Y306684D02*
G02Y309010I2015J1163D01*
G01X1132164Y305143D02*
G03X1132145Y306684I-1384J754D01*
G01Y305109D02*
X1132164Y305143D01*
G01X1132120Y305067D02*
X1132145Y305109D01*
G01Y302784D02*
G02X1132120Y305067I2015J1164D01*
G01X1134075Y301622D02*
G02X1132145Y302784I85J2325D01*
G01X1134204Y301622D02*
X1134075D01*
G01X1135525Y300834D02*
G03X1134204Y301622I-1365J-787D01*
G01X1137470Y299671D02*
G02X1135525Y300834I70J2325D01*
G01X1138184Y299671D02*
X1137470D01*
G01X1139377Y298478D02*
X1138184Y299671D01*
G01X1141688Y298478D02*
X1139377D01*
G01X1142875Y299665D02*
X1141688Y298478D01*
G01X1145445Y299665D02*
X1142875D01*
G01X1146632Y298478D02*
X1145445Y299665D01*
G01X1148330Y298478D02*
X1146632D01*
G01X1149517Y299665D02*
X1148330Y298478D01*
G01X1152185Y299665D02*
X1149517D01*
G01X1153372Y298478D02*
X1152185Y299665D01*
G01X1155132Y298478D02*
X1153372D01*
G01X1157083Y296527D02*
X1155132Y298478D01*
G01X1144385Y280921D02*
G02X1146315Y279759I-85J-2325D01*
G01X1144256Y280921D02*
X1144385D01*
G01X1142935Y281709D02*
G03X1144256Y280921I1365J787D01*
G01X1140990Y282872D02*
G02X1142935Y281709I-70J-2325D01*
G01X1140850Y282872D02*
X1140990D01*
G01X1138905Y281709D02*
G02X1140850Y282872I2015J-1162D01*
G01X1137584Y280921D02*
G03X1138905Y281709I-44J1575D01*
G01X1137496Y280921D02*
X1137584D01*
G01X1136175Y281709D02*
G03X1137496Y280921I1365J787D01*
G01X1134230Y282872D02*
G02X1136175Y281709I-70J-2325D01*
G01X1134090Y282872D02*
X1134230D01*
G01X1132145Y281709D02*
G02X1134090Y282872I2015J-1162D01*
G01X1130824Y280921D02*
G03X1132145Y281709I-44J1575D01*
G01X1130736Y280921D02*
X1130824D01*
G01X1129415Y281709D02*
G03X1130736Y280921I1365J787D01*
G01X1127470Y282872D02*
G02X1129415Y281709I-70J-2325D01*
G01X1127356Y282872D02*
X1127470D01*
G01X1126035Y283660D02*
G03X1127356Y282872I1365J787D01*
G01X1125415Y284280D02*
X1126035Y283660D01*
G01X1123859Y284280D02*
X1125415D01*
G01X1120169Y287970D02*
X1123859Y284280D01*
G01X1118810Y287970D02*
X1120169D01*
G01X1116096Y290684D02*
X1118810Y287970D01*
G01X1116096Y294005D02*
Y290684D01*
G01X1121614Y321622D02*
X1115113Y328123D01*
G01X1121614Y319927D02*
Y321622D01*
G01X1124230Y317311D02*
X1121614Y319927D01*
G01X1124230Y315100D02*
Y317311D01*
G01X1125690Y313640D02*
X1124230Y315100D01*
G01X1128100Y313640D02*
X1125690D01*
G01X1129120Y312620D02*
X1128100Y313640D01*
G01X1129120Y301437D02*
Y312620D01*
G01X1130130Y300427D02*
X1129120Y301437D01*
G01X1130763Y300427D02*
X1130130D01*
G01X1133450Y297740D02*
X1130763Y300427D01*
G01X1135520Y297740D02*
X1133450D01*
G01X1136733Y296527D02*
X1135520Y297740D01*
G01X1138190Y296527D02*
X1136733D01*
G01X1139379Y297716D02*
X1138190Y296527D01*
G01X1142304Y297716D02*
X1139379D01*
G01X1143499Y296521D02*
X1142304Y297716D01*
G01X1144944Y296521D02*
X1143499D01*
G01X1146139Y297716D02*
X1144944Y296521D01*
G01X1148330Y297716D02*
X1146139D01*
G01X1150026Y296020D02*
X1148330Y297716D01*
G01X1151800Y296020D02*
X1150026D01*
G01X1154004Y293816D02*
X1151800Y296020D01*
G01X1155981Y293816D02*
X1154004D01*
G01X1157170Y292627D02*
X1155981Y293816D01*
G01X1118765Y280165D02*
X1120235D01*
G01X1126071Y402294D02*
G03X1126036Y404560I-2050J1102D01*
G01Y402234D02*
X1126071Y402294D01*
G01X1126036Y400660D02*
G02Y402234I1364J787D01*
G01X1126071Y398394D02*
G03X1126036Y400660I-2050J1102D01*
G01Y398334D02*
X1126071Y398394D01*
G01X1126036Y396760D02*
G02Y398334I1364J787D01*
G01X1126071Y394494D02*
G03X1126036Y396760I-2050J1102D01*
G01Y394434D02*
X1126071Y394494D01*
G01X1126036Y392860D02*
G02Y394434I1364J787D01*
G01X1126071Y390595D02*
G03X1126036Y392860I-2049J1101D01*
G01X1125906Y390314D02*
G03X1126071Y390595I-3642J2328D01*
G01X1125903Y390309D02*
X1125906Y390314D01*
G01X1124021Y387796D02*
G03X1125903Y390309I-11321J10439D01*
G01X1121981Y402276D02*
G02X1122006Y404559I2040J1119D01*
G01Y402234D02*
X1121981Y402276D01*
G01X1122025Y402200D02*
X1122006Y402234D01*
G01Y400659D02*
G03X1122025Y402200I-1365J787D01*
G01X1121981Y398376D02*
G02X1122006Y400659I2040J1119D01*
G01Y398334D02*
X1121981Y398376D01*
G01X1122025Y398300D02*
X1122006Y398334D01*
G01Y396759D02*
G03X1122025Y398300I-1365J787D01*
G01X1121981Y394476D02*
G02X1122006Y396759I2040J1119D01*
G01Y394434D02*
X1121981Y394476D01*
G01X1122025Y394400D02*
X1122006Y394434D01*
G01Y392859D02*
G03X1122025Y394400I-1365J787D01*
G01X1121611Y392407D02*
G03X1122006Y392859I-981J1255D01*
G01X1121376Y392255D02*
G03X1121611Y392407I-735J1394D01*
G01X1119562Y390896D02*
G02X1121376Y392255I5140J-4970D01*
G01X1119526Y390861D02*
X1119562Y390896D01*
G01X1119276Y388959D02*
G02X1119526Y390861I1364J788D01*
G01X1121154Y387337D02*
G02X1119276Y388959I1394J3512D01*
G01X1122006Y385059D02*
G03X1121154Y387337I-1365J788D01*
G01X1121940Y384946D02*
X1122006Y385059D01*
G01X1120641Y381947D02*
X1121940Y384946D01*
G01X1108451Y402293D02*
G02X1108173Y403395I2049J1103D01*
G01X1108513Y402185D02*
X1108451Y402293D01*
G01X1108486Y400659D02*
G03X1108513Y402185I-1365J787D01*
G01X1108451Y398393D02*
G02X1108486Y400659I2050J1102D01*
G01X1108513Y398285D02*
X1108451Y398393D01*
G01X1108486Y396759D02*
G03X1108513Y398285I-1365J787D01*
G01X1108451Y394493D02*
G02X1108486Y396759I2050J1102D01*
G01X1108513Y394385D02*
X1108451Y394493D01*
G01X1108486Y392859D02*
G03X1108513Y394385I-1365J787D01*
G01X1108285Y392408D02*
G02X1108486Y392859I2266J-740D01*
G01Y390536D02*
G02X1108285Y392408I2015J1163D01*
G01X1108486Y388962D02*
G03Y390536I-1365J787D01*
G01X1108369Y386866D02*
G02X1108486Y388962I2132J932D01*
G01Y386636D02*
G02X1108369Y386866I1906J1114D01*
G01X1108696Y386426D02*
X1108486Y386636D01*
G01X1108696Y384246D02*
Y386426D01*
G01X1109046Y383896D02*
X1108696Y384246D01*
G01X1110501Y383896D02*
X1109046D01*
G01X1152904Y349178D02*
X1169495D01*
G01X1151717Y350365D02*
X1152904Y349178D01*
G01X1150403Y350365D02*
X1151717D01*
G01X1149216Y349178D02*
X1150403Y350365D01*
G01X1146144Y349178D02*
X1149216D01*
G01X1144957Y350365D02*
X1146144Y349178D01*
G01X1143643Y350365D02*
X1144957D01*
G01X1142456Y349178D02*
X1143643Y350365D01*
G01X1139384Y349178D02*
X1142456D01*
G01X1138197Y350365D02*
X1139384Y349178D01*
G01X1136883Y350365D02*
X1138197D01*
G01X1135696Y349178D02*
X1136883Y350365D01*
G01X1132624Y349178D02*
X1135696D01*
G01X1131437Y350365D02*
X1132624Y349178D01*
G01X1130123Y350365D02*
X1131437D01*
G01X1128936Y349178D02*
X1130123Y350365D01*
G01X1125865Y349178D02*
X1128936D01*
G01X1123916Y351127D02*
X1125865Y349178D01*
G01X1123371Y351127D02*
X1123916D01*
G01X1121420Y353078D02*
X1123371Y351127D01*
G01X1119991Y353078D02*
X1121420D01*
G01X1119072Y353997D02*
X1119991Y353078D01*
G01X1119072Y357004D02*
Y353997D01*
G01X1117911Y358165D02*
X1119072Y357004D01*
G01X1116611Y358165D02*
X1117911D01*
G01X1115418Y356972D02*
X1116611Y358165D01*
G01X1113822Y356972D02*
X1115418D01*
G01X1112516Y357759D02*
G03X1113822Y356972I1365J788D01*
G01X1108486Y357759D02*
G02X1112516I2015J-1163D01*
G01X1105756D02*
G03X1108486I1365J788D01*
G01X1101726D02*
G02X1105756I2015J-1163D01*
G01X1098996D02*
G03X1101726I1365J788D01*
G01X1125385Y402609D02*
G03Y404183I-1364J787D01*
G01X1125350Y402549D02*
X1125385Y402609D01*
G01Y400283D02*
G02X1125350Y402549I2015J1164D01*
G01X1125385Y398709D02*
G03Y400283I-1364J787D01*
G01X1125360Y398666D02*
X1125385Y398709D01*
G01X1125350Y398649D02*
X1125360Y398666D01*
G01X1125385Y396383D02*
G02X1125350Y398649I2015J1164D01*
G01X1125385Y394809D02*
G03Y396383I-1364J787D01*
G01X1125350Y394749D02*
X1125385Y394809D01*
G01Y392483D02*
G02X1125350Y394749I2015J1164D01*
G01X1125385Y390910D02*
G03Y392483I-1363J787D01*
G01X1125218Y390648D02*
G03X1125385Y390910I-3270J2269D01*
G01X1123637Y389340D02*
G03X1125218Y390648I-1546J3478D01*
G01X1123538Y389296D02*
X1123637Y389340D01*
G01X1122637Y387043D02*
G02X1123538Y389296I1384J753D01*
G01X1122724Y386892D02*
X1122637Y387043D01*
G01X1124021Y383896D02*
X1122724Y386892D01*
G01X1097066Y355021D02*
X1096896D01*
G01X1098996Y353859D02*
G03X1097066Y355021I-2015J-1163D01*
G01X1100302Y353072D02*
G02X1098996Y353859I59J1575D01*
G01X1100431Y353072D02*
X1100302D01*
G01X1102376Y351909D02*
G03X1100431Y353072I-2015J-1162D01*
G01X1103697Y351121D02*
G02X1102376Y351909I44J1575D01*
G01X1103826Y351121D02*
X1103697D01*
G01X1105756Y349959D02*
G03X1103826Y351121I-2015J-1163D01*
G01X1107062Y349172D02*
G02X1105756Y349959I59J1575D01*
G01X1109052Y349172D02*
X1107062D01*
G01X1109774Y348450D02*
X1109052Y349172D01*
G01X1115000Y348450D02*
X1109774D01*
G01X1118172Y345278D02*
X1115000Y348450D01*
G01X1121420Y345278D02*
X1118172D01*
G01X1123371Y343327D02*
X1121420Y345278D01*
G01X1125561Y343327D02*
X1123371D01*
G01X1126750Y344516D02*
X1125561Y343327D01*
G01X1128181Y344516D02*
X1126750D01*
G01X1130130Y346465D02*
X1128181Y344516D01*
G01X1131635Y346465D02*
X1130130D01*
G01X1133150Y344950D02*
X1131635Y346465D01*
G01X1135375Y344950D02*
X1133150D01*
G01X1136890Y346465D02*
X1135375Y344950D01*
G01X1139083Y346465D02*
X1136890D01*
G01X1140348Y345200D02*
X1139083Y346465D01*
G01X1142385Y345200D02*
X1140348D01*
G01X1143650Y346465D02*
X1142385Y345200D01*
G01X1144950Y346465D02*
X1143650D01*
G01X1146365Y345050D02*
X1144950Y346465D01*
G01X1148995Y345050D02*
X1146365D01*
G01X1150410Y346465D02*
X1148995Y345050D01*
G01X1152085Y346465D02*
X1150410D01*
G01X1153600Y344950D02*
X1152085Y346465D01*
G01X1157400Y344950D02*
X1153600D01*
G01X1102684Y399967D02*
X1099356Y403295D01*
G01X1102684Y393020D02*
Y399967D01*
G01X1102310Y392368D02*
X1102684Y393020D01*
G01X1100361Y389747D02*
X1102310Y392368D01*
G01X1145787Y402149D02*
X1148236Y404598D01*
G01X1145787Y400983D02*
Y402149D01*
G01X1144300Y399496D02*
X1145787Y400983D01*
G01X1111885Y402642D02*
G03X1111866Y404183I-1384J754D01*
G01Y402608D02*
X1111885Y402642D01*
G01X1111866Y400282D02*
G02Y402608I2015J1163D01*
G01X1111885Y400248D02*
X1111866Y400282D01*
G01Y398707D02*
G03X1111885Y400248I-1365J787D01*
G01X1111841Y396424D02*
G02X1111866Y398707I2040J1119D01*
G01Y396382D02*
X1111841Y396424D01*
G01X1111866Y394808D02*
G03Y396382I-1365J787D01*
G01X1111765Y394614D02*
G02X1111866Y394808I1938J-886D01*
G01Y392484D02*
G02X1111765Y394614I2015J1163D01*
G01X1111866Y390912D02*
G03Y392484I-1362J786D01*
G01Y388586D02*
G02Y390912I2015J1163D01*
G01X1112325Y386097D02*
G03X1111866Y388586I-3743J597D01*
G01X1112460Y381947D02*
X1113881D01*
G01X1112106Y382301D02*
X1112460Y381947D01*
G01X1112106Y383791D02*
Y382301D01*
G01X1112391Y384076D02*
X1112106Y383791D01*
G01X1112391Y385338D02*
Y384076D01*
G01X1112325Y386097D02*
G03X1112391Y385338I1556J-247D01*
G01X1142937Y401788D02*
Y403339D01*
G01X1142285Y400659D02*
X1142937Y401788D01*
G01X1142285Y398333D02*
G02Y400659I2015J1163D01*
G01Y396759D02*
G03Y398333I-1365J787D01*
G01X1141776Y395801D02*
X1142285Y396759D01*
G01X1140920Y393647D02*
X1141776Y395801D01*
G01X1129505Y402783D02*
X1128987Y403301D01*
G01X1129505Y398042D02*
Y402783D01*
G01X1128765Y396759D02*
X1129505Y398042D01*
G01X1128740Y394476D02*
G02X1128765Y396759I2040J1119D01*
G01Y394434D02*
X1128740Y394476D01*
G01X1128784Y394400D02*
X1128765Y394434D01*
G01Y392859D02*
G03X1128784Y394400I-1365J787D01*
G01X1128740Y390576D02*
G02X1128765Y392859I2040J1119D01*
G01Y390534D02*
X1128740Y390576D01*
G01X1128784Y390500D02*
X1128765Y390534D01*
G01Y388959D02*
G03X1128784Y390500I-1365J787D01*
G01X1130523Y385484D02*
G02X1128765Y388959I257J2312D01*
G01X1130780Y385227D02*
X1130523Y385484D01*
G01X1130780Y383896D02*
Y385227D01*
G01X1096922Y354271D02*
G03X1095616Y353484I59J-1575D01*
G01X1097040Y354271D02*
X1096922D01*
G01X1098346Y353484D02*
G03X1097040Y354271I-1365J-788D01*
G01X1100276Y352322D02*
G02X1098346Y353484I85J2325D01*
G01X1100405Y352322D02*
X1100276D01*
G01X1101726Y351534D02*
G03X1100405Y352322I-1365J-787D01*
G01X1103671Y350371D02*
G02X1101726Y351534I70J2325D01*
G01X1103800Y350371D02*
X1103671D01*
G01X1105106Y349584D02*
G03X1103800Y350371I-1365J-788D01*
G01X1107036Y348422D02*
G02X1105106Y349584I85J2325D01*
G01X1107978Y348422D02*
X1107036D01*
G01X1108773Y347627D02*
X1107978Y348422D01*
G01X1108773Y343697D02*
Y347627D01*
G01X1133105Y394972D02*
Y404175D01*
G01X1132776Y394400D02*
X1133105Y394972D01*
G01X1132795Y392859D02*
G02X1132776Y394400I1365J787D01*
G01X1132861Y392746D02*
X1132795Y392859D01*
G01X1134160Y389747D02*
X1132861Y392746D01*
G01X1101936Y399657D02*
X1098608Y402985D01*
G01X1101936Y393222D02*
Y399657D01*
G01X1101726Y392859D02*
X1101936Y393222D01*
G01X1100420Y392072D02*
G03X1101726Y392859I-59J1575D01*
G01X1100361Y392072D02*
X1100420D01*
G01X1099644Y391658D02*
G02X1100361Y392072I717J-414D01*
G01X1098977Y390500D02*
X1099644Y391658D01*
G01X1098996Y388959D02*
G02X1098977Y390500I1365J787D01*
G01X1099021Y386676D02*
G03X1098996Y388959I-2040J1119D01*
G01Y386634D02*
X1099021Y386676D01*
G01X1098977Y386600D02*
X1098996Y386634D01*
G01Y385059D02*
G02X1098977Y386600I1365J787D01*
G01X1099062Y384946D02*
X1098996Y385059D01*
G01X1100361Y381947D02*
X1099062Y384946D01*
G01X1142187Y402714D02*
Y403651D01*
G01X1140920Y401447D02*
X1142187Y402714D01*
G01X1109108Y402657D02*
G02X1108924Y403396I1392J739D01*
G01X1109109Y402657D02*
X1109108D01*
G01X1109171Y402549D02*
X1109109Y402657D01*
G01X1109136Y400283D02*
G03X1109171Y402549I-2015J1164D01*
G01X1109109Y398757D02*
G02X1109136Y400283I1392J739D01*
G01X1109161Y398666D02*
X1109109Y398757D01*
G01X1109171Y398649D02*
X1109161Y398666D01*
G01X1109136Y396383D02*
G03X1109171Y398649I-2015J1164D01*
G01X1109109Y394857D02*
G02X1109136Y396383I1392J739D01*
G01Y394809D02*
X1109109Y394857D01*
G01X1109161Y394767D02*
X1109136Y394809D01*
G01Y392484D02*
G03X1109161Y394767I-2015J1164D01*
G01X1109000Y392178D02*
G02X1109136Y392484I1462J-467D01*
G01Y390912D02*
G02X1109000Y392178I1365J787D01*
G01X1110501Y387796D02*
G03X1109136Y390912I-14773J-4615D01*
G01X1104989Y401473D02*
X1101626Y404836D01*
G01X1104989Y394045D02*
Y401473D01*
G01X1105316Y393718D02*
X1104989Y394045D01*
G01X1105316Y391740D02*
Y393718D01*
G01X1103785Y390121D02*
G03X1105316Y391740I-44J1575D01*
G01X1103741Y390121D02*
X1103785D01*
G01X1103024Y389707D02*
G02X1103741Y390121I717J-414D01*
G01X1102376Y388584D02*
X1103024Y389707D01*
G01X1102357Y387043D02*
G02X1102376Y388584I1384J754D01*
G01X1102444Y386892D02*
X1102357Y387043D01*
G01X1103741Y383896D02*
X1102444Y386892D01*
G01X1112541Y402274D02*
G03X1112516Y404559I-2040J1120D01*
G01Y402232D02*
X1112541Y402274D01*
G01X1112516Y400658D02*
G02Y402232I1365J787D01*
G01Y398332D02*
G03Y400658I-2015J1163D01*
G01X1112497Y396791D02*
G02X1112516Y398332I1384J754D01*
G01Y396757D02*
X1112497Y396791D01*
G01X1112541Y396715D02*
X1112516Y396757D01*
G01Y394432D02*
G03X1112541Y396715I-2015J1164D01*
G01X1112432Y394265D02*
G02X1112516Y394432I1308J-553D01*
G01Y392859D02*
G02X1112432Y394265I1377J788D01*
G01X1112728Y392368D02*
G03X1112516Y392859I-2227J-670D01*
G01X1113881Y389747D02*
X1112728Y392368D01*
G01X1132355Y395173D02*
Y403864D01*
G01X1132120Y394767D02*
X1132355Y395173D01*
G01X1132145Y392484D02*
G02X1132120Y394767I2015J1164D01*
G01X1132164Y390943D02*
G03X1132145Y392484I-1384J754D01*
G01Y390909D02*
X1132164Y390943D01*
G01X1132120Y390867D02*
X1132145Y390909D01*
G01Y388584D02*
G02X1132120Y390867I2015J1164D01*
G01X1132164Y387043D02*
G03X1132145Y388584I-1384J754D01*
G01Y387009D02*
X1132164Y387043D01*
G01X1132120Y386967D02*
X1132145Y387009D01*
G01Y384684D02*
G02X1132120Y386967I2015J1164D01*
G01X1132211Y384568D02*
X1132145Y384684D01*
G01X1134160Y381947D02*
X1132211Y384568D01*
G01X1130255Y397840D02*
Y403094D01*
G01X1129415Y396384D02*
X1130255Y397840D01*
G01X1129396Y394843D02*
G02X1129415Y396384I1384J754D01*
G01Y394809D02*
X1129396Y394843D01*
G01X1129440Y394767D02*
X1129415Y394809D01*
G01Y392484D02*
G03X1129440Y394767I-2015J1164D01*
G01X1129396Y390943D02*
G02X1129415Y392484I1384J754D01*
G01Y390909D02*
X1129396Y390943D01*
G01X1129440Y390867D02*
X1129415Y390909D01*
G01Y388584D02*
G03X1129440Y390867I-2015J1164D01*
G01X1130552Y386237D02*
G02X1129415Y388584I228J1559D01*
G01X1130780Y386465D02*
X1130552Y386237D01*
G01X1130780Y387796D02*
Y386465D01*
G01X1105737Y401783D02*
X1102374Y405146D01*
G01X1105737Y394355D02*
Y401783D01*
G01X1106064Y394028D02*
X1105737Y394355D01*
G01X1106064Y391754D02*
Y394028D01*
G01X1106068Y391750D02*
X1106064Y391754D01*
G01X1105786Y390584D02*
G03X1106068Y391750I-2045J1112D01*
G01X1105758Y390533D02*
X1105786Y390584D01*
G01X1105755Y390533D02*
X1105758D01*
G01X1105690Y390418D02*
X1105755Y390533D01*
G01X1103741Y387796D02*
X1105690Y390418D01*
G01X1145260Y402684D02*
X1147924Y405348D01*
G01X1145256Y402684D02*
X1145260D01*
G01X1145256Y402683D02*
Y402684D01*
G01X1143077Y400504D02*
X1145256Y402683D01*
G01X1142935Y400284D02*
X1143077Y400504D01*
G01X1142916Y398743D02*
G02X1142935Y400284I1384J754D01*
G01X1143496Y397705D02*
X1142916Y398743D01*
G01X1144300Y396901D02*
X1143496Y397705D01*
G01X1144300Y395597D02*
Y396901D01*
G01X1122637Y402643D02*
G02X1122656Y404184I1384J754D01*
G01Y402609D02*
X1122637Y402643D01*
G01X1122681Y402567D02*
X1122656Y402609D01*
G01Y400284D02*
G03X1122681Y402567I-2015J1164D01*
G01X1122637Y398743D02*
G02X1122656Y400284I1384J754D01*
G01Y398709D02*
X1122637Y398743D01*
G01X1122681Y398667D02*
X1122656Y398709D01*
G01Y396384D02*
G03X1122681Y398667I-2015J1164D01*
G01X1122637Y394843D02*
G02X1122656Y396384I1384J754D01*
G01Y394809D02*
X1122637Y394843D01*
G01X1122681Y394767D02*
X1122656Y394809D01*
G01Y392484D02*
G03X1122681Y394767I-2015J1164D01*
G01X1122590Y392368D02*
X1122656Y392484D01*
G01X1120641Y389747D02*
X1122590Y392368D01*
G01X1142331Y348428D02*
X1143106Y347653D01*
G01X1140282Y348428D02*
X1142331D01*
G01X1139069Y347215D02*
X1140282Y348428D01*
G01X1136579Y347215D02*
X1139069D01*
G01X1136578Y347214D02*
X1136579Y347215D01*
G01X1136012Y347214D02*
X1136578D01*
G01X1134810Y348416D02*
X1136012Y347214D01*
G01X1132619Y348416D02*
X1134810D01*
G01X1131430Y347227D02*
X1132619Y348416D01*
G01X1130130Y347227D02*
X1131430D01*
G01X1128941Y348416D02*
X1130130Y347227D01*
G01X1126750Y348416D02*
X1128941D01*
G01X1125561Y347227D02*
X1126750Y348416D01*
G01X1123371Y347227D02*
X1125561D01*
G01X1121420Y349178D02*
X1123371Y347227D01*
G01X1119991Y349178D02*
X1121420D01*
G01X1118042Y351127D02*
X1119991Y349178D01*
G01X1116611Y351127D02*
X1118042D01*
G01X1115692Y352046D02*
X1116611Y351127D01*
G01X1115692Y355055D02*
Y352046D01*
G01X1114525Y356222D02*
X1115692Y355055D01*
G01X1113796Y356222D02*
X1114525D01*
G01X1111866Y357384D02*
G03X1113796Y356222I2015J1163D01*
G01X1109136Y357384D02*
G02X1111866I1365J-788D01*
G01X1105106D02*
G03X1109136I2015J1163D01*
G01X1102376D02*
G02X1105106I1365J-788D01*
G01X1098346D02*
G03X1102376I2015J1163D01*
G01X1095616D02*
G02X1098346I1365J-788D01*
G01X1127712Y418277D02*
X1128700D01*
G01X1126499Y417064D02*
X1127712Y418277D01*
G01X1126499Y411047D02*
Y417064D01*
G01X1126036Y410034D02*
X1126499Y411047D01*
G01X1126036Y408460D02*
G02Y410034I1364J787D01*
G01X1126071Y406194D02*
G03X1126036Y408460I-2050J1102D01*
G01Y406134D02*
X1126071Y406194D01*
G01X1126036Y404560D02*
G02Y406134I1364J787D01*
G01X1121931Y417736D02*
X1121276Y418391D01*
G01X1121931Y410169D02*
Y417736D01*
G01X1122025Y410000D02*
X1121931Y410169D01*
G01X1122006Y408459D02*
G03X1122025Y410000I-1365J787D01*
G01X1121981Y406176D02*
G02X1122006Y408459I2040J1119D01*
G01Y406134D02*
X1121981Y406176D01*
G01X1122025Y406100D02*
X1122006Y406134D01*
G01Y404559D02*
G03X1122025Y406100I-1365J787D01*
G01X1104574Y413838D02*
X1103676Y414736D01*
G01X1104574Y410611D02*
Y413838D01*
G01X1108173Y407012D02*
X1104574Y410611D01*
G01X1108173Y403395D02*
Y407012D01*
G01X1127122Y418747D02*
Y420136D01*
G01X1125749Y417374D02*
X1127122Y418747D01*
G01X1125749Y411218D02*
Y417374D01*
G01X1125350Y410349D02*
X1125749Y411218D01*
G01X1125385Y408083D02*
G02X1125350Y410349I2015J1164D01*
G01X1125385Y406509D02*
G03Y408083I-1364J787D01*
G01X1125350Y406449D02*
X1125385Y406509D01*
G01Y404183D02*
G02X1125350Y406449I2015J1164D01*
G01X1099356Y403295D02*
Y408495D01*
G01X1148236Y404598D02*
X1160952D01*
G01X1109544Y414682D02*
X1108776Y415450D01*
G01X1109544Y413588D02*
Y414682D01*
G01X1111554Y411578D02*
X1109544Y413588D01*
G01X1111554Y405347D02*
Y411578D01*
G01X1111866Y404183D02*
G02X1111554Y405347I2015J1164D01*
G01X1147048Y407450D02*
X1159600D01*
G01X1142937Y403339D02*
X1147048Y407450D01*
G01X1128987Y409998D02*
X1134819Y415830D01*
G01X1128987Y403301D02*
Y409998D01*
G01X1141600Y422611D02*
Y423500D01*
G01X1134819Y415830D02*
X1141600Y422611D01*
G01X1145862Y419550D02*
X1147062D01*
G01X1132585Y406273D02*
X1145862Y419550D01*
G01X1132585Y404695D02*
Y406273D01*
G01X1133105Y404175D02*
X1132585Y404695D01*
G01X1098608Y402985D02*
Y408185D01*
G01X1146736Y408200D02*
X1159288D01*
G01X1142187Y403651D02*
X1146736Y408200D01*
G01X1105324Y413804D02*
X1106226Y414706D01*
G01X1105324Y410919D02*
Y413804D01*
G01X1108924Y407319D02*
X1105324Y410919D01*
G01X1108924Y403396D02*
Y407319D01*
G01X1098556Y416285D02*
X1097700Y417141D01*
G01X1098556Y412359D02*
Y416285D01*
G01X1101626Y409289D02*
X1098556Y412359D01*
G01X1101626Y404836D02*
Y409289D01*
G01X1110295Y414454D02*
X1111326Y415485D01*
G01X1110295Y413900D02*
Y414454D01*
G01X1112305Y411890D02*
X1110295Y413900D01*
G01X1112305Y405346D02*
Y411890D01*
G01X1112516Y404559D02*
G02X1112305Y405346I1365J788D01*
G01X1145400Y420149D02*
Y421150D01*
G01X1131837Y406586D02*
X1145400Y420149D01*
G01X1131837Y404382D02*
Y406586D01*
G01X1132355Y403864D02*
X1131837Y404382D01*
G01X1142000Y421950D02*
X1143300D01*
G01X1129737Y409687D02*
X1142000Y421950D01*
G01X1129737Y403612D02*
Y409687D01*
G01X1130255Y403094D02*
X1129737Y403612D01*
G01X1099304Y416171D02*
X1100274Y417141D01*
G01X1099304Y412669D02*
Y416171D01*
G01X1102374Y409599D02*
X1099304Y412669D01*
G01X1102374Y405146D02*
Y409599D01*
G01X1147924Y405348D02*
X1160640D01*
G01X1122681Y418079D02*
X1123826Y419224D01*
G01X1122681Y410367D02*
Y418079D01*
G01X1122656Y408084D02*
G03X1122681Y410367I-2015J1164D01*
G01X1122637Y406543D02*
G02X1122656Y408084I1384J754D01*
G01Y406509D02*
X1122637Y406543D01*
G01X1122681Y406467D02*
X1122656Y406509D01*
G01Y404184D02*
G03X1122681Y406467I-2015J1164D01*
G01X1158481Y276290D02*
X1157051D01*
G01X1160075Y274696D02*
X1158481Y276290D01*
G01X1178953Y272747D02*
X1174719D01*
G01X1180590Y274384D02*
X1178953Y272747D01*
G01X1182781Y274384D02*
X1180590D01*
G01X1184365Y272800D02*
X1182781Y274384D01*
G01X1185619Y272800D02*
X1184365D01*
G01X1187222Y274403D02*
X1185619Y272800D01*
G01X1189009Y274403D02*
X1187222D01*
G01X1190700Y272712D02*
X1189009Y274403D01*
G01X1192188Y272712D02*
X1190700D01*
G01X1193722Y271178D02*
X1192188Y272712D01*
G01X1195011Y271178D02*
X1193722D01*
G01X1196364Y271959D02*
G02X1195011Y271178I-1353J782D01*
G01X1198294Y273121D02*
G03X1196364Y271959I85J-2325D01*
G01X1198464Y273121D02*
X1198294D01*
G01X1200394Y271959D02*
G03X1198464Y273121I-2015J-1163D01*
G01X1201700Y271172D02*
G02X1200394Y271959I59J1575D01*
G01X1201829Y271172D02*
X1201700D01*
G01X1203774Y270009D02*
G03X1201829Y271172I-2015J-1162D01*
G01X1205095Y269221D02*
G02X1203774Y270009I44J1575D01*
G01X1205224Y269221D02*
X1205095D01*
G01X1207154Y268059D02*
G03X1205224Y269221I-2015J-1163D01*
G01X1208460Y267272D02*
G02X1207154Y268059I59J1575D01*
G01X1209993Y267272D02*
X1208460D01*
G01X1160130Y263200D02*
X1159390Y262460D01*
G01X1163419Y263200D02*
X1160130D01*
G01X1164578Y264359D02*
X1163419Y263200D01*
G01X1164578Y264781D02*
Y264359D01*
G01X1166520Y266723D02*
X1164578Y264781D01*
G01X1168345Y266723D02*
X1166520D01*
G01X1170171Y268549D02*
X1168345Y266723D01*
G01X1171728Y268549D02*
X1170171D01*
G01X1173900Y270721D02*
X1171728Y268549D01*
G01X1175113Y270721D02*
X1173900D01*
G01X1176553Y269281D02*
X1175113Y270721D01*
G01X1176679Y269281D02*
X1176553D01*
G01X1177150Y268810D02*
X1176679Y269281D01*
G01X1179053Y268810D02*
X1177150D01*
G01X1180898Y270655D02*
X1179053Y268810D01*
G01X1182252Y270655D02*
X1180898D01*
G01X1182781Y270126D02*
X1182252Y270655D01*
G01X1182781Y269910D02*
Y270126D01*
G01X1183793Y268898D02*
X1182781Y269910D01*
G01X1185792Y268898D02*
X1183793D01*
G01X1187464Y270570D02*
X1185792Y268898D01*
G01X1188966Y270570D02*
X1187464D01*
G01X1190407Y269129D02*
X1188966Y270570D01*
G01X1192726Y269129D02*
X1190407D01*
G01X1194021Y270424D02*
X1192726Y269129D01*
G01X1195006Y270424D02*
X1194021D01*
G01X1197014Y271584D02*
G02X1195006Y270424I-2008J1158D01*
G01X1198320Y272371D02*
G03X1197014Y271584I59J-1575D01*
G01X1198438Y272371D02*
X1198320D01*
G01X1199744Y271584D02*
G03X1198438Y272371I-1365J-788D01*
G01X1201674Y270422D02*
G02X1199744Y271584I85J2325D01*
G01X1201803Y270422D02*
X1201674D01*
G01X1203124Y269634D02*
G03X1201803Y270422I-1365J-787D01*
G01X1205069Y268471D02*
G02X1203124Y269634I70J2325D01*
G01X1205198Y268471D02*
X1205069D01*
G01X1206504Y267684D02*
G03X1205198Y268471I-1365J-788D01*
G01X1208434Y266522D02*
G02X1206504Y267684I85J2325D01*
G01X1209303Y266522D02*
X1208434D01*
G01X1210897Y264928D02*
X1209303Y266522D01*
G01X1210897Y262880D02*
Y264928D01*
G01X1169113Y256482D02*
X1167960Y257147D01*
G01X1169196Y256172D02*
X1169113Y256482D01*
G01X1167960Y255572D02*
G03X1169196Y256172I-1J1575D01*
G01X1167890Y255572D02*
X1167960D01*
G01X1165945Y254409D02*
G02X1167890Y255572I2015J-1162D01*
G01X1164637Y253621D02*
G03X1165945Y254409I-57J1575D01*
G01X1164523Y253621D02*
X1164637D01*
G01X1163216Y254409D02*
G03X1164523Y253621I1365J787D01*
G01X1163215Y254409D02*
X1163216D01*
G01X1163111Y254574D02*
G02X1163215Y254409I-1914J-1322D01*
G01X1161607Y256411D02*
G02X1163111Y254574I-10656J-10258D01*
G01X1161088Y256930D02*
X1161607Y256411D01*
G01X1159055Y257772D02*
G02X1161088Y256930I0J-2875D01*
G01X1158752Y257772D02*
X1159055D01*
G01X1158303Y257958D02*
G03X1158752Y257772I449J449D01*
G01X1157830Y258431D02*
X1158303Y257958D01*
G01X1170186Y255861D02*
X1171339Y255196D01*
G01X1169834Y255766D02*
X1170186Y255861D01*
G01X1168058Y254822D02*
G03X1169834Y255766I-97J2325D01*
G01X1167916Y254822D02*
X1168058D01*
G01X1166595Y254034D02*
G02X1167916Y254822I1365J-787D01*
G01X1164650Y252871D02*
G03X1166595Y254034I-70J2325D01*
G01X1164510Y252871D02*
X1164650D01*
G01X1162565Y254034D02*
G03X1164510Y252871I2015J1162D01*
G01X1162315Y254362D02*
G02X1162565Y254034I-1118J-1111D01*
G01X1160638Y256039D02*
X1162315Y254362D01*
G01X1160293Y256383D02*
X1160638Y256039D01*
G01X1159650Y256650D02*
G02X1160293Y256383I-1J-910D01*
G01X1157772Y257428D02*
G03X1159650Y256650I1878J1878D01*
G01X1157300Y257900D02*
X1157772Y257428D01*
G01X1194238Y341012D02*
X1192300Y342950D01*
G01X1195740Y341012D02*
X1194238D01*
G01X1197561Y339191D02*
X1195740Y341012D01*
G01X1199227Y339191D02*
X1197561D01*
G01X1200900Y340864D02*
X1199227Y339191D01*
G01X1203052Y340864D02*
X1200900D01*
G01X1205683Y338233D02*
X1203052Y340864D01*
G01X1158601Y296527D02*
X1157083D01*
G01X1160550Y294578D02*
X1158601Y296527D01*
G01X1161850Y294578D02*
X1160550D01*
G01X1163043Y295771D02*
X1161850Y294578D01*
G01X1164639Y295771D02*
X1163043D01*
G01X1165945Y294984D02*
G03X1164639Y295771I-1365J-788D01*
G01X1167875Y293822D02*
G02X1165945Y294984I85J2325D01*
G01X1168606Y293822D02*
X1167875D01*
G01X1170218Y292210D02*
X1168606Y293822D01*
G01X1172535Y292210D02*
X1170218D01*
G01X1174068Y290677D02*
X1172535Y292210D01*
G01X1175697Y290677D02*
X1174068D01*
G01X1176886Y291866D02*
X1175697Y290677D01*
G01X1179124Y291866D02*
X1176886D01*
G01X1181073Y289917D02*
X1179124Y291866D01*
G01X1182622Y289917D02*
X1181073D01*
G01X1183818Y288721D02*
X1182622Y289917D01*
G01X1184944Y288721D02*
X1183818D01*
G01X1186874Y287559D02*
G03X1184944Y288721I-2015J-1163D01*
G01X1188180Y286772D02*
G02X1186874Y287559I59J1575D01*
G01X1188309Y286772D02*
X1188180D01*
G01X1190254Y285609D02*
G03X1188309Y286772I-2015J-1162D01*
G01X1191575Y284821D02*
G02X1190254Y285609I44J1575D01*
G01X1191704Y284821D02*
X1191575D01*
G01X1193634Y283659D02*
G03X1191704Y284821I-2015J-1163D01*
G01X1194940Y282872D02*
G02X1193634Y283659I59J1575D01*
G01X1195069Y282872D02*
X1194940D01*
G01X1197014Y281709D02*
G03X1195069Y282872I-2015J-1162D01*
G01X1198335Y280921D02*
G02X1197014Y281709I44J1575D01*
G01X1198423Y280921D02*
X1198335D01*
G01X1199744Y281709D02*
G02X1198423Y280921I-1365J787D01*
G01X1201689Y282872D02*
G03X1199744Y281709I70J-2325D01*
G01X1201818Y282872D02*
X1201689D01*
G01X1203124Y283659D02*
G02X1201818Y282872I-1365J788D01*
G01X1205680Y284894D02*
G03X1203124Y283659I-502J-2224D01*
G01X1207311Y283648D02*
G03X1205680Y284894I-2172J-1152D01*
G01X1208162Y282872D02*
G02X1207311Y283648I657J1575D01*
G01X1208904Y282872D02*
X1208162D01*
G01X1210834Y281710D02*
G03X1208904Y282872I-2015J-1163D01*
G01X1211440Y281360D02*
G02X1210834Y281710I0J699D01*
G01X1168326Y317978D02*
X1169835Y318603D01*
G01X1167546Y317978D02*
X1168326D01*
G01X1165983Y318625D02*
X1167546Y317978D01*
G01X1158470Y292627D02*
X1157170D01*
G01X1159659Y293816D02*
X1158470Y292627D01*
G01X1161850Y293816D02*
X1159659D01*
G01X1163801Y291865D02*
X1161850Y293816D01*
G01X1165230Y291865D02*
X1163801D01*
G01X1167179Y289916D02*
X1165230Y291865D01*
G01X1168612Y289916D02*
X1167179D01*
G01X1169428Y289100D02*
X1168612Y289916D01*
G01X1184853Y287965D02*
X1183605D01*
G01X1184859Y287971D02*
X1184853Y287965D01*
G01X1184918Y287971D02*
X1184859D01*
G01X1186224Y287184D02*
G03X1184918Y287971I-1365J-788D01*
G01X1188154Y286022D02*
G02X1186224Y287184I85J2325D01*
G01X1188283Y286022D02*
X1188154D01*
G01X1189604Y285234D02*
G03X1188283Y286022I-1365J-787D01*
G01X1191549Y284071D02*
G02X1189604Y285234I70J2325D01*
G01X1191678Y284071D02*
X1191549D01*
G01X1192984Y283284D02*
G03X1191678Y284071I-1365J-788D01*
G01X1194914Y282122D02*
G02X1192984Y283284I85J2325D01*
G01X1195043Y282122D02*
X1194914D01*
G01X1196364Y281334D02*
G03X1195043Y282122I-1365J-787D01*
G01X1198309Y280171D02*
G02X1196364Y281334I70J2325D01*
G01X1198449Y280171D02*
X1198309D01*
G01X1200394Y281334D02*
G02X1198449Y280171I-2015J1162D01*
G01X1201715Y282122D02*
G03X1200394Y281334I44J-1575D01*
G01X1201844Y282122D02*
X1201715D01*
G01X1203774Y283284D02*
G02X1201844Y282122I-2015J1163D01*
G01X1205563Y284149D02*
G03X1203774Y283284I-258J-1749D01*
G01X1206647Y283295D02*
G03X1205563Y284149I-1508J-799D01*
G01X1208019Y282122D02*
G02X1206647Y283295I800J2325D01*
G01X1208863Y282122D02*
X1208019D01*
G01X1210184Y281334D02*
G03X1208863Y282122I-1365J-787D01*
G01X1211490Y280580D02*
G02X1210184Y281334I0J1508D01*
G01X1212979Y280580D02*
X1211490D01*
G01X1193601Y349040D02*
X1195608D01*
G01X1192276Y350365D02*
X1193601Y349040D01*
G01X1190962Y350365D02*
X1192276D01*
G01X1189775Y349178D02*
X1190962Y350365D01*
G01X1186703Y349178D02*
X1189775D01*
G01X1185516Y350365D02*
X1186703Y349178D01*
G01X1184202Y350365D02*
X1185516D01*
G01X1182250Y352317D02*
X1184202Y350365D01*
G01X1180828Y352317D02*
X1182250D01*
G01X1179998Y351487D02*
X1180828Y352317D01*
G01X1179109Y351487D02*
X1179998D01*
G01X1178749Y351127D02*
X1179109Y351487D01*
G01X1177449Y351127D02*
X1178749D01*
G01X1176259Y352317D02*
X1177449Y351127D01*
G01X1173948Y352317D02*
X1176259D01*
G01X1171996Y350365D02*
X1173948Y352317D01*
G01X1170682Y350365D02*
X1171996D01*
G01X1169495Y349178D02*
X1170682Y350365D01*
G01X1158100Y344250D02*
X1157400Y344950D01*
G01X1167044Y344250D02*
X1158100D01*
G01X1167978Y345184D02*
X1167044Y344250D01*
G01X1169079Y345184D02*
X1167978D01*
G01X1170360Y346465D02*
X1169079Y345184D01*
G01X1172035Y346465D02*
X1170360D01*
G01X1173222Y345278D02*
X1172035Y346465D01*
G01X1175978Y345278D02*
X1173222D01*
G01X1177300Y346600D02*
X1175978Y345278D01*
G01X1178614Y346600D02*
X1177300D01*
G01X1180614Y344600D02*
X1178614Y346600D01*
G01X1182433Y344600D02*
X1180614D01*
G01X1183930Y343103D02*
X1182433Y344600D01*
G01X1185748Y343103D02*
X1183930D01*
G01X1187161Y344516D02*
X1185748Y343103D01*
G01X1189203Y344516D02*
X1187161D01*
G01X1190771Y342950D02*
X1189203Y344516D01*
G01X1192300Y342950D02*
X1190771D01*
G01X1171250Y410350D02*
X1172100Y409500D01*
G01X1166704Y410350D02*
X1171250D01*
G01X1160952Y404598D02*
X1166704Y410350D01*
G01X1171800Y414650D02*
X1172350Y414100D01*
G01X1166800Y414650D02*
X1171800D01*
G01X1159600Y407450D02*
X1166800Y414650D01*
G01X1171800Y415400D02*
X1172400Y416000D01*
G01X1166488Y415400D02*
X1171800D01*
G01X1159288Y408200D02*
X1166488Y415400D01*
G01X1171199Y411100D02*
X1172099Y412000D01*
G01X1166392Y411100D02*
X1171199D01*
G01X1160640Y405348D02*
X1166392Y411100D01*
G01X1225681Y175599D02*
X1223100Y178180D01*
G01X1231640Y175599D02*
X1225681D01*
G01X1233902Y173337D02*
X1231640Y175599D01*
G01X1488560Y144760D02*
X1488800Y145000D01*
G01X1488560Y138334D02*
Y144760D01*
G01X1489223Y137671D02*
X1488560Y138334D01*
G01X1489223Y116938D02*
Y137671D01*
G01X1492200Y113961D02*
X1489223Y116938D01*
G01X1492200Y111466D02*
Y113961D01*
G01X1487770Y107036D02*
X1492200Y111466D01*
G01X1487770Y104608D02*
Y107036D01*
G01X1489053Y103325D02*
X1487770Y104608D01*
G01X1485880Y385920D02*
X1485156Y385196D01*
G01X1486041Y386066D02*
G03X1485880Y385920I1480J-1794D01*
G01X1488688Y386289D02*
G03X1486041Y386066I-1163J-2015D01*
G01X1490262Y386289D02*
G02X1488688I-787J1365D01*
G01X1492588D02*
G03X1490262I-1163J-2015D01*
G01X1494162D02*
G02X1492588I-787J1365D01*
G01X1496488D02*
G03X1494162I-1163J-2015D01*
G01X1498062D02*
G02X1496488I-787J1365D01*
G01X1500388D02*
G03X1498062I-1163J-2015D01*
G01X1501962D02*
G02X1500388I-787J1365D01*
G01X1504288D02*
G03X1501962I-1163J-2015D01*
G01X1505862D02*
G02X1504288I-787J1365D01*
G01X1508188D02*
G03X1505862I-1163J-2015D01*
G01X1509762D02*
G02X1508188I-787J1365D01*
G01X1512088D02*
G03X1509762I-1163J-2015D01*
G01X1513662D02*
G02X1512088I-787J1365D01*
G01X1515988D02*
G03X1513662I-1163J-2015D01*
G01X1517562D02*
G02X1515988I-787J1365D01*
G01X1519888D02*
G03X1517562I-1163J-2015D01*
G01X1521462D02*
G02X1519888I-787J1365D01*
G01X1523788D02*
G03X1521462I-1163J-2015D01*
G01X1525362D02*
G02X1523788I-787J1365D01*
G01X1527688D02*
G03X1525362I-1163J-2015D01*
G01Y389019D02*
G03X1528850Y390949I1163J2015D01*
G01X1523788Y389019D02*
G02X1525362I787J-1365D01*
G01X1521462D02*
G03X1523788I1163J2015D01*
G01X1519888D02*
G02X1521462I787J-1365D01*
G01X1517562D02*
G03X1519888I1163J2015D01*
G01X1515988D02*
G02X1517562I787J-1365D01*
G01X1513662D02*
G03X1515988I1163J2015D01*
G01X1512088D02*
G02X1513662I787J-1365D01*
G01X1509762D02*
G03X1512088I1163J2015D01*
G01X1508188D02*
G02X1509762I787J-1365D01*
G01X1505862D02*
G03X1508188I1163J2015D01*
G01X1504288D02*
G02X1505862I787J-1365D01*
G01X1501962D02*
G03X1504288I1163J2015D01*
G01X1500388D02*
G02X1501962I787J-1365D01*
G01X1498062D02*
G03X1500388I1163J2015D01*
G01X1496488D02*
G02X1498062I787J-1365D01*
G01X1494162D02*
G03X1496488I1163J2015D01*
G01X1492588D02*
G02X1494162I787J-1365D01*
G01X1490867Y388026D02*
X1492588Y389019D01*
G01X1489475Y387654D02*
G03X1490867Y388026I1J2786D01*
G01X1486420Y385396D02*
X1485909Y384885D01*
G01X1486738Y385639D02*
G03X1486420Y385396I753J-1315D01*
G01X1488312Y385639D02*
G03X1486738I-787J-1365D01*
G01X1490638D02*
G02X1488312I-1163J2015D01*
G01X1492212D02*
G03X1490638I-787J-1365D01*
G01X1494538D02*
G02X1492212I-1163J2015D01*
G01X1496112D02*
G03X1494538I-787J-1365D01*
G01X1498438D02*
G02X1496112I-1163J2015D01*
G01X1500012D02*
G03X1498438I-787J-1365D01*
G01X1502338D02*
G02X1500012I-1163J2015D01*
G01X1503912D02*
G03X1502338I-787J-1365D01*
G01X1506238D02*
G02X1503912I-1163J2015D01*
G01X1507812D02*
G03X1506238I-787J-1365D01*
G01X1510138D02*
G02X1507812I-1163J2015D01*
G01X1511712D02*
G03X1510138I-787J-1365D01*
G01X1514038D02*
G02X1511712I-1163J2015D01*
G01X1515612D02*
G03X1514038I-787J-1365D01*
G01X1517938D02*
G02X1515612I-1163J2015D01*
G01X1519512D02*
G03X1517938I-787J-1365D01*
G01X1521838D02*
G02X1519512I-1163J2015D01*
G01X1523412D02*
G03X1521838I-787J-1365D01*
G01X1525738D02*
G02X1523412I-1163J2015D01*
G01X1527312D02*
G03X1525738I-787J-1365D01*
G01X1500617Y390662D02*
G03X1499225Y391034I-1391J-2414D01*
G01X1502338Y389669D02*
X1500617Y390662D01*
G01X1503912Y389669D02*
G02X1502338I-787J1365D01*
G01X1506238D02*
G03X1503912I-1163J-2015D01*
G01X1507812D02*
G02X1506238I-787J1365D01*
G01X1510138D02*
G03X1507812I-1163J-2015D01*
G01X1511712D02*
G02X1510138I-787J1365D01*
G01X1514038D02*
G03X1511712I-1163J-2015D01*
G01X1515612D02*
G02X1514038I-787J1365D01*
G01X1517938D02*
G03X1515612I-1163J-2015D01*
G01X1519512D02*
G02X1517938I-787J1365D01*
G01X1521838D02*
G03X1519512I-1163J-2015D01*
G01X1523412D02*
G02X1521838I-787J1365D01*
G01X1525738D02*
G03X1523412I-1163J-2015D01*
G01X1528100Y390990D02*
G02X1525738Y389669I-1575J44D01*
G01X1526900Y470630D02*
G02X1527688Y471951I1575J-44D01*
G01X1526900Y470501D02*
Y470630D01*
G01X1525738Y468571D02*
G03X1526900Y470501I-1163J2015D01*
G01X1524950Y467250D02*
G02X1525738Y468571I1575J-44D01*
G01X1524950Y467121D02*
Y467250D01*
G01X1523788Y465190D02*
G03X1524950Y467121I-1023J1931D01*
G01X1526150Y470671D02*
G02X1527312Y472601I2325J-85D01*
G01X1526150Y470542D02*
Y470671D01*
G01X1525362Y469221D02*
G03X1526150Y470542I-787J1365D01*
G01X1524200Y467291D02*
G02X1525362Y469221I2325J-85D01*
G01X1524200Y467162D02*
Y467291D01*
G01X1523412Y465842D02*
G03X1524200Y467162I-712J1320D01*
G01X1523600Y472276D02*
G03X1522625Y470651I975J-1690D01*
G01X1524575Y473901D02*
G02X1523600Y472276I-1950J65D01*
G01X1524575Y474031D02*
Y473901D01*
G01X1525550Y475656D02*
G03X1524575Y474031I975J-1690D01*
G01X1526525Y477281D02*
G02X1525550Y475656I-1950J65D01*
G01X1526525Y477411D02*
Y477281D01*
G01X1527500Y479036D02*
G03X1526525Y477411I975J-1690D01*
G01Y484041D02*
G03X1527500Y482416I1950J65D01*
G01X1526525Y484171D02*
Y484041D01*
G01X1527500Y485796D02*
G03X1526525Y484171I975J-1690D01*
G01X1530050Y387610D02*
G02X1527688Y386289I-1575J44D01*
G01X1530050Y387739D02*
Y387610D01*
G01X1530425Y391034D02*
G03X1530050Y387739I14289J-3295D01*
G01X1535488Y402539D02*
G03X1536650Y404469I-1163J2015D01*
G01X1534700Y401218D02*
G02X1535488Y402539I1575J-44D01*
G01X1534700Y401089D02*
Y401218D01*
G01X1533538Y399159D02*
G03X1534700Y401089I-1163J2015D01*
G01X1532750Y397838D02*
G02X1533538Y399159I1575J-44D01*
G01X1532750Y397709D02*
Y397838D01*
G01X1531588Y395779D02*
G03X1532750Y397709I-1163J2015D01*
G01X1530800Y394458D02*
G02X1531588Y395779I1575J-44D01*
G01X1530800Y394329D02*
Y394458D01*
G01X1529638Y392399D02*
G03X1530800Y394329I-1163J2015D01*
G01X1528850Y391078D02*
G02X1529638Y392399I1575J-44D01*
G01X1528850Y390949D02*
Y391078D01*
G01X1530800Y387569D02*
G02X1527312Y385639I-2325J85D01*
G01X1530800Y387698D02*
Y387569D01*
G01X1531588Y389019D02*
G03X1530800Y387698I787J-1365D01*
G01X1532738Y390778D02*
G02X1531588Y389019I-2312J256D01*
G01X1533538Y392399D02*
G03X1532738Y390778I812J-1409D01*
G01X1535112Y392399D02*
G03X1533538I-787J-1365D01*
G01X1538600Y394329D02*
G02X1535112Y392399I-2325J85D01*
G01X1538615Y394749D02*
X1538600Y394329D01*
G01X1542125Y397794D02*
G03X1538615Y394749I-336J-3158D01*
G01X1560709Y406323D02*
X1565145Y401887D01*
G01X1528100Y391119D02*
Y390990D01*
G01X1529262Y393049D02*
G03X1528100Y391119I1163J-2015D01*
G01X1530050Y394370D02*
G02X1529262Y393049I-1575J44D01*
G01X1530050Y394499D02*
Y394370D01*
G01X1531212Y396429D02*
G03X1530050Y394499I1163J-2015D01*
G01X1532000Y397750D02*
G02X1531212Y396429I-1575J44D01*
G01X1532000Y397879D02*
Y397750D01*
G01X1533162Y399809D02*
G03X1532000Y397879I1163J-2015D01*
G01X1533950Y401130D02*
G02X1533162Y399809I-1575J44D01*
G01X1533950Y401259D02*
Y401130D01*
G01X1535112Y403189D02*
G03X1533950Y401259I1163J-2015D01*
G01X1572556Y452005D02*
X1574126Y453575D01*
G01X1571165Y452005D02*
X1572556D01*
G01X1570588Y451671D02*
X1571165Y452005D01*
G01X1568262Y451671D02*
G03X1570588I1163J2015D01*
G01X1566688D02*
G02X1568262I787J-1365D01*
G01X1564592Y451554D02*
G03X1566688Y451671I932J2132D01*
G01X1564240Y451460D02*
X1564592Y451554D01*
G01X1563575Y450306D02*
X1564240Y451460D01*
G01X1539513Y465652D02*
G03X1536275Y463826I106685J-192966D01*
G01X1565192Y453108D02*
X1565525Y453686D01*
G01X1564860Y452532D02*
X1565192Y453108D01*
G01X1564944Y452222D02*
X1564860Y452532D01*
G01X1566312Y452321D02*
G02X1564944Y452222I-786J1365D01*
G01X1568638Y452321D02*
G03X1566312I-1163J-2015D01*
G01X1570212D02*
G02X1568638I-787J1365D01*
G01X1571949Y453325D02*
X1570212Y452321D01*
G01X1574858Y441008D02*
X1576425Y442575D01*
G01X1572163Y441008D02*
X1574858D01*
G01X1570212Y441531D02*
G03X1572163Y441008I1951J3376D01*
G01X1568638Y441531D02*
G02X1570212I787J-1365D01*
G01X1566312D02*
G03X1568638I1163J2015D01*
G01X1564738D02*
G02X1566312I787J-1365D01*
G01X1562412D02*
G03X1564738I1163J2015D01*
G01X1560050Y440210D02*
G02X1562412Y441531I1575J-44D01*
G01X1560050Y440081D02*
Y440210D01*
G01X1558888Y438151D02*
G03X1560050Y440081I-1163J2015D01*
G01X1558100Y436787D02*
G02X1558888Y438151I1574J0D01*
G01X1558100Y435490D02*
Y436787D01*
G01X1559106Y433466D02*
G02X1558100Y435490I1533J2024D01*
G01X1560050Y431679D02*
G03X1559106Y433466I-2325J-85D01*
G01X1560050Y431509D02*
Y431679D01*
G01X1558888Y429579D02*
G03X1560050Y431509I-1163J2015D01*
G01X1558100Y428258D02*
G02X1558888Y429579I1575J-44D01*
G01X1558100Y428129D02*
Y428258D01*
G01X1556938Y426199D02*
G03X1558100Y428129I-1163J2015D01*
G01X1556372Y425642D02*
G02X1556938Y426199I1353J-808D01*
G01X1553765Y423035D02*
X1556372Y425642D01*
G01X1553765Y420668D02*
Y423035D01*
G01X1551727Y418630D02*
X1553765Y420668D01*
G01X1551727Y417273D02*
Y418630D01*
G01X1554206Y414794D02*
X1551727Y417273D01*
G01X1554206Y414044D02*
Y414794D01*
G01X1556216Y412034D02*
X1554206Y414044D01*
G01X1556216Y411828D02*
Y412034D01*
G01X1556150Y411280D02*
X1556216Y411828D01*
G01X1556150Y411278D02*
Y411280D01*
G01X1556151Y411231D02*
X1556150Y411278D01*
G01X1554988Y409299D02*
G03X1556151Y411231I-1162J2016D01*
G01X1554200Y407978D02*
G02X1554988Y409299I1575J-44D01*
G01X1554200Y407849D02*
Y407978D01*
G01X1550712Y405919D02*
G03X1554200Y407849I1163J2015D01*
G01X1549138Y405919D02*
G02X1550712I787J-1365D01*
G01X1546812D02*
G03X1549138I1163J2015D01*
G01X1545238D02*
G02X1546812I787J-1365D01*
G01X1542912D02*
G03X1545238I1163J2015D01*
G01X1541338D02*
G02X1542912I787J-1365D01*
G01X1539012D02*
G03X1541338I1163J2015D01*
G01X1536650Y404598D02*
G02X1539012Y405919I1575J-44D01*
G01X1536650Y404469D02*
Y404598D01*
G01X1532375Y463826D02*
X1533040Y464980D01*
G01X1560265Y406323D02*
X1560709D01*
G01X1558888Y406569D02*
G03X1560265Y406323I1029J1786D01*
G01X1558888Y409299D02*
G03Y406569I787J-1365D01*
G01X1560050Y411229D02*
G02X1558888Y409299I-2325J85D01*
G01X1560050Y411358D02*
Y411229D01*
G01X1560838Y412679D02*
G03X1560050Y411358I787J-1365D01*
G01X1561244Y413085D02*
X1560838Y412679D01*
G01X1561244Y415280D02*
Y413085D01*
G01X1563365Y417401D02*
X1561244Y415280D01*
G01X1563365Y418598D02*
Y417401D01*
G01X1565144Y420377D02*
X1563365Y418598D01*
G01X1565144Y422104D02*
Y420377D01*
G01X1563867Y423381D02*
X1565144Y422104D01*
G01X1563867Y424811D02*
Y423381D01*
G01X1562000Y426678D02*
X1563867Y424811D01*
G01X1562000Y428258D02*
Y426678D01*
G01X1562788Y429579D02*
G03X1562000Y428258I787J-1365D01*
G01X1563950Y431509D02*
G02X1562788Y429579I-2325J85D01*
G01X1563950Y433402D02*
Y431509D01*
G01X1535900Y404510D02*
G02X1535112Y403189I-1575J44D01*
G01X1535900Y404639D02*
Y404510D01*
G01X1539388Y406569D02*
G03X1535900Y404639I-1163J-2015D01*
G01X1540962Y406569D02*
G02X1539388I-787J1365D01*
G01X1543288D02*
G03X1540962I-1163J-2015D01*
G01X1544862D02*
G02X1543288I-787J1365D01*
G01X1547188D02*
G03X1544862I-1163J-2015D01*
G01X1548762D02*
G02X1547188I-787J1365D01*
G01X1551088D02*
G03X1548762I-1163J-2015D01*
G01X1553450Y407890D02*
G02X1551088Y406569I-1575J44D01*
G01X1553450Y409470D02*
Y407890D01*
G01X1552256Y410664D02*
X1553450Y409470D01*
G01X1552256Y412094D02*
Y410664D01*
G01X1550306Y414044D02*
X1552256Y412094D01*
G01X1550306Y415344D02*
Y414044D01*
G01X1550978Y416016D02*
X1550306Y415344D01*
G01X1550978Y418368D02*
Y416016D01*
G01X1550139Y419207D02*
X1550978Y418368D01*
G01X1550139Y421808D02*
Y419207D01*
G01X1554835Y426504D02*
X1550139Y421808D01*
G01X1556105Y426504D02*
X1554835D01*
G01X1556562Y426849D02*
G03X1556105Y426504I1163J-2015D01*
G01X1557350Y428170D02*
G02X1556562Y426849I-1575J44D01*
G01X1557350Y428299D02*
Y428170D01*
G01X1558512Y430229D02*
G03X1557350Y428299I1163J-2015D01*
G01X1558512Y432959D02*
G02Y430229I-787J-1365D01*
G01X1557346Y435488D02*
G03X1558512Y432959I3326J0D01*
G01X1557346Y436782D02*
Y435488D01*
G01X1558512Y438801D02*
G03X1557346Y436782I1164J-2019D01*
G01X1559300Y440122D02*
G02X1558512Y438801I-1575J44D01*
G01X1559300Y440251D02*
Y440122D01*
G01X1562788Y442181D02*
G03X1559300Y440251I-1163J-2015D01*
G01X1564362Y442181D02*
G02X1562788I-787J1365D01*
G01X1566688D02*
G03X1564362I-1163J-2015D01*
G01X1568262D02*
G02X1566688I-787J1365D01*
G01X1570588D02*
G03X1568262I-1163J-2015D01*
G01X1572162D02*
G02X1570588I-787J1365D01*
G01X1573325Y442492D02*
G03X1572162Y442181I-1J-2327D01*
G01X1575242Y442492D02*
X1573325D01*
G01X1575750Y443000D02*
X1575242Y442492D01*
G01X1587573Y443973D02*
Y445300D01*
G01X1582771Y439171D02*
X1587573Y443973D01*
G01X1571091Y439171D02*
X1582771D01*
G01X1570359Y438439D02*
X1571091Y439171D01*
G01X1566049Y438439D02*
X1570359D01*
G01X1563200Y435590D02*
X1566049Y438439D01*
G01X1563200Y431550D02*
Y435590D01*
G01X1562412Y430229D02*
G03X1563200Y431550I-787J1365D01*
G01X1561250Y428299D02*
G02X1562412Y430229I2325J-85D01*
G01X1561250Y428170D02*
Y428299D01*
G01X1561244Y428164D02*
X1561250Y428170D01*
G01X1561244Y427564D02*
Y428164D01*
G01X1560325Y426645D02*
X1561244Y427564D01*
G01X1560315Y426645D02*
X1560325D01*
G01X1560056Y426386D02*
X1560315Y426645D01*
G01X1560056Y424184D02*
Y426386D01*
G01X1561545Y422695D02*
X1560056Y424184D01*
G01X1561545Y420213D02*
Y422695D01*
G01X1559822Y418490D02*
X1561545Y420213D01*
G01X1559822Y417232D02*
Y418490D01*
G01X1558106Y415516D02*
X1559822Y417232D01*
G01X1558106Y410166D02*
Y415516D01*
G01X1557672Y409118D02*
X1558106Y410166D01*
G01X1558512Y405919D02*
G02X1557672Y409118I1163J2015D01*
G01X1559160Y403275D02*
G03X1558512Y405919I-1590J1012D01*
G01X1557155Y459457D02*
X1557725Y460446D01*
G01X1557155Y458940D02*
Y459457D01*
G01X1558100Y457151D02*
G03X1557155Y458940I-2325J-84D01*
G01X1558100Y457022D02*
Y457151D01*
G01X1558888Y455701D02*
G02X1558100Y457022I787J1365D01*
G01X1561927Y453370D02*
G03X1558888Y455701I-10359J-10358D01*
G01X1561929Y453368D02*
X1561927Y453370D01*
G01X1561929Y450882D02*
Y453368D01*
G01X1562000Y450391D02*
G03X1561929Y450882I-2325J-86D01*
G01X1562000Y450262D02*
Y450391D01*
G01X1564362Y448941D02*
G02X1562000Y450262I-787J1365D01*
G01X1566688Y448941D02*
G03X1564362I-1163J-2015D01*
G01X1568262D02*
G02X1566688I-787J1365D01*
G01X1570588D02*
G03X1568262I-1163J-2015D01*
G01X1572162D02*
G02X1570588I-787J1365D01*
G01X1573317Y449250D02*
G03X1572162Y448941I0J-2312D01*
G01X1539880Y466503D02*
G02X1539513Y465652I-733J-189D01*
G01X1539812Y467462D02*
G03X1539880Y466503I2653J-294D01*
G01X1540962Y469221D02*
G03X1539812Y467462I1162J-2015D01*
G01X1541750Y470542D02*
G02X1540962Y469221I-1575J44D01*
G01X1541750Y470671D02*
Y470542D01*
G01X1542912Y472601D02*
G03X1541750Y470671I1163J-2015D01*
G01X1543700Y473922D02*
G02X1542912Y472601I-1575J44D01*
G01X1543700Y474051D02*
Y473922D01*
G01X1544862Y475981D02*
G03X1543700Y474051I1163J-2015D01*
G01X1545650Y477302D02*
G02X1544862Y475981I-1575J44D01*
G01X1545650Y477431D02*
Y477302D01*
G01X1546812Y479361D02*
G03X1545650Y477431I1163J-2015D01*
G01X1546812Y482091D02*
G02Y479361I-787J-1365D01*
G01X1545650Y484021D02*
G03X1546812Y482091I2325J85D01*
G01X1545650Y484191D02*
Y484021D01*
G01X1546812Y486121D02*
G03X1545650Y484191I1163J-2015D01*
G01X1547600Y487442D02*
G02X1546812Y486121I-1575J44D01*
G01X1547600Y489251D02*
Y487442D01*
G01X1532750Y487530D02*
G02X1533159Y488546I1466J0D01*
G01X1532750Y487401D02*
Y487530D01*
G01X1531588Y485471D02*
G03X1532750Y487401I-1163J2015D01*
G01X1531588Y482741D02*
G02Y485471I787J1365D01*
G01X1532643Y481428D02*
G03X1531588Y482741I-2218J-702D01*
G01X1532750Y480641D02*
G03X1532643Y481428I-2327J84D01*
G01X1531588Y478711D02*
G03X1532750Y480641I-1163J2015D01*
G01X1530800Y477390D02*
G02X1531588Y478711I1575J-44D01*
G01X1530800Y477261D02*
Y477390D01*
G01X1529638Y475331D02*
G03X1530800Y477261I-1163J2015D01*
G01X1528850Y474010D02*
G02X1529638Y475331I1575J-44D01*
G01X1528850Y473881D02*
Y474010D01*
G01X1527688Y471951D02*
G03X1528850Y473881I-1163J2015D01*
G01X1536275Y487551D02*
G02X1536794Y488813I1950J-64D01*
G01X1536275Y487421D02*
Y487551D01*
G01X1535300Y485796D02*
G03X1536275Y487421I-975J1690D01*
G01X1534325Y484171D02*
G02X1535300Y485796I1950J-65D01*
G01X1534325Y484041D02*
Y484171D01*
G01X1535300Y482416D02*
G02X1534325Y484041I975J1690D01*
G01X1536275Y480791D02*
G03X1535300Y482416I-1950J-65D01*
G01X1536275Y480661D02*
Y480791D01*
G01X1535300Y479036D02*
G03X1536275Y480661I-975J1690D01*
G01X1534325Y477411D02*
G02X1535300Y479036I1950J-65D01*
G01X1534325Y477281D02*
Y477411D01*
G01X1533350Y475656D02*
G03X1534325Y477281I-975J1690D01*
G01X1532375Y474031D02*
G02X1533350Y475656I1950J-65D01*
G01X1532375Y473901D02*
Y474031D01*
G01X1531400Y472276D02*
G03X1532375Y473901I-975J1690D01*
G01X1531063Y472030D02*
G02X1531400Y472276I1312J-1444D01*
G01X1548350Y488938D02*
X1549368Y489956D01*
G01X1548350Y487401D02*
Y488938D01*
G01X1547188Y485471D02*
G03X1548350Y487401I-1163J2015D01*
G01X1547188Y482741D02*
G02Y485471I787J1365D01*
G01X1548350Y480811D02*
G03X1547188Y482741I-2325J-85D01*
G01X1548350Y480641D02*
Y480811D01*
G01X1547188Y478711D02*
G03X1548350Y480641I-1163J2015D01*
G01X1546400Y477390D02*
G02X1547188Y478711I1575J-44D01*
G01X1546400Y477261D02*
Y477390D01*
G01X1545238Y475331D02*
G03X1546400Y477261I-1163J2015D01*
G01X1544450Y474010D02*
G02X1545238Y475331I1575J-44D01*
G01X1544450Y473881D02*
Y474010D01*
G01X1543288Y471951D02*
G03X1544450Y473881I-1163J2015D01*
G01X1542500Y470630D02*
G02X1543288Y471951I1575J-44D01*
G01X1542500Y470501D02*
Y470630D01*
G01X1541975Y469112D02*
G03X1542500Y470501I-1800J1474D01*
G01X1542125Y467206D02*
G02X1541975Y469112I918J1031D01*
G01X1543700Y487442D02*
Y488770D01*
G01X1542912Y486121D02*
G03X1543700Y487442I-787J1365D01*
G01X1541750Y484191D02*
G02X1542912Y486121I2325J-85D01*
G01X1541750Y484021D02*
Y484191D01*
G01X1542912Y482091D02*
G02X1541750Y484021I1163J2015D01*
G01X1543700Y480770D02*
G03X1542912Y482091I-1575J-44D01*
G01X1543700Y480682D02*
Y480770D01*
G01X1542912Y479361D02*
G03X1543700Y480682I-787J1365D01*
G01X1541750Y477431D02*
G02X1542912Y479361I2325J-85D01*
G01X1541750Y477302D02*
Y477431D01*
G01X1540962Y475981D02*
G03X1541750Y477302I-787J1365D01*
G01X1539800Y474051D02*
G02X1540962Y475981I2325J-85D01*
G01X1539800Y473922D02*
Y474051D01*
G01X1539012Y472601D02*
G03X1539800Y473922I-787J1365D01*
G01X1537850Y470671D02*
G02X1539012Y472601I2325J-85D01*
G01X1537850Y470542D02*
Y470671D01*
G01X1537494Y469587D02*
G03X1537850Y470542I-1219J998D01*
G01X1536650Y467291D02*
G02X1537494Y469587I3545J0D01*
G01X1536650Y467121D02*
Y467291D01*
G01X1533392Y465074D02*
G03X1536650Y467121I933J2132D01*
G01X1533040Y464980D02*
X1533392Y465074D01*
G01X1532000Y487571D02*
G02X1532675Y489126I2129J0D01*
G01X1532000Y487442D02*
Y487571D01*
G01X1531212Y486121D02*
G03X1532000Y487442I-787J1365D01*
G01X1530050Y484191D02*
G02X1531212Y486121I2325J-85D01*
G01X1530160Y483393D02*
G02X1530050Y484191I2209J711D01*
G01X1531212Y482091D02*
G02X1530160Y483393I1163J2015D01*
G01X1531212Y479361D02*
G03Y482091I-787J1365D01*
G01X1530050Y477431D02*
G02X1531212Y479361I2325J-85D01*
G01X1530050Y477302D02*
Y477431D01*
G01X1529262Y475981D02*
G03X1530050Y477302I-787J1365D01*
G01X1528100Y474051D02*
G02X1529262Y475981I2325J-85D01*
G01X1528100Y473922D02*
Y474051D01*
G01X1527312Y472601D02*
G03X1528100Y473922I-787J1365D01*
G01X1540550Y489417D02*
X1541215Y490082D01*
G01X1540550Y487401D02*
Y489417D01*
G01X1539388Y485471D02*
G03X1540550Y487401I-1163J2015D01*
G01X1539388Y482741D02*
G02Y485471I787J1365D01*
G01X1540550Y480811D02*
G03X1539388Y482741I-2325J-85D01*
G01X1540550Y480641D02*
Y480811D01*
G01X1539388Y478711D02*
G03X1540550Y480641I-1163J2015D01*
G01X1538600Y477390D02*
G02X1539388Y478711I1575J-44D01*
G01X1538600Y477261D02*
Y477390D01*
G01X1537438Y475331D02*
G03X1538600Y477261I-1163J2015D01*
G01X1536650Y474010D02*
G02X1537438Y475331I1575J-44D01*
G01X1536650Y473881D02*
Y474010D01*
G01X1535488Y471951D02*
G03X1536650Y473881I-1163J2015D01*
G01X1535179Y471718D02*
G02X1535488Y471951I1096J-1132D01*
G01X1528475Y480661D02*
G02X1527500Y479036I-1950J65D01*
G01X1528475Y480791D02*
Y480661D01*
G01X1527500Y482416D02*
G02X1528475Y480791I-975J-1690D01*
G01Y487421D02*
G02X1527500Y485796I-1950J65D01*
G01X1528475Y487551D02*
Y487421D01*
G01X1528994Y488813D02*
G03X1528475Y487551I1431J-1326D01*
G01X1544450Y488385D02*
X1545418Y489353D01*
G01X1544450Y487401D02*
Y488385D01*
G01X1543288Y485471D02*
G03X1544450Y487401I-1163J2015D01*
G01X1542500Y484150D02*
G02X1543288Y485471I1575J-44D01*
G01X1542500Y484062D02*
Y484150D01*
G01X1543288Y482741D02*
G02X1542500Y484062I787J1365D01*
G01X1544450Y480811D02*
G03X1543288Y482741I-2325J-85D01*
G01X1544450Y480641D02*
Y480811D01*
G01X1543288Y478711D02*
G03X1544450Y480641I-1163J2015D01*
G01X1542500Y477390D02*
G02X1543288Y478711I1575J-44D01*
G01X1542500Y477261D02*
Y477390D01*
G01X1541338Y475331D02*
G03X1542500Y477261I-1163J2015D01*
G01X1540550Y474010D02*
G02X1541338Y475331I1575J-44D01*
G01X1540550Y473881D02*
Y474010D01*
G01X1540487Y473422D02*
G03X1540550Y473881I-2262J544D01*
G01X1539388Y471951D02*
G03X1540487Y473422I-1163J2015D01*
G01X1538600Y470630D02*
G02X1539388Y471951I1575J-44D01*
G01X1538600Y470501D02*
Y470630D01*
G01X1538330Y469495D02*
G03X1538600Y470501I-2055J1091D01*
G01X1538225Y467206D02*
G02X1538330Y469495I2470J1034D01*
G01X1734875Y10196D02*
Y9238D01*
G01X1739684Y15005D02*
X1734875Y10196D01*
G01X1774584Y15005D02*
X1739684D01*
G01X1773235Y66715D02*
X1811553D01*
G01X1769600Y70350D02*
X1773235Y66715D01*
G01X1769250Y70350D02*
X1769600D01*
G01X1758060Y73699D02*
X1757998Y73637D01*
G01X1784661Y73699D02*
X1758060D01*
G01X1783264Y6325D02*
X1774584Y15005D01*
G01X1794470Y6325D02*
X1783264D01*
G01X1795100Y6955D02*
X1794470Y6325D01*
G01X1802484Y6955D02*
X1795100D01*
G01X1802486Y6957D02*
X1802484Y6955D01*
G01X1805514Y6957D02*
X1802486D01*
G01X1805516Y6955D02*
X1805514Y6957D01*
G01X1808769Y6955D02*
X1805516D01*
G01X1812204Y10390D02*
X1808769Y6955D01*
G01X1814531Y10390D02*
X1812204D01*
G01X1815697Y11556D02*
X1814531Y10390D01*
G01X1817429Y11556D02*
X1815697D01*
G01X1818468Y12595D02*
X1817429Y11556D01*
G01X1818468Y14067D02*
Y12595D01*
G01X1811597Y20938D02*
X1818468Y14067D01*
G01X1811597Y28264D02*
Y20938D01*
G01X1817058Y33725D02*
X1811597Y28264D01*
G01X1820664Y33725D02*
X1817058D01*
G01X1822355Y35416D02*
X1820664Y33725D01*
G01X1822355Y40910D02*
Y35416D01*
G01X1820984Y42281D02*
X1822355Y40910D01*
G01X1820984Y57284D02*
Y42281D01*
G01X1811553Y66715D02*
X1820984Y57284D01*
G01X1797432Y86470D02*
X1784661Y73699D01*
G01X1802324Y86470D02*
X1797432D01*
G01X1806384Y82410D02*
X1802324Y86470D01*
G01X1816510Y82410D02*
X1806384D01*
G01X1826245Y92145D02*
X1816510Y82410D01*
G01X1833061Y92145D02*
X1826245D01*
G54D13*
G01X-20523Y179181D02*
Y238278D01*
G01X-2978Y161636D02*
X-20523Y179181D01*
G01X-17119Y181044D02*
Y236868D01*
G01X-1547Y165472D02*
X-17119Y181044D01*
G01X-18821Y180050D02*
Y237573D01*
G01X-2252Y163481D02*
X-18821Y180050D01*
G01X-20523Y238278D02*
X-12247Y246554D01*
G01X-17119Y236868D02*
X-8763Y245224D01*
G01X-18821Y237573D02*
X-10465Y245929D01*
G01X-19218Y308348D02*
Y341479D01*
G01X-12247Y301377D02*
X-19218Y308348D01*
G01X-15813Y338888D02*
X-7042Y347659D01*
G01X-15813Y310750D02*
Y338888D01*
G01X-8763Y303700D02*
X-15813Y310750D01*
G01X-17515Y340737D02*
X-8891Y349361D01*
G01X-17515Y340615D02*
Y340737D01*
G01X-17516Y340614D02*
X-17515Y340615D01*
G01X-17516Y339328D02*
Y340614D01*
G01X-17515Y339327D02*
X-17516Y339328D01*
G01X-17515Y309052D02*
Y339327D01*
G01X-10465Y302002D02*
X-17515Y309052D01*
G01X-19218Y341479D02*
X-9634Y351063D01*
G01X-19861Y497011D02*
X-16766Y500106D01*
G01X-19861Y484578D02*
Y497011D01*
G01X18383Y446334D02*
X-19861Y484578D01*
G01X-15000Y504496D02*
X-17302Y506798D01*
G01X-16457Y490273D02*
X-15000Y491730D01*
G01X-16457Y485988D02*
Y490273D01*
G01X19495Y450036D02*
X-16457Y485988D01*
G01X-17000Y497400D02*
X-16700D01*
G01X-18159Y496241D02*
X-17000Y497400D01*
G01X-18159Y485283D02*
Y496241D01*
G01X18790Y448334D02*
X-18159Y485283D01*
G01X-16186Y519304D02*
X-15206Y518324D01*
G01X-18034Y511634D02*
X-17200Y510800D01*
G01X-18034Y519832D02*
Y511634D01*
G01X-15766Y522100D02*
X-18034Y519832D01*
G01X-8350Y522100D02*
X-15766D01*
G01X41001Y24354D02*
X82919D01*
G01X37739Y21092D02*
X41001Y24354D01*
G01X37739Y19501D02*
Y21092D01*
G01X43960Y20572D02*
X84396D01*
G01X42609Y22299D02*
X83630D01*
G01X40530Y20220D02*
X42609Y22299D01*
G01X37776Y97126D02*
X34000Y93350D01*
G01X38831Y94331D02*
X35650Y91150D01*
G01X38831Y139957D02*
Y94331D01*
G01X37776Y132751D02*
Y97126D01*
G01X32684Y137843D02*
X37776Y132751D01*
G01X25976Y137843D02*
X32684D01*
G01X23228Y140591D02*
X25976Y137843D01*
G01X35666Y143122D02*
X38831Y139957D01*
G01X20247Y143122D02*
X35666D01*
G01X17716Y140591D02*
X20247Y143122D01*
G01X47370Y161636D02*
X-2978D01*
G01X49175Y165472D02*
X-1547D01*
G01X48620Y163481D02*
X-2252D01*
G01X46066Y214747D02*
X54248Y206565D01*
G01X46066Y263689D02*
Y214747D01*
G01X-12247Y246554D02*
Y301377D01*
G01X-8763Y245224D02*
Y303700D01*
G01X-10465Y245929D02*
Y302002D01*
G01X50151Y267774D02*
X46066Y263689D01*
G01X37303Y357583D02*
Y407174D01*
G01X30783Y351063D02*
X37303Y357583D01*
G01X-9634Y351063D02*
X30783D01*
G01X40765Y355891D02*
Y408529D01*
G01X32533Y347659D02*
X40765Y355891D01*
G01X-7042Y347659D02*
X32533D01*
G01X39063Y356936D02*
Y407823D01*
G01X31488Y349361D02*
X39063Y356936D01*
G01X-8891Y349361D02*
X31488D01*
G01X45822Y354752D02*
X47441Y353133D01*
G01X45822Y404195D02*
Y354752D01*
G01X25062Y446334D02*
X18383D01*
G01X29038Y442358D02*
X25062Y446334D01*
G01X29038Y415439D02*
Y442358D01*
G01X37303Y407174D02*
X29038Y415439D01*
G01X26660Y450036D02*
X19495D01*
G01X33297Y443399D02*
X26660Y450036D01*
G01X33297Y415997D02*
Y443399D01*
G01X40765Y408529D02*
X33297Y415997D01*
G01X25662Y448334D02*
X18790D01*
G01X31300Y442696D02*
X25662Y448334D01*
G01X31300Y415586D02*
Y442696D01*
G01X39063Y407823D02*
X31300Y415586D01*
G01X85462Y443835D02*
X45822Y404195D01*
G01X-15000Y491730D02*
Y504496D01*
G01X44790Y483400D02*
X72417D01*
G01X38899Y477509D02*
X44790Y483400D01*
G01X23486Y477509D02*
X38899D01*
G01X18748Y482247D02*
X23486Y477509D01*
G01X8872Y482247D02*
X18748D01*
G01X6812Y480187D02*
X8872Y482247D01*
G01X3937Y480187D02*
X6812D01*
G01X2750Y479000D02*
X3937Y480187D01*
G01X2160Y479000D02*
X2750D01*
G01X45237Y482500D02*
X71970D01*
G01X39294Y476557D02*
X45237Y482500D01*
G01X23091Y476557D02*
X39294D01*
G01X18353Y481295D02*
X23091Y476557D01*
G01X9641Y481295D02*
X18353D01*
G01X6676Y478330D02*
X9641Y481295D01*
G01X5100Y478330D02*
X6676D01*
G01X18900Y491408D02*
X50492D01*
G01X15392Y487900D02*
X18900Y491408D01*
G01X8510Y487900D02*
X15392D01*
G01X5002Y491408D02*
X8510Y487900D01*
G01X162Y491408D02*
X5002D01*
G01X-3328Y494898D02*
X162Y491408D01*
G01X-3328Y509296D02*
Y494898D01*
G01X-3680Y509648D02*
X-3328Y509296D01*
G01X-11649Y509648D02*
X-3680D01*
G01X-15206Y513205D02*
X-11649Y509648D01*
G01X-15206Y518324D02*
Y513205D01*
G01X-255Y509274D02*
X-6712Y515731D01*
G01X-255Y495266D02*
Y509274D01*
G01X2850Y492161D02*
X-255Y495266D01*
G01X5859Y492161D02*
X2850D01*
G01X9010Y489010D02*
X5859Y492161D01*
G01X15109Y489010D02*
X9010D01*
G01X18260Y492161D02*
X15109Y489010D01*
G01X52139Y492161D02*
X18260D01*
G01X-5880Y524570D02*
X-8350Y522100D01*
G01X-5680Y524570D02*
X-5880D01*
G01X64450Y-56200D02*
X60500Y-52250D01*
G01X145030Y-56200D02*
X64450D01*
G01X84253Y25688D02*
Y82042D01*
G01X82919Y24354D02*
X84253Y25688D01*
G01X106700Y6500D02*
X116700Y16500D01*
G01X104723Y6500D02*
X106700D01*
G01X99028Y805D02*
X104723Y6500D01*
G01X91668Y805D02*
X99028D01*
G01X87201Y-3662D02*
X91668Y805D01*
G01X87201Y-12433D02*
Y-3662D01*
G01X83034Y-16600D02*
X87201Y-12433D01*
G01X82300Y-16600D02*
X83034D01*
G01X87800Y23976D02*
Y83500D01*
G01X84396Y20572D02*
X87800Y23976D01*
G01X85955Y24624D02*
Y82747D01*
G01X83630Y22299D02*
X85955Y24624D01*
G01X93382Y-15191D02*
X452722D01*
G01X88777Y-10586D02*
X93382Y-15191D01*
G01X54400Y88900D02*
Y154606D01*
G01X59200Y84100D02*
X54400Y88900D01*
G01X82195Y84100D02*
X59200D01*
G01X84253Y82042D02*
X82195Y84100D01*
G01X57804Y90896D02*
Y156843D01*
G01X61196Y87504D02*
X57804Y90896D01*
G01X83796Y87504D02*
X61196D01*
G01X87800Y83500D02*
X83796Y87504D01*
G01X56102Y89605D02*
Y155999D01*
G01X59905Y85802D02*
X56102Y89605D01*
G01X82900Y85802D02*
X59905D01*
G01X85955Y82747D02*
X82900Y85802D01*
G01X89804Y97204D02*
X86600Y94000D01*
G01X54400Y154606D02*
X47370Y161636D01*
G01X56102Y155999D02*
X48620Y163481D01*
G01X104600Y132246D02*
Y168877D01*
G01X103108Y130754D02*
X104600Y132246D01*
G01X103108Y126409D02*
Y130754D01*
G01X103917Y125600D02*
X103108Y126409D01*
G01X103917Y114472D02*
Y125600D01*
G01X98682Y109237D02*
X103917Y114472D01*
G01X96722Y109237D02*
X98682D01*
G01X92485Y105000D02*
X96722Y109237D01*
G01X107804Y97204D02*
X89804D01*
G01X110400Y99800D02*
X107804Y97204D01*
G01X104735Y122401D02*
X110400Y116736D01*
G01X104735Y125846D02*
Y122401D01*
G01X103860Y126721D02*
X104735Y125846D01*
G01X103860Y130442D02*
Y126721D01*
G01X105693Y132275D02*
X103860Y130442D01*
G01X105693Y171493D02*
Y132275D01*
G01X57804Y156843D02*
X49175Y165472D01*
G01X47218Y215225D02*
Y263027D01*
G01X55400Y207043D02*
X47218Y215225D01*
G01X55400Y203500D02*
Y207043D01*
G01X61050Y197850D02*
X55400Y203500D01*
G01X76850Y197850D02*
X61050D01*
G01X82378Y192322D02*
X76850Y197850D01*
G01X86249Y192322D02*
X82378D01*
G01X88979Y189592D02*
X86249Y192322D01*
G01X88979Y184498D02*
Y189592D01*
G01X104600Y168877D02*
X88979Y184498D01*
G01X94100Y183086D02*
X105693Y171493D01*
G01X94100Y189220D02*
Y183086D01*
G01X88500Y194820D02*
X94100Y189220D01*
G01X88500Y205400D02*
Y194820D01*
G01X81241Y212659D02*
X88500Y205400D01*
G01X81241Y261515D02*
Y212659D01*
G01X87151Y185919D02*
Y184872D01*
G01X76372Y196698D02*
X87151Y185919D01*
G01X60572Y196698D02*
X76372D01*
G01X54247Y203023D02*
X60572Y196698D01*
G01X54247Y203977D02*
Y203023D01*
G01X54248Y203978D02*
X54247Y203977D01*
G01X54248Y206565D02*
Y203978D01*
G01X51303Y267112D02*
Y281076D01*
G01X47218Y263027D02*
X51303Y267112D01*
G01X89200Y269474D02*
X81241Y261515D01*
G01X89200Y302397D02*
Y269474D01*
G01X50151Y281651D02*
Y267774D01*
G01X72600Y305200D02*
Y310800D01*
G01X54600Y287200D02*
X72600Y305200D01*
G01X54600Y284373D02*
Y287200D01*
G01X51303Y281076D02*
X53425Y283198D01*
G01X88600Y302997D02*
X89200Y302397D01*
G01X51700Y301472D02*
Y283200D01*
G01X49500Y303672D02*
X51700Y301472D01*
G01X49500Y316391D02*
Y303672D01*
G01X49526Y316391D02*
X49500D01*
G01X55007Y321872D02*
X49526Y316391D01*
G01X55007Y327973D02*
Y321872D01*
G01X53368Y329612D02*
X55007Y327973D01*
G01X51102Y329612D02*
X53368D01*
G01X47441Y333273D02*
X51102Y329612D01*
G01X47441Y353133D02*
Y333273D01*
G01X85462Y458347D02*
Y443835D01*
G01X69830Y473979D02*
X85462Y458347D01*
G01X89497Y477539D02*
Y479201D01*
G01X88628Y476670D02*
X89497Y477539D01*
G01X79147Y476670D02*
X88628D01*
G01X72417Y483400D02*
X79147Y476670D01*
G01X91073Y479145D02*
X92326Y480398D01*
G01X91073Y477768D02*
Y479145D01*
G01X89023Y475718D02*
X91073Y477768D01*
G01X78752Y475718D02*
X89023D01*
G01X71970Y482500D02*
X78752Y475718D01*
G01X70348Y489448D02*
X86100Y505200D01*
G01X52452Y489448D02*
X70348D01*
G01X50492Y491408D02*
X52452Y489448D01*
G01X61521Y473979D02*
X69830D01*
G01X58850Y476650D02*
X61521Y473979D01*
G01X58850Y479185D02*
Y476650D01*
G01X59731Y480066D02*
X58850Y479185D01*
G01X52868Y491432D02*
X52139Y492161D01*
G01X64157Y491432D02*
X52868D01*
G01X68878Y496153D02*
X64157Y491432D01*
G01X68878Y508203D02*
Y496153D01*
G01X87657Y526982D02*
X68878Y508203D01*
G01X87657Y613321D02*
Y526982D01*
G01X93130Y619849D02*
X345239D01*
G01X92501Y619220D02*
X93130Y619849D01*
G01X92120Y619220D02*
X92501D01*
G01X91150Y618250D02*
X92120Y619220D01*
G01X93800Y618111D02*
X344553D01*
G01X84054Y616924D02*
X87657Y613321D01*
G01X84054Y621345D02*
Y616924D01*
G01X85259Y622550D02*
X84054Y621345D01*
G01X90302Y622550D02*
X85259D01*
G01X91952Y620900D02*
X90302Y622550D01*
G01X102236Y614281D02*
Y614167D01*
G01X104264Y616309D02*
X102236Y614281D01*
G01X343948Y616309D02*
X104264D01*
G01X147382Y-53848D02*
X145030Y-56200D01*
G01X445509Y-53848D02*
X147382D01*
G01X148901Y-50496D02*
X445509D01*
G01X116700Y16500D02*
Y32900D01*
G01X118300Y82800D02*
Y107302D01*
G01X119800Y81300D02*
X118300Y82800D01*
G01X119800Y69400D02*
Y81300D01*
G01X122000Y67200D02*
X119800Y69400D01*
G01X122000Y44700D02*
Y67200D01*
G01X118300Y41000D02*
X122000Y44700D01*
G01X118300Y34500D02*
Y41000D01*
G01X116700Y32900D02*
X118300Y34500D01*
G01Y107302D02*
X120533Y109535D01*
G01X110400Y116736D02*
Y99800D01*
G01X347375Y617713D02*
X355616D01*
G01X345239Y619849D02*
X347375Y617713D01*
G01X346653Y616011D02*
X356625D01*
G01X344553Y618111D02*
X346653Y616011D01*
G01X345948Y614309D02*
X343948Y616309D01*
G01X357734Y614309D02*
X345948D01*
G01X396511Y15328D02*
X394682Y17157D01*
G01X396511Y10593D02*
Y15328D01*
G01X396226Y10308D02*
X396511Y10593D01*
G01X396226Y4080D02*
Y10308D01*
G01X396579Y3727D02*
X396226Y4080D01*
G01X396579Y-3171D02*
Y3727D01*
G01X396090Y-3660D02*
X396579Y-3171D01*
G01X396090Y-10643D02*
Y-3660D01*
G01X396886Y-11439D02*
X396090Y-10643D01*
G01X397338Y-11439D02*
X396886D01*
G01X397376Y-11477D02*
X397338Y-11439D01*
G01X398682Y-11477D02*
X397376D01*
G01X398720Y-11439D02*
X398682Y-11477D01*
G01X404031Y-11439D02*
X398720D01*
G01X404069Y-11477D02*
X404031Y-11439D01*
G01X405375Y-11477D02*
X404069D01*
G01X405413Y-11439D02*
X405375Y-11477D01*
G01X430803Y-11439D02*
X405413D01*
G01X382470Y619530D02*
X617281D01*
G01X378810Y623190D02*
X382470Y619530D01*
G01X361093Y623190D02*
X378810D01*
G01X355616Y617713D02*
X361093Y623190D01*
G01X381339Y617800D02*
X618394D01*
G01X377929Y621210D02*
X381339Y617800D01*
G01X361824Y621210D02*
X377929D01*
G01X356625Y616011D02*
X361824Y621210D01*
G01X393507Y614246D02*
X423244D01*
G01X393000Y613739D02*
X393507Y614246D01*
G01X393000Y609300D02*
Y613739D01*
G01X394682Y607618D02*
X393000Y609300D01*
G01X394682Y607292D02*
Y607618D01*
G01X362933Y619508D02*
X357734Y614309D01*
G01X376902Y619508D02*
X362933D01*
G01X380312Y616098D02*
X376902Y619508D01*
G01X619099Y616098D02*
X380312D01*
G01X445509Y-50496D02*
G02Y-53848I0J-1676D01*
G01X457207Y-19676D02*
X655035D01*
G01X452722Y-15191D02*
X457207Y-19676D01*
G01X421455Y-1742D02*
Y9121D01*
G01X421454Y-1743D02*
X421455Y-1742D01*
G01X421454Y-1817D02*
Y-1743D01*
G01X430841Y-11477D02*
X430803Y-11439D01*
G01X432147Y-11477D02*
X430841D01*
G01X432185Y-11439D02*
X432147Y-11477D01*
G01X445754Y-11439D02*
X432185D01*
G01X447576Y-9617D02*
X445754Y-11439D01*
G01X448369Y-9617D02*
X447576D01*
G01X449661Y-8325D02*
X448369Y-9617D01*
G01X452592Y-8325D02*
X449661D01*
G01X456005Y-11738D02*
X452592Y-8325D01*
G01X459068Y-11738D02*
X456005D01*
G01X459069Y-11737D02*
X459068Y-11738D01*
G01X459691Y-11737D02*
X459069D01*
G01X459768Y-11814D02*
X459691Y-11737D01*
G01X461995Y-11814D02*
X459768D01*
G01X466505Y-16324D02*
X461995Y-11814D01*
G01X646476Y-16324D02*
X466505D01*
G01X457725Y267274D02*
X460239D01*
G01X456179Y268820D02*
X457725Y267274D01*
G01X454126Y268820D02*
X456179D01*
G01X452865Y270081D02*
X454126Y268820D01*
G01X445625Y265061D02*
X444752Y264188D01*
G01X447913Y265061D02*
X445625D01*
G01X448955Y264854D02*
X447913Y265061D01*
G01X450433Y264242D02*
X448955Y264854D01*
G01X451109Y263566D02*
X450433Y264242D01*
G01X452666Y263566D02*
X451109D01*
G01X454100Y265000D02*
X452666Y263566D01*
G01X455700Y265000D02*
X454100D01*
G01X457222Y266522D02*
X455700Y265000D01*
G01X464976Y266522D02*
X457222D01*
G01X455258Y621472D02*
X616315D01*
G01X453410Y623320D02*
X455258Y621472D01*
G01X453250Y623320D02*
X453410D01*
G01X458006Y622224D02*
X615923D01*
G01X456910Y623320D02*
X458006Y622224D01*
G01X446840Y614246D02*
X619867D01*
G01X444034Y611440D02*
X446840Y614246D01*
G01X443940Y611440D02*
X444034D01*
G01X443481Y610981D02*
X443940Y611440D01*
G01X440880Y610981D02*
X443481D01*
G01X440421Y611440D02*
X440880Y610981D01*
G01X437534Y611440D02*
X440421D01*
G01X436684Y610590D02*
X437534Y611440D01*
G01X434678Y610590D02*
X436684D01*
G01X433648Y611620D02*
X434678Y610590D01*
G01X431021Y611620D02*
X433648D01*
G01X430241Y610840D02*
X431021Y611620D01*
G01X426650Y610840D02*
X430241D01*
G01X423244Y614246D02*
X426650Y610840D01*
G01X513251Y257147D02*
X518352D01*
G01X511463Y255359D02*
X513251Y257147D01*
G01X504256Y255359D02*
X511463D01*
G01X502825Y256790D02*
X504256Y255359D01*
G01X499970Y256790D02*
X502825D01*
G01X498733Y255553D02*
X499970Y256790D01*
G01X497409Y255553D02*
X498733D01*
G01X495460Y257502D02*
X497409Y255553D01*
G01X492743Y257502D02*
X495460D01*
G01X493290Y252890D02*
X488382Y257798D01*
G01X495353Y252890D02*
X493290D01*
G01X498072Y250171D02*
X495353Y252890D01*
G01X498072Y249347D02*
Y250171D01*
G01X603855Y29554D02*
Y53144D01*
G01X605510Y27899D02*
X603855Y29554D01*
G01X605510Y16999D02*
Y27899D01*
G01X603855Y15344D02*
X605510Y16999D01*
G01X603855Y-8246D02*
Y15344D01*
G01X605510Y-9901D02*
X603855Y-8246D01*
G01X605510Y-9690D02*
Y-9901D01*
G01X608400Y-6800D02*
X605510Y-9690D01*
G01X616100Y-6800D02*
X608400D01*
G01X624300Y1400D02*
X616100Y-6800D01*
G01X640000Y1400D02*
X624300D01*
G01X647100Y-5700D02*
X640000Y1400D01*
G01X647100Y-6600D02*
Y-5700D01*
G01X647400Y-6900D02*
X647100Y-6600D01*
G01X658981Y-15730D02*
X663451D01*
G01X655035Y-19676D02*
X658981Y-15730D01*
G01X660157Y29380D02*
X665054Y34277D01*
G01X648138Y29380D02*
X660157D01*
G01X647255Y30263D02*
X648138Y29380D01*
G01X647255Y75155D02*
Y30263D01*
G01X605510Y9157D02*
Y-1743D01*
G01X607192Y10839D02*
X605510Y9157D01*
G01X607192Y34375D02*
Y10839D01*
G01X605510Y-2410D02*
Y-1743D01*
G01X608400Y-5300D02*
X605510Y-2410D01*
G01X615200Y-5300D02*
X608400D01*
G01X623100Y2600D02*
X615200Y-5300D01*
G01X640600Y2600D02*
X623100D01*
G01X649200Y-6000D02*
X640600Y2600D01*
G01X649200Y-8350D02*
Y-6000D01*
G01X648050Y-9500D02*
X649200Y-8350D01*
G01X647000Y-9500D02*
X648050D01*
G01X650400Y-12400D02*
X646476Y-16324D01*
G01X650400Y-1298D02*
Y-12400D01*
G01X646160Y2942D02*
X650400Y-1298D01*
G01X646160Y3312D02*
Y2942D01*
G01X645984Y3488D02*
X646160Y3312D01*
G01X645984Y21124D02*
Y3488D01*
G01X650865Y26005D02*
X645984Y21124D01*
G01X661010Y26005D02*
X650865D01*
G01X665853Y30848D02*
X661010Y26005D01*
G01X660786Y27879D02*
X665261Y32354D01*
G01X647179Y27879D02*
X660786D01*
G01X642500Y23200D02*
X647179Y27879D01*
G01X635400Y23200D02*
X642500D01*
G01X623780Y34820D02*
X635400Y23200D01*
G01X603855Y90944D02*
X605510Y92599D01*
G01X603855Y67354D02*
Y90944D01*
G01X605510Y65699D02*
X603855Y67354D01*
G01X605510Y54799D02*
Y65699D01*
G01X603855Y53144D02*
X605510Y54799D01*
G01X649500Y77400D02*
X647255Y75155D01*
G01X653200Y77400D02*
X649500D01*
G01X660150Y84350D02*
X653200Y77400D01*
G01X665146Y84350D02*
X660150D01*
G01X605510Y36057D02*
X607192Y34375D01*
G01X605510Y46957D02*
Y36057D01*
G01X607192Y48639D02*
X605510Y46957D01*
G01X607192Y72175D02*
Y48639D01*
G01X605510Y73857D02*
X607192Y72175D01*
G01X605510Y84757D02*
Y73857D01*
G01X623780Y95120D02*
Y34820D01*
G01X618800Y100100D02*
X623780Y95120D01*
G01X652862Y187652D02*
X714126D01*
G01X635162Y205352D02*
X652862Y187652D01*
G01X635162Y231364D02*
Y205352D01*
G01X651268Y184762D02*
X711238D01*
G01X632360Y203670D02*
X651268Y184762D01*
G01X632360Y231754D02*
Y203670D01*
G01X662994Y177860D02*
X667258Y173596D01*
G01X652950Y177860D02*
X662994D01*
G01X629396Y201414D02*
X652950Y177860D01*
G01X629396Y229560D02*
Y201414D01*
G01X634410Y205040D02*
Y231676D01*
G01X652550Y186900D02*
X634410Y205040D01*
G01X713814Y186900D02*
X652550D01*
G01X633112Y203982D02*
Y231442D01*
G01X651580Y185514D02*
X633112Y203982D01*
G01X711833Y185514D02*
X651580D01*
G01X638080Y234282D02*
X635162Y231364D01*
G01X638080Y245090D02*
Y234282D01*
G01X640090Y247100D02*
X638080Y245090D01*
G01X645030Y247100D02*
X640090D01*
G01X652762Y239368D02*
X645030Y247100D01*
G01X681562Y239368D02*
X652762D01*
G01X643500Y276979D02*
Y274868D01*
G01X645105Y278584D02*
X643500Y276979D01*
G01X645105Y285405D02*
Y278584D01*
G01X635768Y235162D02*
X632360Y231754D01*
G01X635768Y246492D02*
Y235162D01*
G01X639478Y250202D02*
X635768Y246492D01*
G01X645652Y250202D02*
X639478D01*
G01X652492Y243362D02*
X645652Y250202D01*
G01X680938Y243362D02*
X652492D01*
G01X643403Y279289D02*
Y284961D01*
G01X641684Y277570D02*
X643403Y279289D01*
G01X641684Y270831D02*
Y277570D01*
G01X642855Y269660D02*
X641684Y270831D01*
G01X622300Y236656D02*
X629396Y229560D01*
G01X622294Y236656D02*
X622300D01*
G01X622060Y236890D02*
X622294Y236656D01*
G01X612436Y236890D02*
X622060D01*
G01X607340Y241986D02*
X612436Y236890D01*
G01X607340Y257020D02*
Y241986D01*
G01X616470Y266150D02*
X607340Y257020D01*
G01X634110Y266150D02*
X616470D01*
G01X637435Y269475D02*
X634110Y266150D01*
G01X637435Y276372D02*
Y269475D01*
G01X622500Y291307D02*
X637435Y276372D01*
G01X653074Y240120D02*
X681250D01*
G01X645342Y247852D02*
X653074Y240120D01*
G01X639778Y247852D02*
X645342D01*
G01X637328Y245402D02*
X639778Y247852D01*
G01X637328Y234594D02*
Y245402D01*
G01X634410Y231676D02*
X637328Y234594D01*
G01X652180Y242610D02*
X681250D01*
G01X645340Y249450D02*
X652180Y242610D01*
G01X639790Y249450D02*
X645340D01*
G01X636520Y246180D02*
X639790Y249450D01*
G01X636520Y234850D02*
Y246180D01*
G01X633112Y231442D02*
X636520Y234850D01*
G01X639852Y270256D02*
Y287751D01*
G01X643125Y266983D02*
X639852Y270256D01*
G01X643591Y266983D02*
X643125D01*
G01X647100Y287400D02*
X645105Y285405D01*
G01X647100Y292800D02*
Y287400D01*
G01X645880Y294020D02*
X647100Y292800D01*
G01X641451Y294020D02*
X645880D01*
G01X630435Y305036D02*
X641451Y294020D01*
G01X630435Y385728D02*
Y305036D01*
G01X628733Y304331D02*
Y386433D01*
G01X641639Y291425D02*
X628733Y304331D01*
G01X641639Y286725D02*
Y291425D01*
G01X643403Y284961D02*
X641639Y286725D01*
G01X622500Y392000D02*
Y291307D01*
G01X627031Y303626D02*
Y387139D01*
G01X638046Y292611D02*
X627031Y303626D01*
G01X638046Y289557D02*
Y292611D01*
G01X639852Y287751D02*
X638046Y289557D01*
G01X639456Y394749D02*
X630435Y385728D01*
G01X639456Y428708D02*
Y394749D01*
G01X637754Y395454D02*
Y428002D01*
G01X628733Y386433D02*
X637754Y395454D01*
G01X632200Y401700D02*
X622500Y392000D01*
G01X632200Y425700D02*
Y401700D01*
G01X674135Y387035D02*
X651944Y409226D01*
G01X636052Y396159D02*
Y427297D01*
G01X628028Y388135D02*
X636052Y396159D01*
G01X628027Y388135D02*
X628028D01*
G01X627031Y387139D02*
X628027Y388135D01*
G01X654126Y416874D02*
X682500Y388500D01*
G01X654126Y456170D02*
Y416874D01*
G01X651101Y459195D02*
X654126Y456170D01*
G01X651101Y483191D02*
Y459195D01*
G01X659500Y419120D02*
X684980Y393640D01*
G01X659500Y469660D02*
Y419120D01*
G01X638460Y429704D02*
X639456Y428708D01*
G01X638459Y429704D02*
X638460D01*
G01X620700Y447463D02*
X638459Y429704D01*
G01X620700Y452481D02*
Y447463D01*
G01X621052Y452833D02*
X620700Y452481D01*
G01X622648Y452833D02*
X621052D01*
G01X623000Y453185D02*
X622648Y452833D01*
G01X623000Y453889D02*
Y453185D01*
G01X622648Y454241D02*
X623000Y453889D01*
G01X621052Y454241D02*
X622648D01*
G01X620700Y454593D02*
X621052Y454241D01*
G01X620700Y455297D02*
Y454593D01*
G01X621052Y455649D02*
X620700Y455297D01*
G01X622648Y455649D02*
X621052D01*
G01X623000Y456001D02*
X622648Y455649D01*
G01X623000Y456705D02*
Y456001D01*
G01X622648Y457057D02*
X623000Y456705D01*
G01X621233Y457057D02*
X622648D01*
G01X620881Y457409D02*
X621233Y457057D01*
G01X620881Y463509D02*
Y457409D01*
G01X620400Y463990D02*
X620881Y463509D01*
G01X617341Y464028D02*
Y468974D01*
G01X618916Y462453D02*
X617341Y464028D01*
G01X618916Y446840D02*
Y462453D01*
G01X637754Y428002D02*
X618916Y446840D01*
G01X612700Y445200D02*
X632200Y425700D01*
G01X612700Y471743D02*
Y445200D01*
G01X644461Y461662D02*
Y486340D01*
G01X651944Y454179D02*
X644461Y461662D01*
G01X651944Y409226D02*
Y454179D01*
G01X655078Y417422D02*
X683707Y388793D01*
G01X655078Y456502D02*
Y417422D01*
G01X651959Y459621D02*
X655078Y456502D01*
G01X651959Y483680D02*
Y459621D01*
G01X615639Y463130D02*
Y471339D01*
G01X617000Y461769D02*
X615639Y463130D01*
G01X617000Y446349D02*
Y461769D01*
G01X636052Y427297D02*
X617000Y446349D01*
G01X647930Y514170D02*
Y553830D01*
G01X655000Y507100D02*
X647930Y514170D01*
G01X703800Y507100D02*
X655000D01*
G01X644812Y501088D02*
X646200Y499700D01*
G01X629011Y501088D02*
X644812D01*
G01X622395Y507704D02*
X629011Y501088D01*
G01X622395Y517105D02*
Y507704D01*
G01X619500Y520000D02*
X622395Y517105D01*
G01X619500Y528500D02*
Y520000D01*
G01X644756Y489536D02*
X651101Y483191D01*
G01X644756Y492301D02*
Y489536D01*
G01X649047Y496592D02*
X644756Y492301D01*
G01X649047Y498053D02*
Y496592D01*
G01X647400Y499700D02*
X649047Y498053D01*
G01X646200Y499700D02*
X647400D01*
G01X665710Y475870D02*
X659500Y469660D01*
G01X661300Y486000D02*
X665710Y481590D01*
G01X657740Y486000D02*
X661300D01*
G01X656840Y486900D02*
X657740Y486000D01*
G01X656100Y486900D02*
X656840D01*
G01X656507Y501700D02*
X667707D01*
G01X650911Y507296D02*
X656507Y501700D01*
G01X631584Y507296D02*
X650911D01*
G01X628848Y510032D02*
X631584Y507296D01*
G01X628848Y594027D02*
Y510032D01*
G01X660263Y507937D02*
X658900Y509300D01*
G01X701037Y507937D02*
X660263D01*
G01X648790Y514481D02*
Y552890D01*
G01X653971Y509300D02*
X648790Y514481D01*
G01X658900Y509300D02*
X653971D01*
G01X635800Y524200D02*
X630700Y529300D01*
G01X637699Y524200D02*
X635800D01*
G01X644419Y517480D02*
X637699Y524200D01*
G01X644419Y516581D02*
Y517480D01*
G01X655100Y505900D02*
X644419Y516581D01*
G01X701100Y505900D02*
X655100D01*
G01X619010Y469830D02*
X619390Y469450D01*
G01X618197Y469830D02*
X619010D01*
G01X617341Y468974D02*
X618197Y469830D01*
G01X656000Y499800D02*
X667200D01*
G01X650206Y505594D02*
X656000Y499800D01*
G01X630879Y505594D02*
X650206D01*
G01X627145Y509328D02*
X630879Y505594D01*
G01X627145Y510736D02*
Y509328D01*
G01X627146Y510737D02*
X627145Y510736D01*
G01X627146Y595746D02*
Y510737D01*
G01X620747Y479790D02*
X612700Y471743D01*
G01X620747Y481147D02*
Y479790D01*
G01X626900Y487300D02*
X620747Y481147D01*
G01X636130Y487300D02*
X626900D01*
G01X639197Y490367D02*
X636130Y487300D01*
G01X617648Y507722D02*
Y534803D01*
G01X620748Y504622D02*
X617648Y507722D01*
G01X620748Y504621D02*
Y504622D01*
G01X626121Y499248D02*
X620748Y504621D01*
G01X626122Y499248D02*
X626121D01*
G01X631022Y494348D02*
X626122Y499248D01*
G01X632653Y494348D02*
X631022D01*
G01X633805Y495500D02*
X632653Y494348D01*
G01X637501Y495500D02*
X633805D01*
G01X642000Y491001D02*
X637501Y495500D01*
G01X642000Y488801D02*
Y491001D01*
G01X644461Y486340D02*
X642000Y488801D01*
G01X645708Y489931D02*
X651959Y483680D01*
G01X645708Y491906D02*
Y489931D01*
G01X649999Y496197D02*
X645708Y491906D01*
G01X649999Y498448D02*
Y496197D01*
G01X648025Y500422D02*
X649999Y498448D01*
G01X648025Y501575D02*
Y500422D01*
G01X647560Y502040D02*
X648025Y501575D01*
G01X629406Y502040D02*
X647560D01*
G01X623347Y508099D02*
X629406Y502040D01*
G01X623347Y517500D02*
Y508099D01*
G01X620452Y520395D02*
X623347Y517500D01*
G01X620452Y528105D02*
Y520395D01*
G01X625443Y508623D02*
Y596450D01*
G01X630174Y503892D02*
X625443Y508623D01*
G01X649208Y503892D02*
X630174D01*
G01X655716Y497384D02*
X649208Y503892D01*
G01X655716Y494462D02*
Y497384D01*
G01X656068Y494110D02*
X655716Y494462D01*
G01X656772Y494110D02*
X656068D01*
G01X657124Y494462D02*
X656772Y494110D01*
G01X657124Y497746D02*
Y494462D01*
G01X657476Y498098D02*
X657124Y497746D01*
G01X658180Y498098D02*
X657476D01*
G01X658532Y497746D02*
X658180Y498098D01*
G01X658532Y494462D02*
Y497746D01*
G01X658884Y494110D02*
X658532Y494462D01*
G01X659588Y494110D02*
X658884D01*
G01X659940Y494462D02*
X659588Y494110D01*
G01X659940Y497746D02*
Y494462D01*
G01X660292Y498098D02*
X659940Y497746D01*
G01X660996Y498098D02*
X660292D01*
G01X661348Y497746D02*
X660996Y498098D01*
G01X661348Y494462D02*
Y497746D01*
G01X661700Y494110D02*
X661348Y494462D01*
G01X662404Y494110D02*
X661700D01*
G01X662756Y494462D02*
X662404Y494110D01*
G01X662756Y497746D02*
Y494462D01*
G01X663108Y498098D02*
X662756Y497746D01*
G01X663812Y498098D02*
X663108D01*
G01X615639Y471339D02*
X618800Y474500D01*
G01X645720Y582410D02*
Y591952D01*
G01X649340Y578790D02*
X645720Y582410D01*
G01X653540Y578790D02*
X649340D01*
G01X655760Y576570D02*
X653540Y578790D01*
G01X655760Y561470D02*
Y576570D01*
G01X650520Y556230D02*
X655760Y561470D01*
G01X650330Y556230D02*
X650520D01*
G01X647930Y553830D02*
X650330Y556230D01*
G01X622396Y531396D02*
X619500Y528500D01*
G01X622396Y603863D02*
Y531396D01*
G01X648180Y582460D02*
Y590702D01*
G01X650870Y579770D02*
X648180Y582460D01*
G01X653630Y579770D02*
X650870D01*
G01X657080Y576320D02*
X653630Y579770D01*
G01X657080Y561180D02*
Y576320D01*
G01X648790Y552890D02*
X657080Y561180D01*
G01X644500Y586300D02*
Y594400D01*
G01X639000Y580800D02*
X644500Y586300D01*
G01X633100Y580800D02*
X639000D01*
G01X630700Y578400D02*
X633100Y580800D01*
G01X630700Y529300D02*
Y578400D01*
G01X620526Y537681D02*
Y606626D01*
G01X617648Y534803D02*
X620526Y537681D01*
G01X623348Y531001D02*
X620452Y528105D01*
G01X623348Y603468D02*
Y531001D01*
G01X657470Y590800D02*
X668800D01*
G01X651279Y596991D02*
X657470Y590800D01*
G01X651279Y615731D02*
Y596991D01*
G01X644142Y622868D02*
X651279Y615731D01*
G01X617711Y622868D02*
X644142D01*
G01X616315Y621472D02*
X617711Y622868D01*
G01X645720Y591952D02*
X646760Y592992D01*
G01X628455Y609922D02*
X622396Y603863D01*
G01X628455Y611223D02*
Y609922D01*
G01X627705Y611973D02*
X628455Y611223D01*
G01X631455Y596634D02*
X628848Y594027D01*
G01X642365Y596634D02*
X631455D01*
G01X649380Y603649D02*
X642365Y596634D01*
G01X649380Y613678D02*
Y603649D01*
G01X642042Y621016D02*
X649380Y613678D01*
G01X618767Y621016D02*
X642042D01*
G01X617281Y619530D02*
X618767Y621016D01*
G01X630234Y598834D02*
X627146Y595746D01*
G01X641420Y598834D02*
X630234D01*
G01X647417Y604831D02*
X641420Y598834D01*
G01X647417Y612696D02*
Y604831D01*
G01X640799Y619314D02*
X647417Y612696D01*
G01X620084Y619314D02*
X640799D01*
G01X620083Y619313D02*
X620084Y619314D01*
G01X619907Y619313D02*
X620083D01*
G01X618394Y617800D02*
X619907Y619313D01*
G01X657948Y591952D02*
X668322D01*
G01X652690Y597210D02*
X657948Y591952D01*
G01X652690Y615950D02*
Y597210D01*
G01X644620Y624020D02*
X652690Y615950D01*
G01X617719Y624020D02*
X644620D01*
G01X615923Y622224D02*
X617719Y624020D01*
G01X621380Y615759D02*
X631741D01*
G01X619867Y614246D02*
X621380Y615759D01*
G01X630582Y614600D02*
X631741Y615759D01*
G01X627262Y614600D02*
X630582D01*
G01X625708Y613046D02*
X627262Y614600D01*
G01X625708Y611808D02*
Y613046D01*
G01X620526Y606626D02*
X625708Y611808D01*
G01X629315Y609435D02*
X623348Y603468D01*
G01X629315Y612362D02*
Y609435D01*
G01X629977Y613024D02*
X629315Y612362D01*
G01X620612Y617611D02*
X619099Y616098D01*
G01X639808Y617611D02*
X620612D01*
G01X645531Y611888D02*
X639808Y617611D01*
G01X645531Y605352D02*
Y611888D01*
G01X640715Y600536D02*
X645531Y605352D01*
G01X629529Y600536D02*
X640715D01*
G01X625443Y596450D02*
X629529Y600536D01*
G01X718055Y-19246D02*
X1045423D01*
G01X714400Y-15591D02*
X718055Y-19246D01*
G01X714400Y-12980D02*
Y-15591D01*
G01X708192Y-6772D02*
X714400Y-12980D01*
G01X708192Y-659D02*
Y-6772D01*
G01X707036Y497D02*
X708192Y-659D01*
G01X707036Y11103D02*
Y497D01*
G01X698470Y19669D02*
X707036Y11103D01*
G01X717743Y-19998D02*
X1045735D01*
G01X713756Y-16011D02*
X717743Y-19998D01*
G01X712796Y-16011D02*
X713756D01*
G01X716241Y-20750D02*
X1046613D01*
G01X713824Y-18333D02*
X716241Y-20750D01*
G01X714825Y-21600D02*
X1300244D01*
G01X707440Y-14215D02*
X714825Y-21600D01*
G01X707440Y-971D02*
Y-14215D01*
G01X706284Y185D02*
X707440Y-971D01*
G01X706284Y5869D02*
Y185D01*
G01X705329Y6824D02*
X706284Y5869D01*
G01X704514Y6824D02*
X705329D01*
G01X703221Y8117D02*
X704514Y6824D01*
G01X703221Y8778D02*
Y8117D01*
G01X702323Y9676D02*
X703221Y8778D01*
G01X676928Y9676D02*
X702323D01*
G01X664588Y-2664D02*
X676928Y9676D01*
G01X664588Y-14593D02*
Y-2664D01*
G01X663451Y-15730D02*
X664588Y-14593D01*
G01X718974Y-12179D02*
X725289Y-18494D01*
G01X714730Y-12179D02*
X718974D01*
G01X708944Y-6393D02*
X714730Y-12179D01*
G01X708944Y-343D02*
Y-6393D01*
G01X708019Y582D02*
X708944Y-343D01*
G01X708019Y12720D02*
Y582D01*
G01X701120Y19619D02*
X708019Y12720D01*
G01X671673Y30848D02*
X665853D01*
G01X680791Y21730D02*
X671673Y30848D01*
G01X686704Y21730D02*
X680791D01*
G01X687922Y22948D02*
X686704Y21730D01*
G01X703652Y22948D02*
X687922D01*
G01X708800Y17800D02*
X703652Y22948D01*
G01X708800Y1335D02*
Y17800D01*
G01X709696Y439D02*
X708800Y1335D01*
G01X709696Y-2873D02*
Y439D01*
G01X715722Y-8899D02*
X709696Y-2873D01*
G01X727202Y-8899D02*
X715722D01*
G01X712500Y15900D02*
X735800D01*
G01X704030Y24370D02*
X712500Y15900D01*
G01X686958Y24370D02*
X704030D01*
G01X685688Y23100D02*
X686958Y24370D01*
G01X681193Y23100D02*
X685688D01*
G01X671939Y32354D02*
X681193Y23100D01*
G01X665261Y32354D02*
X671939D01*
G01X723900Y76345D02*
X727700Y72545D01*
G01X723900Y89200D02*
Y76345D01*
G01X721900Y91200D02*
X723900Y89200D01*
G01X697700Y91200D02*
X721900D01*
G01X697100Y90600D02*
X697700Y91200D01*
G01X665054Y34277D02*
X670227D01*
G01X666051Y85255D02*
X665146Y84350D01*
G01X666051Y106398D02*
Y85255D01*
G01X722948Y151805D02*
X725348Y149405D01*
G01X722948Y173052D02*
Y151805D01*
G01X664563Y107886D02*
X666051Y106398D01*
G01X664563Y120946D02*
Y107886D01*
G01X667258Y123641D02*
X664563Y120946D01*
G01X667258Y173596D02*
Y123641D01*
G01X723900Y152200D02*
Y173447D01*
G01X726300Y149800D02*
X723900Y152200D01*
G01X714126Y187652D02*
X728462Y173316D01*
G01X711238Y184762D02*
X722948Y173052D01*
G01X724888Y188930D02*
X725936Y187882D01*
G01X727710Y173004D02*
X713814Y186900D01*
G01X723900Y173447D02*
X711833Y185514D01*
G01X686542Y244348D02*
X681562Y239368D01*
G01X686542Y250148D02*
Y244348D01*
G01X677140Y259550D02*
X686542Y250148D01*
G01X677140Y264120D02*
Y259550D01*
G01X686320Y273300D02*
X677140Y264120D01*
G01X689340Y273300D02*
X686320D01*
G01X693748Y277708D02*
X689340Y273300D01*
G01X693748Y288222D02*
Y277708D01*
G01X683048Y245472D02*
X680938Y243362D01*
G01X683048Y248534D02*
Y245472D01*
G01X681312Y250270D02*
X683048Y248534D01*
G01X676730Y250270D02*
X681312D01*
G01X674600Y252400D02*
X676730Y250270D01*
G01X674600Y265730D02*
Y252400D01*
G01X683146Y274276D02*
X674600Y265730D01*
G01X683146Y277973D02*
Y274276D01*
G01X684288Y279115D02*
X683146Y277973D01*
G01X684288Y281312D02*
Y279115D01*
G01X718500Y254900D02*
X723400Y250000D01*
G01X711210Y254900D02*
X718500D01*
G01X705470Y260640D02*
X711210Y254900D01*
G01X705470Y264372D02*
Y260640D01*
G01X697500Y272342D02*
X705470Y264372D01*
G01X697500Y286793D02*
Y272342D01*
G01X720450Y250543D02*
Y249950D01*
G01X717795Y253198D02*
X720450Y250543D01*
G01X710494Y253198D02*
X717795D01*
G01X703768Y259924D02*
X710494Y253198D01*
G01X703768Y263667D02*
Y259924D01*
G01X695600Y271835D02*
X703768Y263667D01*
G01X695600Y287300D02*
Y271835D01*
G01X719205Y256602D02*
X725828Y249979D01*
G01X711998Y256602D02*
X719205D01*
G01X707202Y261398D02*
X711998Y256602D01*
G01X707202Y265048D02*
Y261398D01*
G01X699400Y272850D02*
X707202Y265048D01*
G01X699400Y286286D02*
Y272850D01*
G01X688240Y276284D02*
Y283710D01*
G01X676388Y264432D02*
X688240Y276284D01*
G01X676388Y259238D02*
Y264432D01*
G01X685790Y249836D02*
X676388Y259238D01*
G01X685790Y244660D02*
Y249836D01*
G01X681250Y240120D02*
X685790Y244660D01*
G01X685240Y278720D02*
Y280990D01*
G01X684000Y277480D02*
X685240Y278720D01*
G01X684000Y273783D02*
Y277480D01*
G01X675552Y265335D02*
X684000Y273783D01*
G01X675552Y252795D02*
Y265335D01*
G01X677125Y251222D02*
X675552Y252795D01*
G01X681707Y251222D02*
X677125D01*
G01X683800Y249129D02*
X681707Y251222D01*
G01X683800Y245160D02*
Y249129D01*
G01X681250Y242610D02*
X683800Y245160D01*
G01X690499Y283602D02*
X690048Y284053D01*
G01X691428Y283602D02*
X690499D01*
G01X691780Y283954D02*
X691428Y283602D01*
G01X691780Y287520D02*
Y283954D01*
G01X690948Y288352D02*
X691780Y287520D01*
G01X690948Y372552D02*
Y288352D01*
G01X692990Y288980D02*
X693748Y288222D01*
G01X692990Y374780D02*
Y288980D01*
G01X683490Y282110D02*
X684288Y281312D01*
G01X700648Y289941D02*
X697500Y286793D01*
G01X700648Y308309D02*
Y289941D01*
G01X700018Y308939D02*
X700648Y308309D01*
G01X700018Y317668D02*
Y308939D01*
G01X704228Y321878D02*
X700018Y317668D01*
G01X709612Y321878D02*
X704228D01*
G01X710892Y320598D02*
X709612Y321878D01*
G01X715607Y320598D02*
X710892D01*
G01X719012Y324003D02*
X715607Y320598D01*
G01X719012Y381924D02*
Y324003D01*
G01X698946Y290646D02*
X695600Y287300D01*
G01X698946Y307604D02*
Y290646D01*
G01X698316Y308234D02*
X698946Y307604D01*
G01X698316Y318374D02*
Y308234D01*
G01X703522Y323580D02*
X698316Y318374D01*
G01X710318Y323580D02*
X703522D01*
G01X711314Y322584D02*
X710318Y323580D01*
G01X711314Y322583D02*
Y322584D01*
G01X711597Y322300D02*
X711314Y322583D01*
G01X714902Y322300D02*
X711597D01*
G01X717150Y324548D02*
X714902Y322300D01*
G01X717150Y381379D02*
Y324548D01*
G01X702400Y289286D02*
X699400Y286286D01*
G01X702400Y308964D02*
Y289286D01*
G01X701720Y309644D02*
X702400Y308964D01*
G01X701720Y316719D02*
Y309644D01*
G01X705177Y320176D02*
X701720Y316719D01*
G01X708907Y320176D02*
X705177D01*
G01X710187Y318896D02*
X708907Y320176D01*
G01X716312Y318896D02*
X710187D01*
G01X717592Y320176D02*
X716312Y318896D01*
G01X717596Y320176D02*
X717592D01*
G01X720104Y322684D02*
X717596Y320176D01*
G01X720104Y322688D02*
Y322684D01*
G01X720714Y323298D02*
X720104Y322688D01*
G01X720714Y382629D02*
Y323298D01*
G01X689520Y309409D02*
Y358200D01*
G01X689676Y309253D02*
X689520Y309409D01*
G01X689676Y307947D02*
Y309253D01*
G01X689520Y307791D02*
X689676Y307947D01*
G01X689520Y296590D02*
Y307791D01*
G01X686900Y293970D02*
X689520Y296590D01*
G01X686900Y285050D02*
Y293970D01*
G01X688240Y283710D02*
X686900Y285050D01*
G01X691645Y282650D02*
X690048Y281053D01*
G01X692051Y282650D02*
X691645D01*
G01X692732Y283331D02*
X692051Y282650D01*
G01X692732Y287769D02*
Y283331D01*
G01X691900Y288601D02*
X692732Y287769D01*
G01X691900Y373200D02*
Y288601D01*
G01X685240Y280990D02*
X686470Y282220D01*
G01X682500Y381000D02*
X690948Y372552D01*
G01X682500Y388500D02*
Y381000D01*
G01X684980Y382790D02*
X692990Y374780D01*
G01X684980Y393640D02*
Y382790D01*
G01X717233Y383703D02*
X719012Y381924D01*
G01X717233Y404312D02*
Y383703D01*
G01X715531Y382998D02*
X717150Y381379D01*
G01X715531Y405017D02*
Y382998D01*
G01X718935Y384408D02*
X720714Y382629D01*
G01X718935Y403528D02*
Y384408D01*
G01X674135Y381265D02*
Y387035D01*
G01X685780Y369620D02*
X674135Y381265D01*
G01X685780Y361940D02*
Y369620D01*
G01X689520Y358200D02*
X685780Y361940D01*
G01X683707Y381393D02*
X691900Y373200D01*
G01X683707Y388793D02*
Y381393D01*
G01X714013Y447401D02*
X739933D01*
G01X680300Y481114D02*
X714013Y447401D01*
G01Y443997D02*
X728803D01*
G01X714012Y443996D02*
X714013Y443997D01*
G01X712604Y443996D02*
X714012D01*
G01X675080Y481520D02*
X712604Y443996D01*
G01X713308Y445699D02*
X677800Y481207D01*
G01X730201Y445699D02*
X713308D01*
G01X736295Y423374D02*
X717233Y404312D01*
G01X735590Y425076D02*
X715531Y405017D01*
G01X737024Y421617D02*
X718935Y403528D01*
G01X680300Y485700D02*
Y481114D01*
G01X665710Y481590D02*
Y475870D01*
G01X723038Y489902D02*
X723792Y489148D01*
G01X703745Y489902D02*
X723038D01*
G01X703412Y489569D02*
X703745Y489902D01*
G01X703411Y489569D02*
X703412D01*
G01X702415Y488573D02*
X703411Y489569D01*
G01X702415Y488572D02*
Y488573D01*
G01X702247Y488404D02*
X702415Y488572D01*
G01X688860Y488404D02*
X702247D01*
G01X681884Y495380D02*
X688860Y488404D01*
G01X676324Y495380D02*
X681884D01*
G01X674004Y497700D02*
X676324Y495380D01*
G01X671707Y497700D02*
X674004D01*
G01X667707Y501700D02*
X671707Y497700D01*
G01X702090Y508990D02*
X701037Y507937D01*
G01X707149Y508990D02*
X702090D01*
G01X710643Y505496D02*
X707149Y508990D01*
G01X675080Y485570D02*
Y481520D01*
G01X677800Y481207D02*
Y485600D01*
G01X722462Y506458D02*
X725026Y509022D01*
G01X720526Y506458D02*
X722462D01*
G01X716916Y502848D02*
X720526Y506458D01*
G01X688421Y502848D02*
X716916D01*
G01X684321Y498748D02*
X688421Y502848D01*
G01X676923Y498748D02*
X684321D01*
G01X674471Y501200D02*
X676923Y498748D01*
G01X674000Y501200D02*
X674471D01*
G01X701500Y505500D02*
X701100Y505900D01*
G01X673248Y499552D02*
X671500Y501300D01*
G01X674772Y499552D02*
X673248D01*
G01X677092Y497232D02*
X674772Y499552D01*
G01X685018Y497232D02*
X677092D01*
G01X689682Y501896D02*
X685018Y497232D01*
G01X717311Y501896D02*
X689682D01*
G01X720920Y505505D02*
X717311Y501896D01*
G01X722856Y505505D02*
X720920D01*
G01X726118Y508767D02*
X722856Y505505D01*
G01X704450Y488200D02*
X721301D01*
G01X702952Y486702D02*
X704450Y488200D01*
G01X688155Y486702D02*
X702952D01*
G01X681179Y493678D02*
X688155Y486702D01*
G01X675619Y493678D02*
X681179D01*
G01X673397Y495900D02*
X675619Y493678D01*
G01X671100Y495900D02*
X673397D01*
G01X667200Y499800D02*
X671100Y495900D01*
G01X723858Y514835D02*
X728628Y519605D01*
G01X723858Y509201D02*
Y514835D01*
G01X722067Y507410D02*
X723858Y509201D01*
G01X720131Y507410D02*
X722067D01*
G01X716521Y503800D02*
X720131Y507410D01*
G01X688026Y503800D02*
X716521D01*
G01X683926Y499700D02*
X688026Y503800D01*
G01X678200Y499700D02*
X683926D01*
G01X676600Y501300D02*
X678200Y499700D01*
G01X664164Y497746D02*
X663812Y498098D01*
G01X664164Y494462D02*
Y497746D01*
G01X664516Y494110D02*
X664164Y494462D01*
G01X665220Y494110D02*
X664516D01*
G01X665572Y494462D02*
X665220Y494110D01*
G01X665572Y497419D02*
Y494462D01*
G01X665924Y497771D02*
X665572Y497419D01*
G01X666628Y497771D02*
X665924D01*
G01X666980Y497419D02*
X666628Y497771D01*
G01X666980Y494462D02*
Y497419D01*
G01X667332Y494110D02*
X666980Y494462D01*
G01X672780Y494110D02*
X667332D01*
G01X674914Y491976D02*
X672780Y494110D01*
G01X680474Y491976D02*
X674914D01*
G01X687450Y485000D02*
X680474Y491976D01*
G01X704150Y485000D02*
X687450D01*
G01X705150Y486000D02*
X704150Y485000D01*
G01X720100Y486000D02*
X705150D01*
G01X720300Y485800D02*
X720100Y486000D01*
G01X713500Y615500D02*
Y618000D01*
G01X709500Y611500D02*
X713500Y615500D01*
G01X709500Y603500D02*
Y611500D01*
G01X698600Y592600D02*
X709500Y603500D01*
G01X670600Y592600D02*
X698600D01*
G01X668800Y590800D02*
X670600Y592600D01*
G01X711144Y616274D02*
X711500D01*
G01X708348Y613478D02*
X711144Y616274D01*
G01X708348Y603978D02*
Y613478D01*
G01X698122Y593752D02*
X708348Y603978D01*
G01X670122Y593752D02*
X698122D01*
G01X668322Y591952D02*
X670122Y593752D01*
G01X753882Y-418D02*
X754600Y300D01*
G01X753882Y-1378D02*
Y-418D01*
G01X754132Y-1628D02*
X753882Y-1378D01*
G01X755798Y-1628D02*
X754132D01*
G01X756368Y-1058D02*
X755798Y-1628D01*
G01X756368Y2446D02*
Y-1058D01*
G01X751856Y6958D02*
X756368Y2446D01*
G01X751856Y8520D02*
Y6958D01*
G01X756671Y13335D02*
X751856Y8520D01*
G01X756671Y18029D02*
Y13335D01*
G01X754752Y19948D02*
X756671Y18029D01*
G01X753240Y19948D02*
X754752D01*
G01X750700Y22488D02*
X753240Y19948D01*
G01X750700Y26599D02*
Y22488D01*
G01X753648Y29547D02*
X750700Y26599D01*
G01X753648Y45259D02*
Y29547D01*
G01X756176Y-4876D02*
Y-4300D01*
G01X763480Y-12180D02*
X756176Y-4876D01*
G01X763483Y-12181D02*
X763480Y-12180D01*
G01X1017690Y-12181D02*
X763483D01*
G01X725289Y-18494D02*
X1043474D01*
G01X729723Y-11420D02*
X727202Y-8899D01*
G01X729756Y-11420D02*
X729723D01*
G01X731210Y-12874D02*
X729756Y-11420D01*
G01X731210Y-15134D02*
Y-12874D01*
G01X737034Y-17448D02*
X1040922D01*
G01X734720Y-15134D02*
X737034Y-17448D01*
G01X731210Y-15134D02*
X734720D01*
G01X754400Y29235D02*
Y45571D01*
G01X751452Y26287D02*
X754400Y29235D01*
G01X751452Y22800D02*
Y26287D01*
G01X753552Y20700D02*
X751452Y22800D01*
G01X755100Y20700D02*
X753552D01*
G01X757430Y18370D02*
X755100Y20700D01*
G01X757423Y18363D02*
X757430Y18370D01*
G01X757423Y13023D02*
Y18363D01*
G01X752608Y8208D02*
X757423Y13023D01*
G01X752608Y7270D02*
Y8208D01*
G01X757120Y2758D02*
X752608Y7270D01*
G01X757120Y-1370D02*
Y2758D01*
G01X756110Y-2380D02*
X757120Y-1370D01*
G01X753820Y-2380D02*
X756110D01*
G01X753070Y-1630D02*
X753820Y-2380D01*
G01X753070Y-770D02*
Y-1630D01*
G01X751900Y400D02*
X753070Y-770D01*
G01X751598Y17255D02*
X755000D01*
G01X748153Y20700D02*
X751598Y17255D01*
G01X740600Y20700D02*
X748153D01*
G01X735800Y15900D02*
X740600Y20700D01*
G01X733671Y77329D02*
Y75412D01*
G01X728462Y82538D02*
X733671Y77329D01*
G01X728462Y173316D02*
Y82538D01*
G01X752848Y46059D02*
X753648Y45259D01*
G01X752848Y53642D02*
Y46059D01*
G01X747531Y58959D02*
X752848Y53642D01*
G01X741661Y58959D02*
X747531D01*
G01X741461Y59159D02*
X741661Y58959D01*
G01X741262Y59159D02*
X741461D01*
G01X736915Y63506D02*
X741262Y59159D01*
G01X736915Y70187D02*
Y63506D01*
G01X734962Y72140D02*
X736915Y70187D01*
G01X729735Y72140D02*
X734962D01*
G01X725347Y76528D02*
X729735Y72140D01*
G01X725347Y77711D02*
Y76528D01*
G01X725348Y77712D02*
X725347Y77711D01*
G01X725348Y149405D02*
Y77712D01*
G01X732176Y93056D02*
X731910Y92790D01*
G01X732176Y94565D02*
Y93056D01*
G01X751600Y53100D02*
Y41000D01*
G01X746893Y57807D02*
X751600Y53100D01*
G01X733513Y57807D02*
X746893D01*
G01X727700Y63620D02*
X733513Y57807D01*
G01X727700Y72545D02*
Y63620D01*
G01X727710Y82226D02*
Y173004D01*
G01X730923Y79013D02*
X727710Y82226D01*
G01X730923Y75315D02*
Y79013D01*
G01X726300Y77317D02*
Y149800D01*
G01X726299Y77316D02*
X726300Y77317D01*
G01X726299Y76923D02*
Y77316D01*
G01X730322Y72900D02*
X726299Y76923D01*
G01X735266Y72900D02*
X730322D01*
G01X737667Y70499D02*
X735266Y72900D01*
G01X737667Y63818D02*
Y70499D01*
G01X741574Y59911D02*
X737667Y63818D01*
G01X747926Y59911D02*
X741574D01*
G01X753600Y54237D02*
X747926Y59911D01*
G01X753600Y46371D02*
Y54237D01*
G01X754400Y45571D02*
X753600Y46371D01*
G01X733740Y95230D02*
Y175638D01*
G01X732164Y94577D02*
X732176Y94565D01*
G01X732164Y95883D02*
Y94577D01*
G01X732885Y96604D02*
X732164Y95883D01*
G01X732885Y175245D02*
Y96604D01*
G01X727628Y188811D02*
X727776D01*
G01X726739Y187922D02*
X727628Y188811D01*
G01X726739Y182639D02*
Y187922D01*
G01X733740Y175638D02*
X726739Y182639D01*
G01X725936Y182194D02*
X732885Y175245D01*
G01X725936Y187882D02*
Y182194D01*
G01X725828Y249979D02*
X726328D01*
G01X747900Y431328D02*
X746151Y433077D01*
G01X747900Y429160D02*
Y431328D01*
G01X746890Y428150D02*
X747900Y429160D01*
G01X745411Y428150D02*
X746890D01*
G01X744112Y428688D02*
X745411Y428150D01*
G01X728803Y443997D02*
X744112Y428688D01*
G01X745601Y430299D02*
X730201Y445699D01*
G01X745961Y430299D02*
X745601D01*
G01X746130Y430130D02*
X745961Y430299D01*
G01X769001Y423374D02*
X736295D01*
G01X772390Y419985D02*
X769001Y423374D01*
G01X772390Y413836D02*
Y419985D01*
G01X778099Y408127D02*
X772390Y413836D01*
G01X797904Y408127D02*
X778099D01*
G01X769706Y425076D02*
X735590D01*
G01X774092Y420690D02*
X769706Y425076D01*
G01X774092Y414541D02*
Y420690D01*
G01X778749Y409884D02*
X774092Y414541D01*
G01X797146Y409884D02*
X778749D01*
G01X768273Y421617D02*
X737024D01*
G01X770633Y419257D02*
X768273Y421617D01*
G01X770633Y413108D02*
Y419257D01*
G01X777316Y406425D02*
X770633Y413108D01*
G01X798609Y406425D02*
X777316D01*
G01X747926Y525084D02*
X752206Y529364D01*
G01X740967Y525084D02*
X747926D01*
G01X734535Y518652D02*
X740967Y525084D01*
G01X729175Y518652D02*
X734535D01*
G01X727944Y517421D02*
X729175Y518652D01*
G01X727944Y517291D02*
Y517421D01*
G01X725026Y514373D02*
X727944Y517291D01*
G01X725026Y509022D02*
Y514373D01*
G01X726118Y514118D02*
Y508767D01*
G01X728896Y516896D02*
X726118Y514118D01*
G01X728896Y517026D02*
Y516896D01*
G01X729570Y517700D02*
X728896Y517026D01*
G01X734930Y517700D02*
X729570D01*
G01X741362Y524132D02*
X734930Y517700D01*
G01X748321Y524132D02*
X741362D01*
G01X753158Y528969D02*
X748321Y524132D01*
G01X730552Y510552D02*
X731600Y511600D01*
G01X730552Y506548D02*
Y510552D01*
G01X734150Y502950D02*
X730552Y506548D01*
G01X734150Y496525D02*
Y502950D01*
G01X729723Y492098D02*
X734150Y496525D01*
G01X729723Y489942D02*
Y492098D01*
G01X730346Y489319D02*
X729723Y489942D01*
G01X731339Y489319D02*
X730346D01*
G01X748799Y522980D02*
X754310Y528491D01*
G01X741840Y522980D02*
X748799D01*
G01X736579Y517719D02*
X741840Y522980D01*
G01X736579Y494119D02*
Y517719D01*
G01X738648Y492050D02*
X736579Y494119D01*
G01X747531Y526036D02*
X751254Y529759D01*
G01X740572Y526036D02*
X747531D01*
G01X734141Y519605D02*
X740572Y526036D01*
G01X728628Y519605D02*
X734141D01*
G01X729800Y510700D02*
X729000Y511500D01*
G01X729800Y506236D02*
Y510700D01*
G01X733398Y502638D02*
X729800Y506236D01*
G01X733398Y496837D02*
Y502638D01*
G01X728971Y492410D02*
X733398Y496837D01*
G01X728971Y490082D02*
Y492410D01*
G01X728373Y489484D02*
X728971Y490082D01*
G01X728373Y488356D02*
Y489484D01*
G01X736595Y548005D02*
Y602264D01*
G01X740900Y543700D02*
X736595Y548005D01*
G01X745040Y543700D02*
X740900D01*
G01X752206Y536534D02*
X745040Y543700D01*
G01X752206Y529364D02*
Y536534D01*
G01X753158Y536929D02*
Y528969D01*
G01X745427Y544660D02*
X753158Y536929D01*
G01X741740Y544660D02*
X745427D01*
G01X737547Y548853D02*
X741740Y544660D01*
G01X737547Y600057D02*
Y548853D01*
G01X750919Y542241D02*
Y594001D01*
G01X754310Y538850D02*
X750919Y542241D01*
G01X754310Y528491D02*
Y538850D01*
G01X735443Y547527D02*
Y602608D01*
G01X740422Y542548D02*
X735443Y547527D01*
G01X744562Y542548D02*
X740422D01*
G01X751254Y535856D02*
X744562Y542548D01*
G01X751254Y529759D02*
Y535856D01*
G01X752344Y622798D02*
X1043968D01*
G01X752327Y622781D02*
X752344Y622798D01*
G01X742359Y622781D02*
X752327D01*
G01X734970Y615392D02*
X742359Y622781D01*
G01X734970Y605869D02*
Y615392D01*
G01X733101Y604000D02*
X734970Y605869D01*
G01X733032Y604000D02*
X733101D01*
G01X753217Y620694D02*
X1043095D01*
G01X753200Y620677D02*
X753217Y620694D01*
G01X744972Y620677D02*
X753200D01*
G01X737240Y612945D02*
X744972Y620677D01*
G01X737240Y602909D02*
Y612945D01*
G01X736595Y602264D02*
X737240Y602909D01*
G01X739135Y601645D02*
X737547Y600057D01*
G01X747644Y601645D02*
X739135D01*
G01X752000Y606001D02*
X747644Y601645D01*
G01X752000Y617174D02*
Y606001D01*
G01X751999Y617175D02*
X752000Y617174D01*
G01X751999Y618129D02*
Y617175D01*
G01X752000Y618130D02*
X751999Y618129D01*
G01X752000Y618330D02*
Y618130D01*
G01X753350Y619680D02*
X752000Y618330D01*
G01X753550Y619680D02*
X753350D01*
G01X753612Y619742D02*
X753550Y619680D01*
G01X1042700Y619742D02*
X753612D01*
G01X746070Y598850D02*
X739307D01*
G01X750919Y594001D02*
X746070Y598850D01*
G01X752822Y621646D02*
X1043490D01*
G01X752805Y621629D02*
X752822Y621646D01*
G01X744291Y621629D02*
X752805D01*
G01X736261Y613599D02*
X744291Y621629D01*
G01X736261Y603426D02*
Y613599D01*
G01X735443Y602608D02*
X736261Y603426D01*
G01X754090Y618590D02*
X1042222D01*
G01X753152Y617652D02*
X754090Y618590D01*
G01X753152Y605399D02*
Y617652D01*
G01X752827Y605074D02*
X753152Y605399D01*
G01X752827Y594073D02*
Y605074D01*
G01X753300Y593600D02*
X752827Y594073D01*
G01X798903Y409126D02*
X797904Y408127D01*
G01X798903Y412197D02*
Y409126D01*
G01X798500Y412600D02*
X798903Y412197D01*
G01X797200Y409830D02*
X797146Y409884D01*
G01X800610Y408426D02*
X798609Y406425D01*
G01X800610Y415000D02*
Y408426D01*
G01X956360Y345300D02*
Y350314D01*
G01X1019674Y-10197D02*
X1017690Y-12181D01*
G01X1019674Y-9216D02*
Y-10197D01*
G01X1026290Y-2600D02*
X1019674Y-9216D01*
G01X1026290Y1290D02*
Y-2600D01*
G01X1026700Y1700D02*
X1026290Y1290D01*
G01X1050489Y-14180D02*
X1268826D01*
G01X1045423Y-19246D02*
X1050489Y-14180D01*
G01X1050801Y-14932D02*
X1267500D01*
G01X1045735Y-19998D02*
X1050801Y-14932D01*
G01X1051479Y-15884D02*
X1266800D01*
G01X1046613Y-20750D02*
X1051479Y-15884D01*
G01X1048540Y-13428D02*
X1270228D01*
G01X1043474Y-18494D02*
X1048540Y-13428D01*
G01X1040922Y-17448D02*
X1046000Y-12370D01*
G01X1046259Y-12629D02*
X1271029D01*
G01X1046000Y-12370D02*
X1046259Y-12629D01*
G01X1045746Y-12116D02*
X1046000Y-12370D01*
G01X1045746Y-2974D02*
Y-12116D01*
G01X1045867Y-2853D02*
X1045746Y-2974D01*
G01X1045867Y-1547D02*
Y-2853D01*
G01X1045747Y-1427D02*
X1045867Y-1547D01*
G01X1045747Y-537D02*
Y-1427D01*
G01X1045746Y-536D02*
X1045747Y-537D01*
G01X1045746Y9722D02*
Y-536D01*
G01X1046067Y10043D02*
X1045746Y9722D01*
G01X1046067Y14815D02*
Y10043D01*
G01X1045525Y15357D02*
X1046067Y14815D01*
G01X1069400Y-3479D02*
X1071062Y-1817D01*
G01X1069400Y-8300D02*
Y-3479D01*
G01X1072577Y-11477D02*
X1069400Y-8300D01*
G01X1267474Y-11477D02*
X1072577D01*
G01X1071062Y9120D02*
X1071064Y9122D01*
G01X1071062Y-1817D02*
Y9120D01*
G01X1095000Y274500D02*
Y280000D01*
G01X1089000Y268500D02*
X1095000Y274500D01*
G01X1089000Y267000D02*
Y268500D01*
G01X1093500Y270500D02*
X1100300Y277300D01*
G01X1092999Y270500D02*
X1093500D01*
G01X1090600Y268101D02*
X1092999Y270500D01*
G01X1090600Y266000D02*
Y268101D01*
G01X1089100Y264500D02*
X1090600Y266000D01*
G01X1092300Y264300D02*
X1096600D01*
G01X1092100Y264500D02*
X1092300Y264300D01*
G01Y267800D02*
X1100900Y276400D01*
G01X1092300Y267200D02*
Y267800D01*
G01X1095000Y280000D02*
X1096000Y281000D01*
G01X1097797Y350989D02*
X1072799D01*
G01X1045710Y621601D02*
X1095311D01*
G01X1044530Y622781D02*
X1045710Y621601D01*
G01X1043985Y622781D02*
X1044530D01*
G01X1043968Y622798D02*
X1043985Y622781D01*
G01X1093879Y619050D02*
X1096359Y616570D01*
G01X1045284Y619050D02*
X1093879D01*
G01X1043657Y620677D02*
X1045284Y619050D01*
G01X1043112Y620677D02*
X1043657D01*
G01X1043095Y620694D02*
X1043112Y620677D01*
G01X1042762Y619680D02*
X1042700Y619742D01*
G01X1042848Y619680D02*
X1042762D01*
G01X1044878Y617650D02*
X1042848Y619680D01*
G01X1093380Y617650D02*
X1044878D01*
G01X1095645Y615385D02*
X1093380Y617650D01*
G01X1094191Y620449D02*
X1096940Y617700D01*
G01X1045232Y620449D02*
X1094191D01*
G01X1044052Y621629D02*
X1045232Y620449D01*
G01X1043507Y621629D02*
X1044052D01*
G01X1043490Y621646D02*
X1043507Y621629D01*
G01X1093032Y616368D02*
X1095167Y614233D01*
G01X1044444Y616368D02*
X1093032D01*
G01X1042222Y618590D02*
X1044444Y616368D01*
G01X1121091Y282192D02*
X1124311Y278972D01*
G01X1140546Y272373D02*
X1140920Y272747D01*
G01X1136733Y272373D02*
X1140546D01*
G01X1135537Y271177D02*
X1136733Y272373D01*
G01X1133509Y271177D02*
X1135537D01*
G01X1132468Y272218D02*
X1133509Y271177D01*
G01X1129463Y272218D02*
X1132468D01*
G01X1127481Y274200D02*
X1129463Y272218D01*
G01X1121430Y274200D02*
X1127481D01*
G01X1119030Y276600D02*
X1121430Y274200D01*
G01X1117200Y276600D02*
X1119030D01*
G01X1115829Y275229D02*
X1117200Y276600D01*
G01X1105729Y275229D02*
X1115829D01*
G01X1101000Y270500D02*
X1105729Y275229D01*
G01X1097410Y270500D02*
X1101000D01*
G01X1095700Y268790D02*
X1097410Y270500D01*
G01X1146500Y250527D02*
X1147680Y249347D01*
G01X1146500Y251351D02*
Y250527D01*
G01X1144851Y253000D02*
X1146500Y251351D01*
G01X1144241Y253000D02*
X1144851D01*
G01X1142000Y255241D02*
X1144241Y253000D01*
G01X1142000Y257722D02*
Y255241D01*
G01X1134311Y265411D02*
X1142000Y257722D01*
G01X1133389Y265411D02*
X1134311D01*
G01X1131400Y267400D02*
X1133389Y265411D01*
G01X1128600Y267400D02*
X1131400D01*
G01X1125500Y270500D02*
X1128600Y267400D01*
G01X1121600Y270500D02*
X1125500D01*
G01X1120300Y269200D02*
X1121600Y270500D01*
G01X1118400Y269200D02*
X1120300D01*
G01X1117100Y270500D02*
X1118400Y269200D01*
G01X1115000Y270500D02*
X1117100D01*
G01X1114200Y269700D02*
X1115000Y270500D01*
G01X1109800Y269700D02*
X1114200D01*
G01X1107600Y271900D02*
X1109800Y269700D01*
G01X1146583Y266700D02*
X1148652D01*
G01X1144999Y265116D02*
X1146583Y266700D01*
G01X1143106Y265116D02*
X1144999D01*
G01X1141667Y266555D02*
X1143106Y265116D01*
G01X1140379Y266555D02*
X1141667D01*
G01X1138441Y268493D02*
X1140379Y266555D01*
G01X1137175Y268493D02*
X1138441D01*
G01X1135251Y270417D02*
X1137175Y268493D01*
G01X1128332Y270417D02*
X1135251D01*
G01X1125449Y273300D02*
X1128332Y270417D01*
G01X1115200Y273300D02*
X1125449D01*
G01X1114200Y274300D02*
X1115200Y273300D01*
G01X1106200Y274300D02*
X1114200D01*
G01X1101300Y269400D02*
X1106200Y274300D01*
G01X1099200Y269400D02*
X1101300D01*
G01X1095700Y265900D02*
X1099200Y269400D01*
G01X1150990Y272371D02*
X1151130D01*
G01X1126404Y278221D02*
X1127400D01*
G01X1125792Y277609D02*
X1126404Y278221D01*
G01X1124070Y277609D02*
X1125792D01*
G01X1120753Y280926D02*
X1124070Y277609D01*
G01X1115061Y278340D02*
X1117647Y280926D01*
G01X1112820Y278340D02*
X1115061D01*
G01X1111760Y279400D02*
X1112820Y278340D01*
G01X1106600Y279400D02*
X1111760D01*
G01X1104500Y277300D02*
X1106600Y279400D01*
G01X1100300Y277300D02*
X1104500D01*
G01X1139945Y261207D02*
X1145207D01*
G01X1134452Y266700D02*
X1139945Y261207D01*
G01X1134000Y266700D02*
X1134452D01*
G01X1132000Y268700D02*
X1134000Y266700D01*
G01X1128690Y268700D02*
X1132000D01*
G01X1124990Y272400D02*
X1128690Y268700D01*
G01X1113800Y272400D02*
X1124990D01*
G01X1112700Y273500D02*
X1113800Y272400D01*
G01X1106700Y273500D02*
X1112700D01*
G01X1101300Y268100D02*
X1106700Y273500D01*
G01X1100400Y268100D02*
X1101300D01*
G01X1096600Y264300D02*
X1100400Y268100D01*
G01X1151202Y268471D02*
X1154440Y268847D01*
G01X1150990Y268471D02*
X1151202D01*
G01X1149045Y269634D02*
G03X1150990Y268471I2015J1162D01*
G01X1147724Y270422D02*
G02X1149045Y269634I-44J-1575D01*
G01X1147595Y270422D02*
X1147724D01*
G01X1145665Y271584D02*
G03X1147595Y270422I2015J1163D01*
G01X1144359Y272371D02*
G02X1145665Y271584I-59J-1575D01*
G01X1142218Y274512D02*
X1144359Y272371D01*
G01X1139902Y274512D02*
X1142218D01*
G01X1138516Y273126D02*
X1139902Y274512D01*
G01X1136552Y273126D02*
X1138516D01*
G01X1135177Y274501D02*
X1136552Y273126D01*
G01X1132847Y274501D02*
X1135177D01*
G01X1131317Y272971D02*
X1132847Y274501D01*
G01X1130099Y272971D02*
X1131317D01*
G01X1128070Y275000D02*
X1130099Y272971D01*
G01X1125400Y275000D02*
X1128070D01*
G01X1120235Y280165D02*
X1125400Y275000D01*
G01X1116050Y277450D02*
X1118765Y280165D01*
G01X1112380Y277450D02*
X1116050D01*
G01X1111330Y278500D02*
X1112380Y277450D01*
G01X1107399Y278500D02*
X1111330D01*
G01X1105299Y276400D02*
X1107399Y278500D01*
G01X1100900Y276400D02*
X1105299D01*
G01X1114300Y297400D02*
X1113900Y297800D01*
G01X1114300Y292755D02*
Y297400D01*
G01X1114702Y292353D02*
X1114300Y292755D01*
G01X1114702Y291878D02*
Y292353D01*
G01X1121091Y283147D02*
Y282192D01*
G01X1120172Y284066D02*
X1121091Y283147D01*
G01X1118870Y284066D02*
X1120172D01*
G01X1118544Y283740D02*
X1118870Y284066D01*
G01X1113130Y283740D02*
X1118544D01*
G01X1110390Y281000D02*
X1113130Y283740D01*
G01X1096000Y281000D02*
X1110390D01*
G01X1130780Y330088D02*
Y329296D01*
G01X1133882Y333190D02*
X1130780Y330088D01*
G01X1134690Y333190D02*
X1133882D01*
G01X1136266Y334766D02*
X1134690Y333190D01*
G01X1138434Y334766D02*
X1136266D01*
G01X1139623Y333577D02*
X1138434Y334766D01*
G01X1142277Y333577D02*
X1139623D01*
G01X1143466Y334766D02*
X1142277Y333577D01*
G01X1145034Y334766D02*
X1143466D01*
G01X1146223Y333577D02*
X1145034Y334766D01*
G01X1148677Y333577D02*
X1146223D01*
G01X1149866Y334766D02*
X1148677Y333577D01*
G01X1152600Y334766D02*
X1149866D01*
G01X1153789Y333577D02*
X1152600Y334766D01*
G01X1155091Y333577D02*
X1153789D01*
G01X1156280Y334766D02*
X1155091Y333577D01*
G01X1158734Y334766D02*
X1156280D01*
G01X1156469Y318795D02*
X1157419Y319188D01*
G01X1156224Y318550D02*
X1156469Y318795D01*
G01X1154824Y317970D02*
X1156224Y318550D01*
G01X1154033Y317970D02*
X1154824D01*
G01X1152758Y318498D02*
X1154033Y317970D01*
G01X1152249Y319007D02*
X1152758Y318498D01*
G01X1151489Y319322D02*
X1152249Y319007D01*
G01X1150477Y319322D02*
X1151489D01*
G01X1149884Y319076D02*
X1150477Y319322D01*
G01X1149256Y318448D02*
X1149884Y319076D01*
G01X1148248Y318031D02*
X1149256Y318448D01*
G01X1146061Y317596D02*
X1148248Y318031D01*
G01X1144300Y317596D02*
X1146061D01*
G01X1117647Y280926D02*
X1120753D01*
G01X1116096Y295809D02*
Y294005D01*
G01X1115113Y334153D02*
X1100217Y349049D01*
G01X1115113Y328123D02*
Y334153D01*
G01X1099737Y349049D02*
X1097797Y350989D01*
G01X1100217Y349049D02*
X1099737D01*
G01X1155091Y348417D02*
X1158231Y345277D01*
G01X1153789Y348417D02*
X1155091D01*
G01X1152587Y347215D02*
X1153789Y348417D01*
G01X1152398Y347215D02*
X1152587D01*
G01X1152397Y347216D02*
X1152398Y347215D01*
G01X1150098Y347216D02*
X1152397D01*
G01X1150097Y347215D02*
X1150098Y347216D01*
G01X1150065Y347215D02*
X1150097D01*
G01X1148863Y348417D02*
X1150065Y347215D01*
G01X1146142Y348417D02*
X1148863D01*
G01X1144951Y347226D02*
X1146142Y348417D01*
G01X1143533Y347226D02*
X1144951D01*
G01X1143106Y347653D02*
X1143533Y347226D01*
G01X1097578Y619334D02*
X1273046D01*
G01X1095311Y621601D02*
X1097578Y619334D01*
G01X1096359Y616570D02*
X1273793D01*
G01X1096241Y615385D02*
X1095645D01*
G01X1096243Y615387D02*
X1096241Y615385D01*
G01X1273957Y615387D02*
X1096243D01*
G01X1096940Y617700D02*
X1273576D01*
G01X1096721Y614235D02*
X1274435D01*
G01X1096719Y614233D02*
X1096721Y614235D01*
G01X1095167Y614233D02*
X1096719D01*
G01X1164580Y274696D02*
X1160075D01*
G01X1212059Y265206D02*
X1209993Y267272D01*
G01X1212059Y264041D02*
Y265206D01*
G01X1227362Y248738D02*
X1212059Y264041D01*
G01X1226100Y247677D02*
X1210897Y262880D01*
G01X1207366Y336550D02*
X1205683Y338233D01*
G01X1221722Y336550D02*
X1207366D01*
G01X1218022Y281360D02*
X1211440D01*
G01X1239597Y259785D02*
X1218022Y281360D01*
G01X1159923Y333577D02*
X1158734Y334766D01*
G01X1162277Y333577D02*
X1159923D01*
G01X1163466Y334766D02*
X1162277Y333577D01*
G01X1165534Y334766D02*
X1163466D01*
G01X1166723Y333577D02*
X1165534Y334766D01*
G01X1168877Y333577D02*
X1166723D01*
G01X1170066Y334766D02*
X1168877Y333577D01*
G01X1172434Y334766D02*
X1170066D01*
G01X1173623Y333577D02*
X1172434Y334766D01*
G01X1175717Y333577D02*
X1173623D01*
G01X1176906Y334766D02*
X1175717Y333577D01*
G01X1179374Y334766D02*
X1176906D01*
G01X1181323Y332817D02*
X1179374Y334766D01*
G01X1182130Y332817D02*
X1181323D01*
G01X1183807Y331140D02*
X1182130Y332817D01*
G01X1186125Y331140D02*
X1183807D01*
G01X1187588Y329677D02*
X1186125Y331140D01*
G01X1188959Y329677D02*
X1187588D01*
G01X1191670Y326966D02*
X1188959Y329677D01*
G01X1192270Y326966D02*
X1191670D01*
G01X1193538Y325698D02*
X1192270Y326966D01*
G01X1195096Y325698D02*
X1193538D01*
G01X1196968Y323826D02*
X1195096Y325698D01*
G01X1199790Y323826D02*
X1196968D01*
G01X1200980Y325016D02*
X1199790Y323826D01*
G01X1218986Y325016D02*
X1200980D01*
G01X1197238Y311401D02*
X1230971D01*
G01X1196357Y310520D02*
X1197238Y311401D01*
G01X1195529Y310177D02*
X1196357Y310520D01*
G01X1194563Y310177D02*
X1195529D01*
G01X1193293Y310703D02*
X1194563Y310177D01*
G01X1192614Y311382D02*
X1193293Y310703D01*
G01X1190514Y312252D02*
X1192614Y311382D01*
G01X1189518Y313248D02*
X1190514Y312252D01*
G01X1186417Y314533D02*
X1189518Y313248D01*
G01X1185212Y315738D02*
X1186417Y314533D01*
G01X1184000Y316240D02*
X1185212Y315738D01*
G01X1182958Y316672D02*
X1184000Y316240D01*
G01X1182166Y317464D02*
X1182958Y316672D01*
G01X1180757Y318048D02*
X1182166Y317464D01*
G01X1180468Y318337D02*
X1180757Y318048D01*
G01X1178259Y319252D02*
X1180468Y318337D01*
G01X1177114Y319252D02*
X1178259D01*
G01X1176346Y318484D02*
X1177114Y319252D01*
G01X1175062Y317952D02*
X1176346Y318484D01*
G01X1174264Y317952D02*
X1175062D01*
G01X1172987Y318481D02*
X1174264Y317952D01*
G01X1172660Y318808D02*
X1172987Y318481D01*
G01X1171687Y319211D02*
X1172660Y318808D01*
G01X1170998Y319211D02*
X1171687D01*
G01X1170050Y318818D02*
X1170998Y319211D01*
G01X1169835Y318603D02*
X1170050Y318818D01*
G01X1165738Y318870D02*
X1165983Y318625D01*
G01X1164888Y319222D02*
X1165738Y318870D01*
G01X1164278Y319222D02*
X1164888D01*
G01X1162964Y318678D02*
X1164278Y319222D01*
G01X1162697Y318411D02*
X1162964Y318678D01*
G01X1161631Y317969D02*
X1162697Y318411D01*
G01X1160789Y317969D02*
X1161631D01*
G01X1159154Y318646D02*
X1160789Y317969D01*
G01X1158914Y318886D02*
X1159154Y318646D01*
G01X1158184Y319188D02*
X1158914Y318886D01*
G01X1157419Y319188D02*
X1158184D01*
G01X1169802Y288726D02*
X1169428Y289100D01*
G01X1172119Y288726D02*
X1169802D01*
G01X1174068Y286777D02*
X1172119Y288726D01*
G01X1176259Y286777D02*
X1174068D01*
G01X1177448Y287966D02*
X1176259Y286777D01*
G01X1178750Y287966D02*
X1177448D01*
G01X1179939Y286777D02*
X1178750Y287966D01*
G01X1182417Y286777D02*
X1179939D01*
G01X1183605Y287965D02*
X1182417Y286777D01*
G01X1217698Y280580D02*
X1212979D01*
G01X1238845Y259433D02*
X1217698Y280580D01*
G01X1217985Y341351D02*
X1237052Y322284D01*
G01X1218228Y342172D02*
X1237804Y322596D01*
G01X1208662Y342172D02*
X1218228D01*
G01X1202417Y348417D02*
X1208662Y342172D01*
G01X1200501Y348417D02*
X1202417D01*
G01X1199024Y346940D02*
X1200501Y348417D01*
G01X1197708Y346940D02*
X1199024D01*
G01X1195608Y349040D02*
X1197708Y346940D01*
G01X1207530Y341351D02*
X1217985D01*
G01X1204364Y344517D02*
X1207530Y341351D01*
G01X1200761Y344517D02*
X1204364D01*
G01X1199232Y342988D02*
X1200761Y344517D01*
G01X1197606Y342988D02*
X1199232D01*
G01X1195717Y344877D02*
X1197606Y342988D01*
G01X1194336Y344877D02*
X1195717D01*
G01X1192610Y346603D02*
X1194336Y344877D01*
G01X1190457Y346603D02*
X1192610D01*
G01X1189121Y345267D02*
X1190457Y346603D01*
G01X1187235Y345267D02*
X1189121D01*
G01X1186036Y346466D02*
X1187235Y345267D01*
G01X1184201Y346466D02*
X1186036D01*
G01X1182250Y348417D02*
X1184201Y346466D01*
G01X1180699Y348417D02*
X1182250D01*
G01X1178750Y350366D02*
X1180699Y348417D01*
G01X1177448Y350366D02*
X1178750D01*
G01X1175499Y348417D02*
X1177448Y350366D01*
G01X1173181Y348417D02*
X1175499D01*
G01X1171990Y347226D02*
X1173181Y348417D01*
G01X1170688Y347226D02*
X1171990D01*
G01X1169497Y348417D02*
X1170688Y347226D01*
G01X1167309Y348417D02*
X1169497D01*
G01X1164169Y345277D02*
X1167309Y348417D01*
G01X1158231Y345277D02*
X1164169D01*
G01X1273990Y-19344D02*
X1295392D01*
G01X1268826Y-14180D02*
X1273990Y-19344D01*
G01X1272664Y-20096D02*
X1295704D01*
G01X1267500Y-14932D02*
X1272664Y-20096D01*
G01X1271764Y-20848D02*
X1299932D01*
G01X1266800Y-15884D02*
X1271764Y-20848D01*
G01X1275392Y-18592D02*
X1289008D01*
G01X1270228Y-13428D02*
X1275392Y-18592D01*
G01X1275300Y-5300D02*
X1284524Y-14524D01*
G01X1275300Y47100D02*
Y-5300D01*
G01X1279000Y-7370D02*
Y34600D01*
G01X1284393Y-12763D02*
X1279000Y-7370D01*
G01X1275100Y-16700D02*
X1285117D01*
G01X1271029Y-12629D02*
X1275100Y-16700D01*
G01X1274148Y-5778D02*
X1282252Y-13882D01*
G01X1274148Y46363D02*
Y-5778D01*
G01X1271700Y-7251D02*
X1267474Y-11477D01*
G01X1271700Y35356D02*
Y-7251D01*
G01X1271900Y50500D02*
X1275300Y47100D01*
G01X1271900Y55273D02*
Y50500D01*
G01X1269670Y57503D02*
X1271900Y55273D01*
G01X1268686Y57503D02*
X1269670D01*
G01X1268149Y58040D02*
X1268686Y57503D01*
G01X1268111Y58040D02*
X1268149D01*
G01X1279000Y34600D02*
X1283380Y38980D01*
G01X1273266Y47245D02*
X1274148Y46363D01*
G01X1267959Y47245D02*
X1273266D01*
G01X1263544Y43512D02*
X1271700Y35356D01*
G01X1263544Y55875D02*
Y43512D01*
G01X1273190Y65521D02*
X1263544Y55875D01*
G01X1273190Y105310D02*
Y65521D01*
G01X1262566Y154973D02*
X1261800D01*
G01X1265300Y157707D02*
X1262566Y154973D01*
G01X1274838Y152848D02*
X1269979Y157707D01*
G01X1282226Y152848D02*
X1274838D01*
G01X1273200Y107700D02*
X1285200Y95700D01*
G01X1273200Y128400D02*
Y107700D01*
G01X1266430Y135170D02*
X1273200Y128400D01*
G01X1262030Y135170D02*
X1266430D01*
G01X1260737Y133877D02*
X1262030Y135170D01*
G01X1271600Y106900D02*
X1273190Y105310D01*
G01X1271600Y116993D02*
Y106900D01*
G01X1269229Y119364D02*
X1271600Y116993D01*
G01X1267107Y119364D02*
X1269229D01*
G01X1264624Y121847D02*
X1267107Y119364D01*
G01X1264624Y123576D02*
Y121847D01*
G01X1264600Y123600D02*
X1264624Y123576D01*
G01X1264600Y128348D02*
Y123600D01*
G01X1263798Y129150D02*
X1264600Y128348D01*
G01X1263798Y133493D02*
Y129150D01*
G01X1224688Y178362D02*
Y221489D01*
G01X1226200Y176850D02*
X1224688Y178362D01*
G01X1232967Y176850D02*
X1226200D01*
G01X1239429Y170388D02*
X1232967Y176850D01*
G01X1252888Y170388D02*
X1239429D01*
G01X1258830Y176330D02*
X1252888Y170388D01*
G01X1293870Y176330D02*
X1258830D01*
G01X1269979Y157707D02*
X1265300D01*
G01X1223100Y178180D02*
Y223163D01*
G01X1309861Y176933D02*
X1239597Y247197D01*
G01X1250385Y176395D02*
X1246655D01*
G01X1252050Y178060D02*
X1250385Y176395D01*
G01X1305188Y178060D02*
X1252050D01*
G01X1308901Y176829D02*
X1238845Y246885D01*
G01X1261333Y261888D02*
X1284187Y239034D01*
G01X1261333Y268189D02*
Y261888D01*
G01X1237804Y291718D02*
X1261333Y268189D01*
G01X1227362Y224163D02*
Y248738D01*
G01X1224688Y221489D02*
X1227362Y224163D01*
G01X1259829Y267529D02*
X1236300Y291058D01*
G01X1259829Y260973D02*
Y267529D01*
G01X1285502Y235300D02*
X1259829Y260973D01*
G01X1226100Y226163D02*
Y247677D01*
G01X1223100Y223163D02*
X1226100Y226163D01*
G01X1239597Y247197D02*
Y259785D01*
G01X1259077Y266881D02*
X1234452Y291506D01*
G01X1259077Y260023D02*
Y266881D01*
G01X1289363Y229737D02*
X1259077Y260023D01*
G01X1257925Y259026D02*
X1283720Y233231D01*
G01X1257925Y266339D02*
Y259026D01*
G01X1233300Y290964D02*
X1257925Y266339D01*
G01X1238845Y246885D02*
Y259433D01*
G01X1260581Y261576D02*
X1283875Y238282D01*
G01X1260581Y267877D02*
Y261576D01*
G01X1237052Y291406D02*
X1260581Y267877D01*
G01X1237804Y322596D02*
Y291718D01*
G01X1236300Y321972D02*
X1221722Y336550D01*
G01X1236300Y291058D02*
Y321972D01*
G01X1234452Y309550D02*
X1218986Y325016D01*
G01X1234452Y291506D02*
Y309550D01*
G01X1233300Y309072D02*
Y290964D01*
G01X1230971Y311401D02*
X1233300Y309072D01*
G01X1237052Y322284D02*
Y291406D01*
G01X1278158Y512348D02*
X1284405Y506101D01*
G01X1273791Y512348D02*
X1278158D01*
G01X1272043Y510600D02*
X1273791Y512348D01*
G01X1271300Y510600D02*
X1272043D01*
G01X1267453Y524890D02*
X1271500Y528937D01*
G01X1261690Y524890D02*
X1267453D01*
G01X1260130Y523330D02*
X1261690Y524890D01*
G01X1260130Y507400D02*
Y523330D01*
G01X1257600Y504870D02*
X1260130Y507400D01*
G01X1257600Y496060D02*
Y504870D01*
G01X1262330Y491330D02*
X1257600Y496060D01*
G01X1276787Y491330D02*
X1262330D01*
G01X1277019Y491562D02*
X1276787Y491330D01*
G01X1277987Y491562D02*
X1277019D01*
G01X1277987Y491571D02*
Y491562D01*
G01X1277978Y491571D02*
X1277987D01*
G01X1253500Y519620D02*
X1255120Y518000D01*
G01X1253500Y553524D02*
Y519620D01*
G01X1271982Y496016D02*
X1269006D01*
G01X1273260Y497294D02*
X1271982Y496016D01*
G01X1273260Y500986D02*
Y497294D01*
G01X1268148Y506098D02*
X1273260Y500986D01*
G01X1268148Y511552D02*
Y506098D01*
G01X1266700Y513000D02*
X1268148Y511552D01*
G01X1266700Y515100D02*
Y513000D01*
G01X1276347Y524747D02*
X1266700Y515100D01*
G01X1276347Y534477D02*
Y524747D01*
G01X1275395Y525142D02*
Y534872D01*
G01X1265748Y515495D02*
X1275395Y525142D01*
G01X1265748Y513395D02*
Y515495D01*
G01X1265747Y513394D02*
X1265748Y513395D01*
G01X1265747Y512606D02*
Y513394D01*
G01X1267196Y511157D02*
X1265747Y512606D01*
G01X1267196Y505086D02*
Y511157D01*
G01X1264523Y502413D02*
X1267196Y505086D01*
G01X1264523Y498043D02*
Y502413D01*
G01X1266162Y496404D02*
X1264523Y498043D01*
G01X1278080Y499817D02*
X1294381D01*
G01X1271993Y493730D02*
X1278080Y499817D01*
G01X1265904Y493730D02*
X1271993D01*
G01X1262843Y496791D02*
X1265904Y493730D01*
G01X1262843Y497553D02*
Y496791D01*
G01X1256696Y511734D02*
X1255120Y510158D01*
G01X1256696Y535458D02*
Y511734D01*
G01X1277453Y510646D02*
X1283700Y504399D01*
G01X1274987Y510646D02*
X1277453D01*
G01X1274576Y510235D02*
X1274987Y510646D01*
G01X1276170Y557790D02*
Y592321D01*
G01X1271500Y553120D02*
X1276170Y557790D01*
G01X1271500Y528937D02*
Y553120D01*
G01X1255120Y555144D02*
X1253500Y553524D01*
G01Y556764D02*
X1255120Y555144D01*
G01X1253500Y591980D02*
Y556764D01*
G01X1279870Y547272D02*
X1280928D01*
G01X1279318Y546720D02*
X1279870Y547272D01*
G01X1279318Y545212D02*
Y546720D01*
G01X1279945Y538075D02*
X1276347Y534477D01*
G01X1279945Y541052D02*
Y538075D01*
G01X1275161Y545836D02*
X1279945Y541052D01*
G01X1275161Y552234D02*
Y545836D01*
G01X1279584Y556657D02*
X1275161Y552234D01*
G01X1279584Y591694D02*
Y556657D01*
G01X1278632Y557052D02*
Y592089D01*
G01X1273872Y552292D02*
X1278632Y557052D01*
G01X1273872Y545778D02*
Y552292D01*
G01X1278993Y540657D02*
X1273872Y545778D01*
G01X1278993Y538470D02*
Y540657D01*
G01X1275395Y534872D02*
X1278993Y538470D01*
G01X1279474Y548224D02*
X1281075D01*
G01X1278643Y547393D02*
X1279474Y548224D01*
G01X1277137Y547393D02*
X1278643D01*
G01X1255120Y537034D02*
X1256696Y535458D01*
G01Y538610D02*
X1255120Y537034D01*
G01X1256696Y573258D02*
Y538610D01*
G01X1255120Y574834D02*
X1256696Y573258D01*
G01X1277200Y540700D02*
Y539100D01*
G01X1272720Y545180D02*
X1277200Y540700D01*
G01X1272720Y552770D02*
Y545180D01*
G01X1277480Y557530D02*
X1272720Y552770D01*
G01X1277480Y592567D02*
Y557530D01*
G01X1276170Y592321D02*
X1285381Y601532D01*
G01X1277799Y624087D02*
X1307284D01*
G01X1273046Y619334D02*
X1277799Y624087D01*
G01X1255120Y593600D02*
X1253500Y591980D01*
G01X1286566Y598676D02*
X1279584Y591694D01*
G01X1279022Y621799D02*
X1302910D01*
G01X1273793Y616570D02*
X1279022Y621799D01*
G01X1279417Y620847D02*
X1273957Y615387D01*
G01X1302515Y620847D02*
X1279417D01*
G01X1278632Y592089D02*
X1286171Y599628D01*
G01X1277350Y600550D02*
X1270400Y593600D01*
G01X1277350Y612350D02*
Y600550D01*
G01X1283119Y618119D02*
X1277350Y612350D01*
G01X1278627Y622751D02*
X1303305D01*
G01X1273576Y617700D02*
X1278627Y622751D01*
G01X1285693Y600780D02*
X1277480Y592567D01*
G01X1279895Y619695D02*
X1302037D01*
G01X1274435Y614235D02*
X1279895Y619695D01*
G01X1303774Y-19366D02*
Y-18842D01*
G01X1306039Y-21631D02*
X1303774Y-19366D01*
G01X1385245Y-21631D02*
X1306039D01*
G01X1298550Y20550D02*
Y51950D01*
G01X1297600Y19600D02*
X1298550Y20550D01*
G01X1297600Y-13692D02*
Y19600D01*
G01X1295992Y-15300D02*
X1297600Y-13692D01*
G01X1295992Y-18744D02*
Y-15300D01*
G01X1295392Y-19344D02*
X1295992Y-18744D01*
G01X1299369Y-15866D02*
Y-15680D01*
G01X1296744Y-18491D02*
X1299369Y-15866D01*
G01X1296744Y-19056D02*
Y-18491D01*
G01X1295704Y-20096D02*
X1296744Y-19056D01*
G01X1299600Y20536D02*
Y52530D01*
G01X1298700Y19636D02*
X1299600Y20536D01*
G01X1298700Y-12117D02*
Y19636D01*
G01X1301363Y-14780D02*
X1298700Y-12117D01*
G01X1301363Y-19417D02*
Y-14780D01*
G01X1299932Y-20848D02*
X1301363Y-19417D01*
G01X1300500Y20372D02*
Y45600D01*
G01X1299524Y19396D02*
X1300500Y20372D01*
G01X1299524Y-11447D02*
Y19396D01*
G01X1302120Y-14043D02*
X1299524Y-11447D01*
G01X1302120Y-19724D02*
Y-14043D01*
G01X1300244Y-21600D02*
X1302120Y-19724D01*
G01X1294160Y-460D02*
X1292692Y1008D01*
G01X1294160Y-10111D02*
Y-460D01*
G01X1290300Y-13971D02*
X1294160Y-10111D01*
G01X1290300Y-17300D02*
Y-13971D01*
G01X1289008Y-18592D02*
X1290300Y-17300D01*
G01X1284524Y-14524D02*
X1284859D01*
G01X1285715Y-12763D02*
X1284393D01*
G01X1286800Y-13848D02*
X1285715Y-12763D01*
G01X1286800Y-15017D02*
Y-13848D01*
G01X1285117Y-16700D02*
X1286800Y-15017D01*
G01X1282252Y-13882D02*
Y-14747D01*
G01X1328000Y65300D02*
X1327500D01*
G01X1333054Y70354D02*
X1328000Y65300D01*
G01X1333054Y76857D02*
Y70354D01*
G01X1329658Y80253D02*
X1333054Y76857D01*
G01X1327890Y80253D02*
X1329658D01*
G01X1327889Y80252D02*
X1327890Y80253D01*
G01X1319848Y80252D02*
X1327889D01*
G01X1318276Y81824D02*
X1319848Y80252D01*
G01X1317456Y81824D02*
X1318276D01*
G01X1315448Y83832D02*
X1317456Y81824D01*
G01X1315448Y85052D02*
Y83832D01*
G01X1296682Y103818D02*
X1315448Y85052D01*
G01X1324500Y86900D02*
X1306048Y105352D01*
G01X1335450Y86900D02*
X1324500D01*
G01X1342098Y80252D02*
X1335450Y86900D01*
G01X1314690Y89603D02*
Y94880D01*
G01X1317195Y87098D02*
X1314690Y89603D01*
G01X1329552Y72871D02*
X1327467Y70786D01*
G01X1329552Y75482D02*
Y72871D01*
G01X1328244Y76790D02*
X1329552Y75482D01*
G01X1318496Y76790D02*
X1328244D01*
G01X1316866Y78420D02*
X1318496Y76790D01*
G01X1316046Y78420D02*
X1316866D01*
G01X1312043Y82423D02*
X1316046Y78420D01*
G01X1312043Y83643D02*
Y82423D01*
G01X1293278Y102408D02*
X1312043Y83643D01*
G01X1300600Y88522D02*
X1301219Y89141D01*
G01X1300600Y72800D02*
Y88522D01*
G01X1295534Y67734D02*
X1300600Y72800D01*
G01X1295534Y54966D02*
Y67734D01*
G01X1298550Y51950D02*
X1295534Y54966D01*
G01X1301400Y75542D02*
X1304685Y78827D01*
G01X1301400Y72300D02*
Y75542D01*
G01X1296286Y67186D02*
X1301400Y72300D01*
G01X1296286Y55844D02*
Y67186D01*
G01X1299600Y52530D02*
X1296286Y55844D01*
G01X1328200Y68000D02*
X1327500D01*
G01X1331254Y71054D02*
X1328200Y68000D01*
G01X1331254Y76187D02*
Y71054D01*
G01X1328891Y78550D02*
X1331254Y76187D01*
G01X1319143Y78550D02*
X1328891D01*
G01X1317571Y80122D02*
X1319143Y78550D01*
G01X1316751Y80122D02*
X1317571D01*
G01X1313746Y83127D02*
X1316751Y80122D01*
G01X1313746Y84347D02*
Y83127D01*
G01X1294980Y103113D02*
X1313746Y84347D01*
G01X1309976Y83024D02*
X1309700Y83300D01*
G01X1309976Y55076D02*
Y83024D01*
G01X1300500Y45600D02*
X1309976Y55076D01*
G01X1318224Y83676D02*
X1317300Y84600D01*
G01X1320976Y83676D02*
X1318224D01*
G01X1322600Y85300D02*
X1320976Y83676D01*
G01X1334600Y85300D02*
X1322600D01*
G01X1340800Y79100D02*
X1334600Y85300D01*
G01X1358500Y79100D02*
X1340800D01*
G01X1296400Y76022D02*
X1298422Y74000D01*
G01X1296400Y89700D02*
Y76022D01*
G01X1290400Y95700D02*
X1296400Y89700D01*
G01X1294828Y38980D02*
X1296908Y36900D01*
G01X1283380Y38980D02*
X1294828D01*
G01X1324800Y88300D02*
X1307000Y106100D01*
G01X1335680Y88300D02*
X1324800D01*
G01X1342576Y81404D02*
X1335680Y88300D01*
G01X1296682Y114068D02*
Y103818D01*
G01X1299605Y116991D02*
X1296682Y114068D01*
G01X1299605Y129050D02*
Y116991D01*
G01X1308415Y137860D02*
X1299605Y129050D01*
G01X1324952Y137860D02*
X1308415D01*
G01X1325563Y137249D02*
X1324952Y137860D01*
G01X1329919Y137249D02*
X1325563D01*
G01X1330530Y137860D02*
X1329919Y137249D01*
G01X1337468Y137860D02*
X1330530D01*
G01X1342584Y142976D02*
X1337468Y137860D01*
G01X1322203Y132500D02*
X1323026Y133323D01*
G01X1311950Y132500D02*
X1322203D01*
G01X1306048Y126598D02*
X1311950Y132500D01*
G01X1306048Y105352D02*
Y126598D01*
G01X1331190Y135900D02*
X1372400D01*
G01X1330687Y135397D02*
X1331190Y135900D01*
G01X1324795Y135397D02*
X1330687D01*
G01X1324184Y136008D02*
X1324795Y135397D01*
G01X1313758Y136008D02*
X1324184D01*
G01X1305600Y127850D02*
X1313758Y136008D01*
G01X1305600Y127780D02*
Y127850D01*
G01X1304896Y127076D02*
X1305600Y127780D01*
G01X1304896Y104674D02*
Y127076D01*
G01X1314690Y94880D02*
X1304896Y104674D01*
G01X1293278Y115478D02*
Y102408D01*
G01X1296200Y118400D02*
X1293278Y115478D01*
G01X1296200Y130459D02*
Y118400D01*
G01X1307005Y141264D02*
X1296200Y130459D01*
G01X1326362Y141264D02*
X1307005D01*
G01X1326973Y140653D02*
X1326362Y141264D01*
G01X1328509Y140653D02*
X1326973D01*
G01X1333315Y145459D02*
X1328509Y140653D01*
G01X1333315Y171904D02*
Y145459D01*
G01X1292659Y142415D02*
X1282226Y152848D01*
G01X1300695Y142415D02*
X1292659D01*
G01X1306584Y148304D02*
X1300695Y142415D01*
G01X1311197Y148304D02*
X1306584D01*
G01X1312719Y149826D02*
X1311197Y148304D01*
G01X1324630Y149826D02*
X1312719D01*
G01X1327900Y146556D02*
X1324630Y149826D01*
G01X1327900Y142918D02*
Y146556D01*
G01X1294980Y114773D02*
Y103113D01*
G01X1297903Y117696D02*
X1294980Y114773D01*
G01X1297903Y129755D02*
Y117696D01*
G01X1307710Y139562D02*
X1297903Y129755D01*
G01X1325657Y139562D02*
X1307710D01*
G01X1326268Y138951D02*
X1325657Y139562D01*
G01X1329214Y138951D02*
X1326268D01*
G01X1329825Y139562D02*
X1329214Y138951D01*
G01X1334649Y139562D02*
X1329825D01*
G01X1337659Y142572D02*
X1334649Y139562D01*
G01X1337659Y182709D02*
Y142572D01*
G01X1285200Y95700D02*
X1290400D01*
G01X1324203Y131500D02*
X1326026Y133323D01*
G01X1312500Y131500D02*
X1324203D01*
G01X1307000Y126000D02*
X1312500Y131500D01*
G01X1307000Y106100D02*
Y126000D01*
G01X1333667Y172256D02*
X1333315Y171904D01*
G01X1335448Y172256D02*
X1333667D01*
G01X1335800Y172608D02*
X1335448Y172256D01*
G01X1335800Y173312D02*
Y172608D01*
G01X1335448Y173664D02*
X1335800Y173312D01*
G01X1333667Y173664D02*
X1335448D01*
G01X1333315Y174016D02*
X1333667Y173664D01*
G01X1333315Y174720D02*
Y174016D01*
G01X1333667Y175072D02*
X1333315Y174720D01*
G01X1335448Y175072D02*
X1333667D01*
G01X1335800Y175424D02*
X1335448Y175072D01*
G01X1335800Y176128D02*
Y175424D01*
G01X1335448Y176480D02*
X1335800Y176128D01*
G01X1333667Y176480D02*
X1335448D01*
G01X1333315Y176832D02*
X1333667Y176480D01*
G01X1333315Y177536D02*
Y176832D01*
G01X1333667Y177888D02*
X1333315Y177536D01*
G01X1335448Y177888D02*
X1333667D01*
G01X1335800Y178240D02*
X1335448Y177888D01*
G01X1335800Y178944D02*
Y178240D01*
G01X1335448Y179296D02*
X1335800Y178944D01*
G01X1333667Y179296D02*
X1335448D01*
G01X1333315Y179648D02*
X1333667Y179296D01*
G01X1333315Y180937D02*
Y179648D01*
G01X1356926Y204548D02*
X1333315Y180937D01*
G01X1334724Y209351D02*
Y209051D01*
G01X1332052Y212023D02*
X1334724Y209351D01*
G01X1315211Y212023D02*
X1332052D01*
G01X1288200Y239034D02*
X1315211Y212023D01*
G01X1300300Y169900D02*
X1293870Y176330D01*
G01X1309861Y165435D02*
Y176933D01*
G01X1310061Y165235D02*
X1309861Y165435D01*
G01X1319266Y205602D02*
X1295131Y229737D01*
G01X1337802Y205602D02*
X1319266D01*
G01X1341472Y209272D02*
X1337802Y205602D01*
G01X1344462Y209272D02*
X1341472D01*
G01X1307985Y175263D02*
X1305188Y178060D01*
G01X1307985Y168702D02*
Y175263D01*
G01X1306804Y167521D02*
X1307985Y168702D01*
G01X1305622Y167521D02*
X1306804D01*
G01X1303518Y165417D02*
X1305622Y167521D01*
G01X1303518Y158640D02*
Y165417D01*
G01X1301453Y156575D02*
X1303518Y158640D01*
G01X1287790Y156575D02*
X1301453D01*
G01X1359500Y204550D02*
X1337659Y182709D01*
G01X1308901Y166841D02*
Y176829D01*
G01X1306827Y164767D02*
X1308901Y166841D01*
G01X1305171Y164767D02*
X1306827D01*
G01X1335987Y206814D02*
X1338224Y209051D01*
G01X1319356Y206814D02*
X1335987D01*
G01X1287888Y238282D02*
X1319356Y206814D01*
G01X1284187Y239034D02*
X1288200D01*
G01X1287400Y235300D02*
X1285502D01*
G01X1288800Y233900D02*
X1287400Y235300D01*
G01X1295131Y229737D02*
X1289363D01*
G01X1283720Y233231D02*
Y223870D01*
G01X1283875Y238282D02*
X1287888D01*
G01X1338414Y413157D02*
X1348955Y423698D01*
G01X1319455Y413157D02*
X1338414D01*
G01X1316820Y415792D02*
X1319455Y413157D01*
G01X1316820Y418900D02*
Y415792D01*
G01X1337709Y414859D02*
X1348250Y425400D01*
G01X1320253Y414859D02*
X1337709D01*
G01X1319320Y415792D02*
X1320253Y414859D01*
G01X1319320Y418900D02*
Y415792D01*
G01X1315157Y419737D02*
X1316820Y421400D01*
G01X1315157Y419645D02*
Y419737D01*
G01X1315118Y419606D02*
X1315157Y419645D01*
G01X1315118Y415087D02*
Y419606D01*
G01X1315157Y415048D02*
X1315118Y415087D01*
G01X1315157Y415041D02*
Y415048D01*
G01X1318743Y411455D02*
X1315157Y415041D01*
G01X1339120Y411455D02*
X1318743D01*
G01X1340116Y412451D02*
X1339120Y411455D01*
G01X1340116Y412452D02*
Y412451D01*
G01X1349660Y421996D02*
X1340116Y412452D01*
G01X1337821Y506339D02*
X1356539D01*
G01X1336082Y504600D02*
X1337821Y506339D01*
G01X1328400Y504600D02*
X1336082D01*
G01X1322500Y510500D02*
X1328400Y504600D01*
G01X1303652Y510500D02*
X1322500D01*
G01X1299760Y506608D02*
X1303652Y510500D01*
G01X1293738Y506608D02*
X1299760D01*
G01X1293231Y506101D02*
X1293738Y506608D01*
G01X1284405Y506101D02*
X1293231D01*
G01X1288508Y501897D02*
X1287770D01*
G01X1288919Y502308D02*
X1288508Y501897D01*
G01X1294252Y502308D02*
X1288919D01*
G01X1295148Y503204D02*
X1294252Y502308D01*
G01X1302254Y503204D02*
X1295148D01*
G01X1305550Y506500D02*
X1302254Y503204D01*
G01X1321120Y506500D02*
X1305550D01*
G01X1326424Y501196D02*
X1321120Y506500D01*
G01X1337492Y501196D02*
X1326424D01*
G01X1339231Y502935D02*
X1337492Y501196D01*
G01X1358234Y502935D02*
X1339231D01*
G01X1340583Y501083D02*
X1359182D01*
G01X1338700Y499200D02*
X1340583Y501083D01*
G01X1338700Y498100D02*
Y499200D01*
G01X1337300Y496700D02*
X1338700Y498100D01*
G01X1327329Y496700D02*
X1337300D01*
G01X1319533Y504496D02*
X1327329Y496700D01*
G01X1306196Y504496D02*
X1319533D01*
G01X1303052Y501352D02*
X1306196Y504496D01*
G01X1295916Y501352D02*
X1303052D01*
G01X1294381Y499817D02*
X1295916Y501352D01*
G01X1338526Y504637D02*
X1357436D01*
G01X1336787Y502898D02*
X1338526Y504637D01*
G01X1327129Y502898D02*
X1336787D01*
G01X1321637Y508390D02*
X1327129Y502898D01*
G01X1304011Y508390D02*
X1321637D01*
G01X1300527Y504906D02*
X1304011Y508390D01*
G01X1294443Y504906D02*
X1300527D01*
G01X1293936Y504399D02*
X1294443Y504906D01*
G01X1283700Y504399D02*
X1293936D01*
G01X1341050Y498275D02*
X1342706Y499931D01*
G01X1332480Y545255D02*
X1368695D01*
G01X1328541Y549194D02*
X1332480Y545255D01*
G01X1298906Y549194D02*
X1328541D01*
G01X1298292Y549808D02*
X1298906Y549194D01*
G01X1298292Y559077D02*
Y549808D01*
G01X1298719Y559504D02*
X1298292Y559077D01*
G01X1298719Y583168D02*
Y559504D01*
G01X1296082Y585805D02*
X1298719Y583168D01*
G01X1296082Y599421D02*
Y585805D01*
G01X1295090Y547390D02*
Y579360D01*
G01X1291300Y543600D02*
X1295090Y547390D01*
G01X1284600Y543600D02*
X1291300D01*
G01X1280928Y547272D02*
X1284600Y543600D01*
G01X1340533Y542121D02*
X1349864Y532790D01*
G01X1331490Y542121D02*
X1340533D01*
G01X1327956Y545655D02*
X1331490Y542121D01*
G01X1293290Y578710D02*
Y581160D01*
G01X1294148Y577852D02*
X1293290Y578710D01*
G01X1294148Y547795D02*
Y577852D01*
G01X1290905Y544552D02*
X1294148Y547795D01*
G01X1284747Y544552D02*
X1290905D01*
G01X1281075Y548224D02*
X1284747Y544552D01*
G01X1332114Y543987D02*
X1369087D01*
G01X1328581Y547520D02*
X1332114Y543987D01*
G01X1298470Y547520D02*
X1328581D01*
G01X1297140Y548850D02*
X1298470Y547520D01*
G01X1297140Y558599D02*
Y548850D01*
G01X1297139Y558600D02*
X1297140Y558599D01*
G01X1297139Y559554D02*
Y558600D01*
G01X1297250Y559665D02*
X1297139Y559554D01*
G01X1297250Y583007D02*
Y559665D01*
G01X1294930Y585327D02*
X1297250Y583007D01*
G01X1294930Y598943D02*
Y585327D01*
G01X1297680Y614211D02*
X1296295Y615596D01*
G01X1297680Y612997D02*
Y614211D01*
G01X1296916Y612233D02*
X1297680Y612997D01*
G01X1296916Y608116D02*
Y612233D01*
G01X1290332Y601532D02*
X1296916Y608116D01*
G01X1285381Y601532D02*
X1290332D01*
G01X1302200Y605539D02*
X1296082Y599421D01*
G01X1302200Y609066D02*
Y605539D01*
G01X1309707Y616573D02*
X1302200Y609066D01*
G01X1309707Y621664D02*
Y616573D01*
G01X1307284Y624087D02*
X1309707Y621664D01*
G01X1291603Y598676D02*
X1286566D01*
G01X1299772Y606845D02*
X1291603Y598676D01*
G01X1299772Y611048D02*
Y606845D01*
G01X1305064Y616340D02*
X1299772Y611048D01*
G01X1305064Y619645D02*
Y616340D01*
G01X1302910Y621799D02*
X1305064Y619645D01*
G01X1304112Y619250D02*
X1302515Y620847D01*
G01X1304112Y616735D02*
Y619250D01*
G01X1298820Y611443D02*
X1304112Y616735D01*
G01X1298820Y607240D02*
Y611443D01*
G01X1291208Y599628D02*
X1298820Y607240D01*
G01X1286171Y599628D02*
X1291208D01*
G01X1301384Y618119D02*
X1283119D01*
G01X1294929Y598944D02*
X1294930Y598943D01*
G01X1294929Y599898D02*
Y598944D01*
G01X1295510Y600479D02*
X1294929Y599898D01*
G01X1295510Y600560D02*
Y600479D01*
G01X1300724Y605774D02*
X1295510Y600560D01*
G01X1300724Y610653D02*
Y605774D01*
G01X1306016Y615945D02*
X1300724Y610653D01*
G01X1306016Y620040D02*
Y615945D01*
G01X1303305Y622751D02*
X1306016Y620040D01*
G01X1290730Y600780D02*
X1285693D01*
G01X1297668Y607718D02*
X1290730Y600780D01*
G01X1297668Y611921D02*
Y607718D01*
G01X1302960Y617213D02*
X1297668Y611921D01*
G01X1302960Y618772D02*
Y617213D01*
G01X1302037Y619695D02*
X1302960Y618772D01*
G01X1391214Y-15662D02*
X1385245Y-21631D01*
G01X1391214Y1112D02*
Y-15662D01*
G01X1397502Y7400D02*
X1391214Y1112D01*
G01X1408900Y7400D02*
X1397502D01*
G01X1355372Y80252D02*
X1342098D01*
G01X1358120Y83000D02*
X1355372Y80252D01*
G01X1359500Y83000D02*
X1358120D01*
G01X1364000Y84600D02*
X1358500Y79100D01*
G01X1371317Y84600D02*
X1364000D01*
G01X1374131Y81786D02*
X1371317Y84600D01*
G01X1386284Y81786D02*
X1374131D01*
G01X1387681Y83183D02*
X1386284Y81786D01*
G01X1387681Y90790D02*
Y83183D01*
G01X1389638Y92747D02*
X1387681Y90790D01*
G01X1399514Y92747D02*
X1389638D01*
G01X1400427Y91834D02*
X1399514Y92747D01*
G01X1400427Y80174D02*
Y91834D01*
G01X1404970Y75631D02*
X1400427Y80174D01*
G01X1403640Y47370D02*
X1404970Y48700D01*
G01X1413701Y27647D02*
X1403640Y37708D01*
G01X1355148Y81404D02*
X1342576D01*
G01X1355500Y81756D02*
X1355148Y81404D01*
G01X1355500Y83000D02*
Y81756D01*
G01X1342584Y185213D02*
Y142976D01*
G01X1399400Y130399D02*
Y126400D01*
G01X1396599Y133200D02*
X1399400Y130399D01*
G01X1375100Y133200D02*
X1396599D01*
G01X1372400Y135900D02*
X1375100Y133200D01*
G01X1362000Y204629D02*
X1342584Y185213D01*
G01X1362000Y209300D02*
Y204629D01*
G01X1356926Y209100D02*
Y204548D01*
G01X1359500Y209200D02*
Y204550D01*
G01X1392165Y444565D02*
X1395100Y447500D01*
G01X1392165Y426366D02*
Y444565D01*
G01X1389497Y423698D02*
X1392165Y426366D01*
G01X1348955Y423698D02*
X1389497D01*
G01X1388100Y450500D02*
X1390100Y452500D01*
G01X1388100Y427750D02*
Y450500D01*
G01X1385750Y425400D02*
X1388100Y427750D01*
G01X1348250Y425400D02*
X1385750D01*
G01X1392586Y421996D02*
X1349660D01*
G01X1397430Y426840D02*
X1392586Y421996D01*
G01X1397430Y448348D02*
Y426840D01*
G01X1390100Y455678D02*
X1397430Y448348D01*
G01X1390100Y457500D02*
Y455678D01*
G01X1398831Y508404D02*
X1416496D01*
G01X1397979Y509256D02*
X1398831Y508404D01*
G01X1371630Y509256D02*
X1397979D01*
G01X1370124Y507750D02*
X1371630Y509256D01*
G01X1357950Y507750D02*
X1370124D01*
G01X1356539Y506339D02*
X1357950Y507750D01*
G01X1359641Y504342D02*
X1358234Y502935D01*
G01X1371532Y504342D02*
X1359641D01*
G01X1373042Y505852D02*
X1371532Y504342D01*
G01X1396568Y505852D02*
X1373042D01*
G01X1397420Y505000D02*
X1396568Y505852D01*
G01X1418200Y505000D02*
X1397420D01*
G01X1395862Y501244D02*
X1439856D01*
G01X1395354Y501752D02*
X1395862Y501244D01*
G01X1374256Y501752D02*
X1395354D01*
G01X1373090Y500586D02*
X1374256Y501752D01*
G01X1361570Y500586D02*
X1373090D01*
G01X1359084Y498100D02*
X1361570Y500586D01*
G01X1344943Y498100D02*
X1359084D01*
G01X1344761Y498282D02*
X1344943Y498100D01*
G01X1395756Y530840D02*
X1407884Y518712D01*
G01X1396652Y503148D02*
X1419848D01*
G01X1395800Y504000D02*
X1396652Y503148D01*
G01X1373810Y504000D02*
X1395800D01*
G01X1372300Y502490D02*
X1373810Y504000D01*
G01X1360589Y502490D02*
X1372300D01*
G01X1359182Y501083D02*
X1360589Y502490D01*
G01X1398125Y506702D02*
X1417202D01*
G01X1397273Y507554D02*
X1398125Y506702D01*
G01X1372335Y507554D02*
X1397273D01*
G01X1370829Y506048D02*
X1372335Y507554D01*
G01X1358847Y506048D02*
X1370829D01*
G01X1357436Y504637D02*
X1358847Y506048D01*
G01X1394390Y533836D02*
X1406226Y522000D01*
G01X1396174Y501996D02*
X1421296D01*
G01X1395322Y502848D02*
X1396174Y501996D01*
G01X1374288Y502848D02*
X1395322D01*
G01X1372778Y501338D02*
X1374288Y502848D01*
G01X1361239Y501338D02*
X1372778D01*
G01X1359832Y499931D02*
X1361239Y501338D01*
G01X1342706Y499931D02*
X1359832D01*
G01X1394798Y549328D02*
X1390595D01*
G01X1398145Y545981D02*
X1394798Y549328D01*
G01X1398145Y536856D02*
Y545981D01*
G01X1400810Y534191D02*
X1398145Y536856D01*
G01X1400810Y530110D02*
Y534191D01*
G01X1406732Y524188D02*
X1400810Y530110D01*
G01X1401562Y531198D02*
X1407820Y524940D01*
G01X1401562Y543628D02*
Y531198D01*
G01X1393230Y551960D02*
X1401562Y543628D01*
G01X1389370Y551960D02*
X1393230D01*
G01X1388250Y550840D02*
X1389370Y551960D01*
G01X1374280Y550840D02*
X1388250D01*
G01X1368695Y545255D02*
X1374280Y550840D01*
G01X1370850Y530840D02*
X1395756D01*
G01X1368900Y532790D02*
X1370850Y530840D01*
G01X1349864Y532790D02*
X1368900D01*
G01X1394390Y543304D02*
Y533836D01*
G01X1388224Y549470D02*
X1394390Y543304D01*
G01X1374570Y549470D02*
X1388224D01*
G01X1369087Y543987D02*
X1374570Y549470D01*
G01X1410600Y9100D02*
X1408900Y7400D01*
G01X1452891Y27647D02*
X1413701D01*
G01X1462059Y18479D02*
X1452891Y27647D01*
G01X1469314Y18479D02*
X1462059D01*
G01X1404970Y48700D02*
Y75631D01*
G01X1403640Y37708D02*
Y47370D01*
G01X1460408Y262809D02*
X1482367D01*
G01X1459572Y263645D02*
X1460408Y262809D01*
G01X1459572Y271011D02*
Y263645D01*
G01X1458450Y272133D02*
X1459572Y271011D01*
G01X1457443Y272133D02*
X1458450D01*
G01X1456395Y273181D02*
X1457443Y272133D01*
G01X1456395Y274189D02*
Y273181D01*
G01X1455319Y275265D02*
X1456395Y274189D01*
G01X1454311Y275265D02*
X1455319D01*
G01X1453432Y276144D02*
X1454311Y275265D01*
G01X1453432Y286811D02*
Y276144D01*
G01X1454056Y265123D02*
Y266169D01*
G01X1460450Y258729D02*
X1454056Y265123D01*
G01X1468260Y258729D02*
X1460450D01*
G01X1455800Y257900D02*
X1454000Y259700D01*
G01X1469327Y257900D02*
X1455800D01*
G01X1465014Y263639D02*
X1482640D01*
G01X1462964Y265689D02*
X1465014Y263639D01*
G01X1462964Y268736D02*
Y265689D01*
G01X1461300Y270400D02*
X1462964Y268736D01*
G01X1459547Y261933D02*
X1482143D01*
G01X1456500Y264980D02*
X1459547Y261933D01*
G01X1456500Y272005D02*
Y264980D01*
G01X1454902Y273603D02*
X1456500Y272005D01*
G01X1464351Y276753D02*
X1466029Y275075D01*
G01X1459700Y273026D02*
Y280333D01*
G01X1460856Y271870D02*
X1459700Y273026D01*
G01X1462179Y271870D02*
X1460856D01*
G01X1469312Y264737D02*
X1462179Y271870D01*
G01X1464444Y244716D02*
X1479759Y229401D01*
G01X1464444Y245356D02*
Y244716D01*
G01X1457224Y252576D02*
X1464444Y245356D01*
G01X1457224Y255535D02*
Y252576D01*
G01X1455707Y257052D02*
X1457224Y255535D01*
G01X1452812Y257052D02*
X1455707D01*
G01X1449422Y260442D02*
X1452812Y257052D01*
G01X1449422Y263876D02*
Y260442D01*
G01X1450100Y264554D02*
X1449422Y263876D01*
G01X1450100Y297145D02*
Y264554D01*
G01X1447107Y265792D02*
Y315123D01*
G01X1448100Y264799D02*
X1447107Y265792D01*
G01X1448100Y260700D02*
Y264799D01*
G01X1452500Y256300D02*
X1448100Y260700D01*
G01X1453400Y256300D02*
X1452500D01*
G01X1454024Y255676D02*
X1453400Y256300D01*
G01X1454024Y254173D02*
Y255676D01*
G01X1454947Y253250D02*
X1454024Y254173D01*
G01X1455275Y253250D02*
X1454947D01*
G01X1463481Y245044D02*
X1455275Y253250D01*
G01X1463481Y243972D02*
Y245044D01*
G01X1478118Y229335D02*
X1463481Y243972D01*
G01X1464634Y293055D02*
X1468751Y288938D01*
G01X1463813Y293055D02*
X1464634D01*
G01X1462763Y294105D02*
X1463813Y293055D01*
G01X1462763Y299677D02*
Y294105D01*
G01X1462120Y300320D02*
X1462763Y299677D01*
G01X1460513Y300320D02*
X1462120D01*
G01X1459664Y301169D02*
X1460513Y300320D01*
G01X1459664Y306022D02*
Y301169D01*
G01X1458909Y306777D02*
X1459664Y306022D01*
G01X1456973Y306777D02*
X1458909D01*
G01X1456582Y307168D02*
X1456973Y306777D01*
G01X1456582Y312006D02*
Y307168D01*
G01X1457443Y312867D02*
X1456582Y312006D01*
G01X1458452Y312867D02*
X1457443D01*
G01X1459522Y313937D02*
X1458452Y312867D01*
G01X1459522Y314945D02*
Y313937D01*
G01X1460593Y316016D02*
X1459522Y314945D01*
G01X1462671Y316016D02*
X1460593D01*
G01X1465400Y318745D02*
X1462671Y316016D01*
G01X1459555Y312900D02*
X1458052Y311397D01*
G01X1462436Y312900D02*
X1459555D01*
G01X1469740Y320204D02*
X1462436Y312900D01*
G01X1454293Y287672D02*
X1453432Y286811D01*
G01X1455302Y287672D02*
X1454293D01*
G01X1456372Y288742D02*
X1455302Y287672D01*
G01X1456372Y299528D02*
Y288742D01*
G01X1454902Y300998D02*
X1456372Y299528D01*
G01X1454902Y301948D02*
Y300998D01*
G01X1455028Y320179D02*
X1469649Y334800D01*
G01X1448329Y320179D02*
X1455028D01*
G01X1446998Y318848D02*
X1448329Y320179D01*
G01X1446998Y317034D02*
Y318848D01*
G01X1445746Y315782D02*
X1446998Y317034D01*
G01X1445746Y314493D02*
Y315782D01*
G01X1443900Y312647D02*
X1445746Y314493D01*
G01X1443900Y294053D02*
Y312647D01*
G01X1445427Y292526D02*
X1443900Y294053D01*
G01X1453222Y300478D02*
X1454902Y298798D01*
G01X1451144Y300478D02*
X1453222D01*
G01X1450283Y301339D02*
X1451144Y300478D01*
G01X1450283Y312006D02*
Y301339D01*
G01X1451144Y312867D02*
X1450283Y312006D01*
G01X1452153Y312867D02*
X1451144D01*
G01X1453223Y313937D02*
X1452153Y312867D01*
G01X1453223Y314946D02*
Y313937D01*
G01X1454377Y316100D02*
X1453223Y314946D01*
G01X1455384Y316100D02*
X1454377D01*
G01X1456607Y317323D02*
X1455384Y316100D01*
G01X1456607Y319029D02*
Y317323D01*
G01X1457325Y319747D02*
X1456607Y319029D01*
G01X1457326Y319747D02*
X1457325D01*
G01X1466777Y329198D02*
X1457326Y319747D01*
G01X1464870Y290911D02*
X1468000Y287781D01*
G01X1461819Y290911D02*
X1464870D01*
G01X1459675Y293055D02*
X1461819Y290911D01*
G01X1459675Y299584D02*
Y293055D01*
G01X1458915Y300344D02*
X1459675Y299584D01*
G01X1457517Y300344D02*
X1458915D01*
G01X1456598Y301263D02*
X1457517Y300344D01*
G01X1456598Y301323D02*
Y301263D01*
G01X1456581Y301340D02*
X1456598Y301323D01*
G01X1456581Y302558D02*
Y301340D01*
G01X1456598Y302575D02*
X1456581Y302558D01*
G01X1456598Y304473D02*
Y302575D01*
G01X1456582Y304489D02*
X1456598Y304473D01*
G01X1456582Y305614D02*
Y304489D01*
G01X1455419Y306777D02*
X1456582Y305614D01*
G01X1454293Y306777D02*
X1455419D01*
G01X1453432Y307638D02*
X1454293Y306777D01*
G01X1453432Y312006D02*
Y307638D01*
G01X1454476Y313050D02*
X1453432Y312006D01*
G01X1455485Y313050D02*
X1454476D01*
G01X1456450Y314015D02*
X1455485Y313050D01*
G01X1456450Y315023D02*
Y314015D01*
G01X1457477Y316050D02*
X1456450Y315023D01*
G01X1458483Y316050D02*
X1457477D01*
G01X1460300Y317867D02*
X1458483Y316050D01*
G01X1460300Y320385D02*
Y317867D01*
G01X1466755Y326840D02*
X1460300Y320385D01*
G01X1466349Y303946D02*
X1464351Y301948D01*
G01X1453250Y319193D02*
X1451753Y317696D01*
G01X1455708Y319193D02*
X1453250D01*
G01X1469409Y332894D02*
X1455708Y319193D01*
G01X1463600Y300400D02*
X1465600D01*
G01X1462900Y301100D02*
X1463600Y300400D01*
G01X1462900Y301320D02*
Y301100D01*
G01X1462881Y301339D02*
X1462900Y301320D01*
G01X1462881Y302557D02*
Y301339D01*
G01X1462900Y302576D02*
X1462881Y302557D01*
G01X1462900Y304470D02*
Y302576D01*
G01X1462881Y304489D02*
X1462900Y304470D01*
G01X1462881Y305707D02*
Y304489D01*
G01X1462900Y305726D02*
X1462881Y305707D01*
G01X1462900Y307200D02*
Y305726D01*
G01X1461853Y308247D02*
X1462900Y307200D01*
G01X1458052Y308247D02*
X1461853D01*
G01X1456500Y284604D02*
X1454902Y286202D01*
G01X1456500Y282523D02*
Y284604D01*
G01X1457651Y281372D02*
X1456500Y282523D01*
G01X1458661Y281372D02*
X1457651D01*
G01X1459700Y280333D02*
X1458661Y281372D01*
G01X1451753Y298798D02*
X1450100Y297145D01*
G01X1448603Y316625D02*
Y317696D01*
G01X1447133Y315155D02*
X1448603Y316625D01*
G01X1447133Y315149D02*
Y315155D01*
G01X1447107Y315123D02*
X1447133Y315149D01*
G01X1474775Y442675D02*
X1458300D01*
G01X1422850Y522820D02*
X1430720Y530690D01*
G01X1422850Y514758D02*
Y522820D01*
G01X1416496Y508404D02*
X1422850Y514758D01*
G01X1413352Y524188D02*
X1406732D01*
G01X1419088Y529924D02*
X1413352Y524188D01*
G01X1426832Y513632D02*
X1418200Y505000D01*
G01X1426832Y521561D02*
Y513632D01*
G01X1432556Y527285D02*
X1426832Y521561D01*
G01X1413040Y524940D02*
X1419600Y531500D01*
G01X1407820Y524940D02*
X1413040D01*
G01X1449884Y487592D02*
X1449568Y487276D01*
G01X1449884Y491216D02*
Y487592D01*
G01X1439856Y501244D02*
X1449884Y491216D01*
G01X1407884Y518712D02*
Y512751D01*
G01X1434500Y525514D02*
X1442010Y533024D01*
G01X1434500Y517800D02*
Y525514D01*
G01X1419848Y503148D02*
X1434500Y517800D01*
G01X1452000Y487411D02*
X1452188Y487223D01*
G01X1452000Y490316D02*
Y487411D01*
G01X1439505Y502811D02*
X1452000Y490316D01*
G01X1439505Y526060D02*
Y502811D01*
G01X1438390Y527175D02*
X1439505Y526060D01*
G01X1425130Y522390D02*
X1431728Y528988D01*
G01X1425130Y514631D02*
Y522390D01*
G01X1417494Y506995D02*
X1425130Y514631D01*
G01X1417494Y506994D02*
Y506995D01*
G01X1417202Y506702D02*
X1417494Y506994D01*
G01X1416110Y523600D02*
X1425500Y532990D01*
G01X1414761Y523600D02*
X1416110D01*
G01X1413162Y522001D02*
X1414761Y523600D01*
G01X1407181Y522001D02*
X1413162D01*
G01X1407180Y522000D02*
X1407181Y522001D01*
G01X1406226Y522000D02*
X1407180D01*
G01X1437473Y524027D02*
X1436358Y525142D01*
G01X1437473Y518173D02*
Y524027D01*
G01X1421296Y501996D02*
X1437473Y518173D01*
G01X1438794Y545294D02*
X1439123D01*
G01X1435598Y542098D02*
X1438794Y545294D01*
G01X1435598Y534198D02*
Y542098D01*
G01X1432090Y530690D02*
X1435598Y534198D01*
G01X1430720Y530690D02*
X1432090D01*
G01X1456350Y543720D02*
X1481080D01*
G01X1455407Y542777D02*
X1456350Y543720D01*
G01X1446327Y542777D02*
X1455407D01*
G01X1443844Y545260D02*
X1446327Y542777D01*
G01X1443844Y558682D02*
Y545260D01*
G01X1441409Y561117D02*
X1443844Y558682D01*
G01X1420253Y529924D02*
X1419088D01*
G01X1421176Y530847D02*
X1420253Y529924D01*
G01X1421176Y536451D02*
Y530847D01*
G01X1439833Y555108D02*
X1421176Y536451D01*
G01X1439833Y562921D02*
Y555108D01*
G01X1442842Y565930D02*
X1439833Y562921D01*
G01X1451760Y565930D02*
X1442842D01*
G01X1453613Y567783D02*
X1451760Y565930D01*
G01X1453613Y574711D02*
Y567783D01*
G01X1442533Y585791D02*
X1453613Y574711D01*
G01X1442533Y589205D02*
Y585791D01*
G01X1433499Y527285D02*
X1432556D01*
G01X1439003Y532789D02*
X1433499Y527285D01*
G01X1439003Y536563D02*
Y532789D01*
G01X1439822Y537382D02*
X1439003Y536563D01*
G01X1457538Y541576D02*
X1482343D01*
G01X1456635Y540673D02*
X1457538Y541576D01*
G01X1456633Y540673D02*
X1456635D01*
G01X1456579Y540619D02*
X1456633Y540673D01*
G01X1445140Y540619D02*
X1456579D01*
G01X1442010Y537489D02*
X1445140Y540619D01*
G01X1442010Y533024D02*
Y537489D01*
G01X1438692Y542785D02*
X1438799D01*
G01X1437300Y541393D02*
X1438692Y542785D01*
G01X1437300Y533493D02*
Y541393D01*
G01X1432795Y528988D02*
X1437300Y533493D01*
G01X1431728Y528988D02*
X1432795D01*
G01X1457062Y542730D02*
X1481610D01*
G01X1456157Y541825D02*
X1457062Y542730D01*
G01X1445092Y541825D02*
X1456157D01*
G01X1438893Y548024D02*
X1445092Y541825D01*
G01X1437318Y548024D02*
X1438893D01*
G01X1433000Y543706D02*
X1437318Y548024D01*
G01X1433000Y542010D02*
Y543706D01*
G01X1425500Y534510D02*
X1433000Y542010D01*
G01X1425500Y532990D02*
Y534510D01*
G01X1438459Y593279D02*
X1442533Y589205D01*
G01X1438459Y612820D02*
Y593279D01*
G01X1446266Y620627D02*
X1438459Y612820D01*
G01X1464127Y620627D02*
X1446266D01*
G01X1467500Y624000D02*
X1464127Y620627D01*
G01X1520600Y-200D02*
X1529706D01*
G01X1516900Y3500D02*
X1520600Y-200D01*
G01X1507976Y-4924D02*
X1506300Y-6600D01*
G01X1566377Y-4924D02*
X1507976D01*
G01X1523900Y5100D02*
X1528229D01*
G01X1522300Y3500D02*
X1523900Y5100D01*
G01X1520100Y3500D02*
X1522300D01*
G01X1519568Y-1668D02*
X1567728D01*
G01X1514400Y3500D02*
X1519568Y-1668D01*
G01X1485776Y-1224D02*
X1482000Y-5000D01*
G01X1501424Y-1224D02*
X1485776D01*
G01X1504172Y-3972D02*
X1501424Y-1224D01*
G01X1566772Y-3972D02*
X1504172D01*
G01X1479400Y8393D02*
X1469314Y18479D01*
G01X1479400Y8055D02*
Y8393D01*
G01X1479417Y8038D02*
X1479400Y8055D01*
G01X1479417Y7740D02*
Y8038D01*
G01X1479464Y7693D02*
X1479417Y7740D01*
G01X1479464Y2236D02*
Y7693D01*
G01X1481772Y-72D02*
X1479464Y2236D01*
G01X1502272Y-72D02*
X1481772D01*
G01X1505020Y-2820D02*
X1502272Y-72D01*
G01X1567250Y-2820D02*
X1505020D01*
G01X1489394Y112315D02*
X1490178D01*
G01X1487672Y114037D02*
X1489394Y112315D01*
G01X1487672Y137028D02*
Y114037D01*
G01X1476761Y147939D02*
X1487672Y137028D01*
G01X1476761Y152725D02*
Y147939D01*
G01X1527505Y147983D02*
X1517189Y158299D01*
G01X1497563Y149528D02*
X1496150Y148115D01*
G01X1497563Y151781D02*
Y149528D01*
G01X1496691Y152653D02*
X1497563Y151781D01*
G01X1495385Y152653D02*
X1496691D01*
G01X1494462Y153576D02*
X1495385Y152653D01*
G01X1494462Y155315D02*
Y153576D01*
G01X1497563Y158416D02*
X1494462Y155315D01*
G01X1521601Y134558D02*
X1530116Y126043D01*
G01X1521601Y141537D02*
Y134558D01*
G01X1510268Y152870D02*
X1521601Y141537D01*
G01X1510268Y159201D02*
Y152870D01*
G01X1526728Y123066D02*
X1528289Y121505D01*
G01X1526728Y124168D02*
Y123066D01*
G01X1499067Y151399D02*
Y159164D01*
G01X1499605Y150861D02*
X1499067Y151399D01*
G01X1504664Y150861D02*
X1499605D01*
G01X1510357Y145168D02*
X1504664Y150861D01*
G01X1512094Y145168D02*
X1510357D01*
G01X1517330Y139932D02*
X1512094Y145168D01*
G01X1517330Y132780D02*
Y139932D01*
G01X1516850Y132300D02*
X1517330Y132780D01*
G01X1516850Y129400D02*
Y132300D01*
G01X1518650Y127600D02*
X1516850Y129400D01*
G01X1520150Y127600D02*
X1518650D01*
G01X1498315Y151087D02*
Y159476D01*
G01X1499294Y150108D02*
X1498315Y151087D01*
G01X1504353Y150108D02*
X1499294D01*
G01X1510045Y144416D02*
X1504353Y150108D01*
G01X1511781Y144416D02*
X1510045D01*
G01X1516578Y139619D02*
X1511781Y144416D01*
G01X1516578Y133828D02*
Y139619D01*
G01X1515900Y133150D02*
X1516578Y133828D01*
G01X1515900Y129150D02*
Y133150D01*
G01X1519630Y125420D02*
X1515900Y129150D01*
G01X1519630Y113784D02*
Y125420D01*
G01X1522969Y110445D02*
X1519630Y113784D01*
G01X1525788Y110445D02*
X1522969D01*
G01X1526993Y111650D02*
X1525788Y110445D01*
G01X1529122Y111650D02*
X1526993D01*
G01X1525658Y140614D02*
X1527573Y138699D01*
G01X1525657Y140614D02*
X1525658D01*
G01X1524734Y141537D02*
X1525657Y140614D01*
G01X1524734Y144003D02*
Y141537D01*
G01X1519152Y149585D02*
X1524734Y144003D01*
G01X1519152Y153622D02*
Y149585D01*
G01X1515285Y157489D02*
X1519152Y153622D01*
G01X1526600Y131469D02*
X1532621Y125448D01*
G01X1526600Y134536D02*
Y131469D01*
G01X1522753Y138383D02*
X1526600Y134536D01*
G01X1522753Y142015D02*
Y138383D01*
G01X1511420Y153348D02*
X1522753Y142015D01*
G01X1511420Y158723D02*
Y153348D01*
G01X1518093Y158459D02*
X1528257Y148295D01*
G01X1493710Y155627D02*
X1496515Y158432D01*
G01X1493710Y153475D02*
Y155627D01*
G01X1493069Y152834D02*
X1493710Y153475D01*
G01X1521740Y115317D02*
X1524284Y112773D01*
G01X1521740Y124176D02*
Y115317D01*
G01X1522552Y124988D02*
X1521740Y124176D01*
G01X1522552Y126088D02*
Y124988D01*
G01X1522553Y126089D02*
X1522552Y126088D01*
G01X1522553Y126711D02*
Y126089D01*
G01X1522552Y126712D02*
X1522553Y126711D01*
G01X1522552Y130347D02*
Y126712D01*
G01X1518834Y134065D02*
X1522552Y130347D01*
G01X1518834Y139932D02*
Y134065D01*
G01X1518835Y139933D02*
X1518834Y139932D01*
G01X1518835Y140555D02*
Y139933D01*
G01X1506576Y152814D02*
X1518835Y140555D01*
G01X1506576Y160807D02*
Y152814D01*
G01X1505824Y152502D02*
Y161119D01*
G01X1518082Y140244D02*
X1505824Y152502D01*
G01X1518082Y133753D02*
Y140244D01*
G01X1521800Y130035D02*
X1518082Y133753D01*
G01X1521800Y125300D02*
Y130035D01*
G01X1520600Y124100D02*
X1521800Y125300D01*
G01X1520600Y114228D02*
Y124100D01*
G01X1523631Y111197D02*
X1520600Y114228D01*
G01X1525476Y111197D02*
X1523631D01*
G01X1526681Y112402D02*
X1525476Y111197D01*
G01X1529434Y112402D02*
X1526681D01*
G01X1518845Y158771D02*
X1529009Y148607D01*
G01X1520304Y154100D02*
X1516437Y157967D01*
G01X1520304Y150674D02*
Y154100D01*
G01X1533517Y137461D02*
X1520304Y150674D01*
G01X1520370Y134159D02*
X1528844Y125685D01*
G01X1520370Y140959D02*
Y134159D01*
G01X1508242Y152920D02*
X1520370Y140959D01*
G01X1507728Y153434D02*
X1508242Y152920D01*
G01X1507728Y159921D02*
Y153434D01*
G01X1509100Y211914D02*
Y219909D01*
G01X1508547Y211361D02*
X1509100Y211914D01*
G01X1508547Y204088D02*
Y211361D01*
G01X1508595Y204040D02*
X1508547Y204088D01*
G01X1508595Y199762D02*
Y204040D01*
G01X1508593Y199760D02*
X1508595Y199762D01*
G01X1508593Y199180D02*
Y199760D01*
G01X1510800Y196973D02*
X1508593Y199180D01*
G01X1510800Y193330D02*
Y196973D01*
G01X1520099Y214698D02*
Y221612D01*
G01X1522589Y212208D02*
X1520099Y214698D01*
G01X1522589Y176556D02*
Y212208D01*
G01X1522588Y176555D02*
X1522589Y176556D01*
G01X1522588Y175933D02*
Y176555D01*
G01X1522587Y175932D02*
X1522588Y175933D01*
G01X1522587Y168720D02*
Y175932D01*
G01X1522589Y168718D02*
X1522587Y168720D01*
G01X1522589Y167607D02*
Y168718D01*
G01X1525689Y164507D02*
X1522589Y167607D01*
G01X1526311Y164507D02*
X1525689D01*
G01X1526312Y164506D02*
X1526311Y164507D01*
G01X1526934Y164506D02*
X1526312D01*
G01X1526936Y164508D02*
X1526934Y164506D01*
G01X1531242Y164508D02*
X1526936D01*
G01X1510370Y212120D02*
Y219811D01*
G01X1509575Y211325D02*
X1510370Y212120D01*
G01X1509575Y199262D02*
Y211325D01*
G01X1512438Y196399D02*
X1509575Y199262D01*
G01X1512438Y192739D02*
Y196399D01*
G01X1512348Y192649D02*
X1512438Y192739D01*
G01X1512348Y192607D02*
Y192649D01*
G01X1508772Y189031D02*
X1512348Y192607D01*
G01X1508772Y184789D02*
Y189031D01*
G01X1517189Y176372D02*
X1508772Y184789D01*
G01X1517189Y158299D02*
Y176372D01*
G01X1497237Y219392D02*
Y217281D01*
G01X1497563Y159788D02*
Y158416D01*
G01X1499684Y161909D02*
X1497563Y159788D01*
G01X1499684Y162816D02*
Y161909D01*
G01X1499112Y163388D02*
X1499684Y162816D01*
G01X1499112Y177318D02*
Y163388D01*
G01X1490500Y185930D02*
X1499112Y177318D01*
G01X1490500Y214024D02*
Y185930D01*
G01X1492794Y216318D02*
X1490500Y214024D01*
G01X1492794Y219223D02*
Y216318D01*
G01X1513181Y162114D02*
X1510268Y159201D01*
G01X1513181Y174709D02*
Y162114D01*
G01X1504585Y183305D02*
X1513181Y174709D01*
G01X1504585Y201423D02*
Y183305D01*
G01X1504586Y201424D02*
X1504585Y201423D01*
G01X1504586Y202378D02*
Y201424D01*
G01X1503840Y203124D02*
X1504586Y202378D01*
G01X1503840Y221687D02*
Y203124D01*
G01X1526312Y166012D02*
X1536309D01*
G01X1524093Y168231D02*
X1526312Y166012D01*
G01X1524093Y212832D02*
Y168231D01*
G01X1521603Y215322D02*
X1524093Y212832D01*
G01X1521603Y220988D02*
Y215322D01*
G01X1494585Y183973D02*
Y219916D01*
G01X1500616Y177942D02*
X1494585Y183973D01*
G01X1500616Y164218D02*
Y177942D01*
G01X1501189Y163645D02*
X1500616Y164218D01*
G01X1501189Y161286D02*
Y163645D01*
G01X1499067Y159164D02*
X1501189Y161286D01*
G01X1493833Y183661D02*
Y219604D01*
G01X1499864Y177630D02*
X1493833Y183661D01*
G01X1499864Y163700D02*
Y177630D01*
G01X1500436Y163128D02*
X1499864Y163700D01*
G01X1500436Y161597D02*
Y163128D01*
G01X1498315Y159476D02*
X1500436Y161597D01*
G01X1515285Y175582D02*
Y157489D01*
G01X1506689Y184178D02*
X1515285Y175582D01*
G01X1506689Y200550D02*
Y184178D01*
G01X1506691Y200552D02*
X1506689Y200550D01*
G01X1506691Y203250D02*
Y200552D01*
G01X1505944Y203997D02*
X1506691Y203250D01*
G01X1505944Y219572D02*
Y203997D01*
G01X1520851Y215010D02*
Y221300D01*
G01X1523341Y212520D02*
X1520851Y215010D01*
G01X1523341Y176244D02*
Y212520D01*
G01X1523340Y176243D02*
X1523341Y176244D01*
G01X1523340Y169031D02*
Y176243D01*
G01X1523341Y169030D02*
X1523340Y169031D01*
G01X1523341Y167919D02*
Y169030D01*
G01X1526001Y165259D02*
X1523341Y167919D01*
G01X1526623Y165259D02*
X1526001D01*
G01X1526624Y165260D02*
X1526623Y165259D01*
G01X1531554Y165260D02*
X1526624D01*
G01X1514333Y161636D02*
X1511420Y158723D01*
G01X1514333Y175187D02*
Y161636D01*
G01X1505737Y183783D02*
X1514333Y175187D01*
G01X1505737Y200945D02*
Y183783D01*
G01X1505739Y200947D02*
X1505737Y200945D01*
G01X1505739Y202855D02*
Y200947D01*
G01X1504992Y203602D02*
X1505739Y202855D01*
G01X1504992Y221199D02*
Y203602D01*
G01X1526955Y172344D02*
Y223255D01*
G01X1528682Y170617D02*
X1526955Y172344D01*
G01X1524976Y171556D02*
X1527222Y169310D01*
G01X1524976Y223297D02*
Y171556D01*
G01X1518093Y176406D02*
Y158459D01*
G01X1517941Y176558D02*
X1518093Y176406D01*
G01X1517941Y176684D02*
Y176558D01*
G01X1509524Y185101D02*
X1517941Y176684D01*
G01X1509524Y188719D02*
Y185101D01*
G01X1513403Y192598D02*
X1509524Y188719D01*
G01X1513403Y196498D02*
Y192598D01*
G01X1510800Y199101D02*
X1513403Y196498D01*
G01X1510800Y211182D02*
Y199101D01*
G01X1511759Y212141D02*
X1510800Y211182D01*
G01X1511759Y217159D02*
Y212141D01*
G01X1512600Y218000D02*
X1511759Y217159D01*
G01X1489292Y186074D02*
Y219937D01*
G01X1498360Y177006D02*
X1489292Y186074D01*
G01X1498360Y166460D02*
Y177006D01*
G01X1495734Y163834D02*
X1498360Y166460D01*
G01X1495734Y161152D02*
Y163834D01*
G01X1496515Y160371D02*
X1495734Y161152D01*
G01X1496515Y158432D02*
Y160371D01*
G01X1500703Y158453D02*
Y158233D01*
G01X1506282Y164032D02*
X1500703Y158453D01*
G01X1506282Y165524D02*
Y164032D01*
G01X1505072Y166734D02*
X1506282Y165524D01*
G01X1505072Y175614D02*
Y166734D01*
G01X1496651Y184035D02*
X1505072Y175614D01*
G01X1496651Y214328D02*
Y184035D01*
G01X1498823Y216500D02*
X1496651Y214328D01*
G01X1498823Y218870D02*
Y216500D01*
G01X1504706Y165314D02*
Y164871D01*
G01X1503290Y166730D02*
X1504706Y165314D01*
G01X1503290Y176332D02*
Y166730D01*
G01X1495337Y184285D02*
X1503290Y176332D01*
G01X1495337Y220228D02*
Y184285D01*
G01X1510638Y175622D02*
Y166240D01*
G01X1503433Y182827D02*
X1510638Y175622D01*
G01X1503433Y201901D02*
Y182827D01*
G01X1502688Y202646D02*
X1503433Y201901D01*
G01X1502688Y222165D02*
Y202646D01*
G01X1507786Y162017D02*
X1506576Y160807D01*
G01X1507786Y166148D02*
Y162017D01*
G01X1507299Y166635D02*
X1507786Y166148D01*
G01X1507299Y175515D02*
Y166635D01*
G01X1498224Y184590D02*
X1507299Y175515D01*
G01X1498224Y200212D02*
Y184590D01*
G01X1500384Y202372D02*
X1498224Y200212D01*
G01X1500384Y223121D02*
Y202372D01*
G01X1515722Y216082D02*
Y220115D01*
G01X1515370Y215730D02*
X1515722Y216082D01*
G01X1513152Y215730D02*
X1515370D01*
G01X1512800Y215378D02*
X1513152Y215730D01*
G01X1512800Y214674D02*
Y215378D01*
G01X1513152Y214322D02*
X1512800Y214674D01*
G01X1515370Y214322D02*
X1513152D01*
G01X1515722Y213970D02*
X1515370Y214322D01*
G01X1515722Y213266D02*
Y213970D01*
G01X1515370Y212914D02*
X1515722Y213266D01*
G01X1513152Y212914D02*
X1515370D01*
G01X1512800Y212562D02*
X1513152Y212914D01*
G01X1512800Y211858D02*
Y212562D01*
G01X1513152Y211506D02*
X1512800Y211858D01*
G01X1515370Y211506D02*
X1513152D01*
G01X1515722Y211154D02*
X1515370Y211506D01*
G01X1515722Y210013D02*
Y211154D01*
G01X1516872Y208863D02*
X1515722Y210013D01*
G01X1499598Y216722D02*
Y223399D01*
G01X1499597Y216721D02*
X1499598Y216722D01*
G01X1499597Y202730D02*
Y216721D01*
G01X1497472Y200605D02*
X1499597Y202730D01*
G01X1497472Y184902D02*
Y200605D01*
G01X1497471Y184901D02*
X1497472Y184902D01*
G01X1497471Y184279D02*
Y184901D01*
G01X1506500Y175250D02*
X1497471Y184279D01*
G01X1506500Y166370D02*
Y175250D01*
G01X1507034Y165836D02*
X1506500Y166370D01*
G01X1507034Y162329D02*
Y165836D01*
G01X1505824Y161119D02*
X1507034Y162329D01*
G01X1518845Y178530D02*
Y158771D01*
G01X1511100Y186275D02*
X1518845Y178530D01*
G01X1507096Y204475D02*
Y218172D01*
G01X1507843Y203728D02*
X1507096Y204475D01*
G01X1507843Y200074D02*
Y203728D01*
G01X1507841Y200072D02*
X1507843Y200074D01*
G01X1507841Y184656D02*
Y200072D01*
G01X1516437Y176060D02*
X1507841Y184656D01*
G01X1516437Y157967D02*
Y176060D01*
G01X1508938Y161131D02*
X1507728Y159921D01*
G01X1508938Y166626D02*
Y161131D01*
G01X1508500Y167064D02*
X1508938Y166626D01*
G01X1508500Y175944D02*
Y167064D01*
G01X1502202Y182242D02*
X1508500Y175944D01*
G01X1502202Y200909D02*
Y182242D01*
G01X1501536Y201575D02*
X1502202Y200909D01*
G01X1501536Y222643D02*
Y201575D01*
G01X1485100Y211399D02*
X1478118Y218381D01*
G01X1485100Y167985D02*
Y211399D01*
G01X1493585Y159500D02*
X1485100Y167985D01*
G01X1494939Y159500D02*
X1493585D01*
G01X1472199Y278352D02*
X1473798Y276753D01*
G01X1470120Y278352D02*
X1472199D01*
G01X1468752Y279720D02*
X1470120Y278352D01*
G01X1498105Y279257D02*
Y280563D01*
G01X1498199Y279163D02*
X1498105Y279257D01*
G01X1498199Y279099D02*
Y279163D01*
G01X1502444Y274854D02*
X1498199Y279099D01*
G01X1502444Y274055D02*
Y274854D01*
G01X1510696Y265803D02*
X1502444Y274055D01*
G01X1510696Y251390D02*
Y265803D01*
G01X1507322Y248016D02*
X1510696Y251390D01*
G01X1507322Y243500D02*
Y248016D01*
G01X1507955Y242867D02*
X1507322Y243500D01*
G01X1507955Y221054D02*
Y242867D01*
G01X1509100Y219909D02*
X1507955Y221054D01*
G01X1518872Y277487D02*
Y285343D01*
G01X1522155Y274204D02*
X1518872Y277487D01*
G01X1522155Y256053D02*
Y274204D01*
G01X1525380Y252828D02*
X1522155Y256053D01*
G01X1527361Y252828D02*
X1525380D01*
G01X1525403Y230413D02*
X1528400Y233410D01*
G01X1525403Y226916D02*
Y230413D01*
G01X1520099Y221612D02*
X1525403Y226916D01*
G01X1511448Y270099D02*
X1501500Y280047D01*
G01X1511448Y251078D02*
Y270099D01*
G01X1508074Y247704D02*
X1511448Y251078D01*
G01X1508074Y244000D02*
Y247704D01*
G01X1508707Y243367D02*
X1508074Y244000D01*
G01X1508707Y221474D02*
Y243367D01*
G01X1510370Y219811D02*
X1508707Y221474D01*
G01X1472291Y268812D02*
X1470649Y270454D01*
G01X1487628Y268812D02*
X1472291D01*
G01X1493144Y263296D02*
X1487628Y268812D01*
G01X1495827Y263296D02*
X1493144D01*
G01X1495828Y263295D02*
X1495827Y263296D01*
G01X1496782Y263295D02*
X1495828D01*
G01X1496783Y263294D02*
X1496782Y263295D01*
G01X1497571Y263294D02*
X1496783D01*
G01X1497573Y263296D02*
X1497571Y263294D01*
G01X1498374Y263296D02*
X1497573D01*
G01X1502165Y259505D02*
X1498374Y263296D01*
G01X1502165Y251200D02*
Y259505D01*
G01X1495694Y220935D02*
X1497237Y219392D01*
G01X1495694Y223076D02*
Y220935D01*
G01X1494646Y224124D02*
X1495694Y223076D01*
G01X1494646Y247614D02*
Y224124D01*
G01X1488039Y254221D02*
X1494646Y247614D01*
G01X1488039Y257137D02*
Y254221D01*
G01X1482367Y262809D02*
X1488039Y257137D01*
G01X1491438Y220579D02*
X1492794Y219223D01*
G01X1491438Y221137D02*
Y220579D01*
G01X1504469Y222316D02*
X1503840Y221687D01*
G01X1504469Y235531D02*
Y222316D01*
G01X1502152Y237848D02*
X1504469Y235531D01*
G01X1502152Y247170D02*
Y237848D01*
G01X1507640Y252658D02*
X1502152Y247170D01*
G01X1507640Y260663D02*
Y252658D01*
G01X1496681Y271622D02*
X1507640Y260663D01*
G01X1496678Y271622D02*
X1496681D01*
G01X1494823Y273477D02*
X1496678Y271622D01*
G01X1494823Y275024D02*
Y273477D01*
G01X1491415Y278432D02*
X1494823Y275024D01*
G01X1488585Y278432D02*
X1491415D01*
G01X1487935Y279082D02*
X1488585Y278432D01*
G01X1487935Y289242D02*
Y279082D01*
G01X1527386Y226771D02*
X1521603Y220988D01*
G01X1526004Y254332D02*
X1527985D01*
G01X1523660Y256676D02*
X1526004Y254332D01*
G01X1523660Y277811D02*
Y256676D01*
G01X1523876Y278027D02*
X1523660Y277811D01*
G01X1523876Y280141D02*
Y278027D01*
G01X1469911Y260380D02*
X1468260Y258729D01*
G01X1478597Y260380D02*
X1469911D01*
G01X1484478Y254499D02*
X1478597Y260380D01*
G01X1484500Y254446D02*
X1484478Y254499D01*
G01X1490124Y248822D02*
X1484500Y254446D01*
G01X1490124Y241008D02*
Y248822D01*
G01X1492841Y238291D02*
X1490124Y241008D01*
G01X1492841Y223801D02*
Y238291D01*
G01X1494190Y222452D02*
X1492841Y223801D01*
G01X1494190Y221559D02*
Y222452D01*
G01X1494189Y221558D02*
X1494190Y221559D01*
G01X1494189Y220312D02*
Y221558D01*
G01X1494585Y219916D02*
X1494189Y220312D01*
G01X1478451Y275250D02*
X1480098Y273603D01*
G01X1470073Y275250D02*
X1478451D01*
G01X1468000Y277323D02*
X1470073Y275250D01*
G01X1468000Y287781D02*
Y277323D01*
G01X1526916Y276461D02*
X1527657Y277202D01*
G01X1526916Y262713D02*
Y276461D01*
G01X1537093Y252536D02*
X1526916Y262713D01*
G01X1471055Y259628D02*
X1469327Y257900D01*
G01X1478285Y259628D02*
X1471055D01*
G01X1483105Y254808D02*
X1478285Y259628D01*
G01X1483105Y251154D02*
Y254808D01*
G01X1483979Y250280D02*
X1483105Y251154D01*
G01X1484006Y250280D02*
X1483979D01*
G01X1484794Y249492D02*
X1484006Y250280D01*
G01X1488390Y249492D02*
X1484794D01*
G01X1489372Y248510D02*
X1488390Y249492D01*
G01X1489372Y225629D02*
Y248510D01*
G01X1493127Y221874D02*
X1489372Y225629D01*
G01X1493127Y220310D02*
Y221874D01*
G01X1493833Y219604D02*
X1493127Y220310D01*
G01X1507003Y220631D02*
X1505944Y219572D01*
G01X1507003Y241867D02*
Y220631D01*
G01X1506370Y242500D02*
X1507003Y241867D01*
G01X1506370Y248411D02*
Y242500D01*
G01X1509744Y251785D02*
X1506370Y248411D01*
G01X1509744Y261536D02*
Y251785D01*
G01X1501352Y269928D02*
X1509744Y261536D01*
G01X1501352Y274056D02*
Y269928D01*
G01X1499028Y276380D02*
X1501352Y274056D01*
G01X1497618Y276380D02*
X1499028D01*
G01X1497591Y276407D02*
X1497618Y276380D01*
G01X1496373Y276407D02*
X1497591D01*
G01X1494323Y278457D02*
X1496373Y276407D01*
G01X1494323Y278632D02*
Y278457D01*
G01X1492130Y280825D02*
X1494323Y278632D01*
G01X1519624Y277863D02*
Y284459D01*
G01X1522907Y274580D02*
X1519624Y277863D01*
G01X1522907Y256365D02*
Y274580D01*
G01X1525692Y253580D02*
X1522907Y256365D01*
G01X1527673Y253580D02*
X1525692D01*
G01X1526271Y229859D02*
X1529152Y232740D01*
G01X1526271Y226720D02*
Y229859D01*
G01X1520851Y221300D02*
X1526271Y226720D01*
G01X1504072Y259229D02*
X1504772D01*
G01X1499053Y264248D02*
X1504072Y259229D01*
G01X1493539Y264248D02*
X1499053D01*
G01X1492539Y265248D02*
X1493539Y264248D01*
G01X1492350Y265248D02*
X1492539D01*
G01X1487888Y269710D02*
X1492350Y265248D01*
G01X1487888Y271338D02*
Y269710D01*
G01X1487175Y272051D02*
X1487888Y271338D01*
G01X1478500Y272051D02*
X1487175D01*
G01X1476948Y273603D02*
X1478500Y272051D01*
G01X1506051Y222258D02*
X1504992Y221199D01*
G01X1506051Y241367D02*
Y222258D01*
G01X1505418Y242000D02*
X1506051Y241367D01*
G01X1505418Y248806D02*
Y242000D01*
G01X1508792Y252180D02*
X1505418Y248806D01*
G01X1508792Y261141D02*
Y252180D01*
G01X1500400Y269533D02*
X1508792Y261141D01*
G01X1500400Y273319D02*
Y269533D01*
G01X1498425Y275294D02*
X1500400Y273319D01*
G01X1497319Y275294D02*
X1498425D01*
G01X1497312Y275301D02*
X1497319Y275294D01*
G01X1496178Y275301D02*
X1497312D01*
G01X1491311Y280168D02*
X1496178Y275301D01*
G01X1510600Y279345D02*
Y283971D01*
G01X1518356Y271589D02*
X1510600Y279345D01*
G01X1518356Y253514D02*
Y271589D01*
G01X1523170Y248700D02*
X1518356Y253514D01*
G01X1525650Y248700D02*
X1523170D01*
G01X1525880Y277196D02*
Y281604D01*
G01X1525664Y276980D02*
X1525880Y277196D01*
G01X1525664Y257836D02*
Y276980D01*
G01X1527164Y256336D02*
X1525664Y257836D01*
G01X1526955Y223255D02*
X1531909Y228209D01*
G01X1528254Y226575D02*
X1524976Y223297D01*
G01X1526316Y255084D02*
X1528297D01*
G01X1524412Y256988D02*
X1526316Y255084D01*
G01X1524412Y277499D02*
Y256988D01*
G01X1524628Y277715D02*
X1524412Y277499D01*
G01X1524628Y281085D02*
Y277715D01*
G01X1505793Y279262D02*
Y288847D01*
G01X1514355Y270700D02*
X1505793Y279262D01*
G01X1514355Y252625D02*
Y270700D01*
G01X1516433Y250547D02*
X1514355Y252625D01*
G01X1516433Y240836D02*
Y250547D01*
G01X1516613Y240656D02*
X1516433Y240836D01*
G01X1512696Y247572D02*
X1509800Y244676D01*
G01X1512696Y270595D02*
Y247572D01*
G01X1502652Y280639D02*
X1512696Y270595D01*
G01X1513900Y218000D02*
X1512600D01*
G01X1510739Y240099D02*
X1512790D01*
G01X1509459Y238819D02*
X1510739Y240099D01*
G01X1509459Y222170D02*
Y238819D01*
G01X1510878Y220751D02*
X1509459Y222170D01*
G01X1511989Y220751D02*
X1510878D01*
G01X1513900Y218840D02*
X1511989Y220751D01*
G01X1513900Y218000D02*
Y218840D01*
G01X1481881Y247481D02*
X1482400Y248000D01*
G01X1481881Y243915D02*
Y247481D01*
G01X1487425Y238371D02*
X1481881Y243915D01*
G01X1487425Y221804D02*
Y238371D01*
G01X1489292Y219937D02*
X1487425Y221804D01*
G01X1496446Y221247D02*
X1498823Y218870D01*
G01X1496446Y223388D02*
Y221247D01*
G01X1495398Y224436D02*
X1496446Y223388D01*
G01X1495398Y248682D02*
Y224436D01*
G01X1488791Y255289D02*
X1495398Y248682D01*
G01X1488791Y257488D02*
Y255289D01*
G01X1482640Y263639D02*
X1488791Y257488D01*
G01X1494941Y220624D02*
X1495337Y220228D01*
G01X1494941Y221246D02*
Y220624D01*
G01X1494942Y221247D02*
X1494941Y221246D01*
G01X1494942Y222764D02*
Y221247D01*
G01X1493894Y223812D02*
X1494942Y222764D01*
G01X1493894Y247302D02*
Y223812D01*
G01X1487287Y253909D02*
X1493894Y247302D01*
G01X1487287Y256789D02*
Y253909D01*
G01X1482143Y261933D02*
X1487287Y256789D01*
G01X1481600Y279470D02*
Y290700D01*
G01X1482638Y278432D02*
X1481600Y279470D01*
G01X1484910Y278432D02*
X1482638D01*
G01X1495677Y267665D02*
X1484910Y278432D01*
G01X1496030Y267665D02*
X1495677D01*
G01X1503317Y222794D02*
X1502688Y222165D01*
G01X1503317Y234183D02*
Y222794D01*
G01X1501000Y236500D02*
X1503317Y234183D01*
G01X1501000Y247700D02*
Y236500D01*
G01X1504300Y251000D02*
X1501000Y247700D01*
G01X1504300Y256400D02*
Y251000D01*
G01X1506488Y258588D02*
X1504300Y256400D01*
G01X1506488Y259860D02*
Y258588D01*
G01X1500948Y265400D02*
X1506488Y259860D01*
G01X1496216Y265400D02*
X1500948D01*
G01X1494616Y267000D02*
X1496216Y265400D01*
G01X1494600Y267000D02*
X1494616D01*
G01X1494267Y267333D02*
X1494600Y267000D01*
G01X1494267Y267954D02*
Y267333D01*
G01X1486938Y275283D02*
X1494267Y267954D01*
G01X1481917Y275283D02*
X1486938D01*
G01X1481568Y275632D02*
X1481917Y275283D01*
G01X1481568Y277362D02*
Y275632D01*
G01X1481200Y277730D02*
X1481568Y277362D01*
G01X1481200Y278000D02*
Y277730D01*
G01X1479900Y279300D02*
X1481200Y278000D01*
G01X1479300Y279300D02*
X1479900D01*
G01X1478628Y279972D02*
X1479300Y279300D01*
G01X1520413Y243241D02*
Y239498D01*
G01X1520876Y243704D02*
X1520413Y243241D01*
G01X1520876Y245849D02*
Y243704D01*
G01X1519148Y247577D02*
X1520876Y245849D01*
G01X1519148Y251092D02*
Y247577D01*
G01X1517204Y253036D02*
X1519148Y251092D01*
G01X1517204Y271111D02*
Y253036D01*
G01X1509448Y278867D02*
X1517204Y271111D01*
G01X1509448Y284449D02*
Y278867D01*
G01X1501013Y223750D02*
X1500384Y223121D01*
G01X1501013Y225680D02*
Y223750D01*
G01X1496902Y229791D02*
X1501013Y225680D01*
G01X1496902Y250566D02*
Y229791D01*
G01X1500863Y254527D02*
X1496902Y250566D01*
G01X1500863Y257637D02*
Y254527D01*
G01X1496357Y262143D02*
X1500863Y257637D01*
G01X1496306Y262143D02*
X1496357D01*
G01X1496305Y262142D02*
X1496306Y262143D01*
G01X1495351Y262142D02*
X1496305D01*
G01X1495349Y262144D02*
X1495351Y262142D01*
G01X1489032Y262144D02*
X1495349D01*
G01X1485584Y265592D02*
X1489032Y262144D01*
G01X1473225Y265592D02*
X1485584D01*
G01X1470438Y268379D02*
X1473225Y265592D01*
G01X1467904Y268379D02*
X1470438D01*
G01X1466029Y270254D02*
X1467904Y268379D01*
G01X1466029Y275075D02*
Y270254D01*
G01X1516052Y270633D02*
X1506945Y279740D01*
G01X1516052Y252558D02*
Y270633D01*
G01X1517685Y250925D02*
X1516052Y252558D01*
G01X1517685Y241813D02*
Y250925D01*
G01X1518189Y241309D02*
X1517685Y241813D01*
G01X1518189Y240003D02*
Y241309D01*
G01X1516036Y237850D02*
X1518189Y240003D01*
G01X1511650Y237850D02*
X1516036D01*
G01X1510442Y236642D02*
X1511650Y237850D01*
G01X1510442Y222515D02*
Y236642D01*
G01X1510957Y222000D02*
X1510442Y222515D01*
G01X1511687Y222000D02*
X1510957D01*
G01X1512202Y222515D02*
X1511687Y222000D01*
G01X1512202Y235885D02*
Y222515D01*
G01X1512717Y236400D02*
X1512202Y235885D01*
G01X1513447Y236400D02*
X1512717D01*
G01X1513962Y235885D02*
X1513447Y236400D01*
G01X1513962Y232836D02*
Y235885D01*
G01X1514314Y232484D02*
X1513962Y232836D01*
G01X1518987Y232484D02*
X1514314D01*
G01X1519339Y232836D02*
X1518987Y232484D01*
G01X1519339Y236948D02*
Y232836D01*
G01X1519691Y237300D02*
X1519339Y236948D01*
G01X1520395Y237300D02*
X1519691D01*
G01X1520747Y236948D02*
X1520395Y237300D01*
G01X1520747Y232836D02*
Y236948D01*
G01X1521099Y232484D02*
X1520747Y232836D01*
G01X1521848Y232484D02*
X1521099D01*
G01X1522200Y232132D02*
X1521848Y232484D01*
G01X1522200Y231428D02*
Y232132D01*
G01X1521848Y231076D02*
X1522200Y231428D01*
G01X1514314Y231076D02*
X1521848D01*
G01X1513962Y230724D02*
X1514314Y231076D01*
G01X1513962Y230020D02*
Y230724D01*
G01X1514314Y229668D02*
X1513962Y230020D01*
G01X1521848Y229668D02*
X1514314D01*
G01X1522200Y229316D02*
X1521848Y229668D01*
G01X1522200Y228612D02*
Y229316D01*
G01X1521848Y228260D02*
X1522200Y228612D01*
G01X1514314Y228260D02*
X1521848D01*
G01X1513962Y227908D02*
X1514314Y228260D01*
G01X1513962Y227204D02*
Y227908D01*
G01X1514314Y226852D02*
X1513962Y227204D01*
G01X1518848Y226852D02*
X1514314D01*
G01X1519200Y226500D02*
X1518848Y226852D01*
G01X1519200Y225796D02*
Y226500D01*
G01X1518848Y225444D02*
X1519200Y225796D01*
G01X1514314Y225444D02*
X1518848D01*
G01X1513962Y225092D02*
X1514314Y225444D01*
G01X1513962Y221875D02*
Y225092D01*
G01X1515722Y220115D02*
X1513962Y221875D01*
G01X1513906Y277893D02*
Y285647D01*
G01X1519603Y272196D02*
X1513906Y277893D01*
G01X1519603Y253897D02*
Y272196D01*
G01X1523224Y250276D02*
X1519603Y253897D01*
G01X1526303Y250276D02*
X1523224D01*
G01X1527226Y249353D02*
X1526303Y250276D01*
G01X1525311Y245910D02*
X1527226Y247825D01*
G01X1525311Y240273D02*
Y245910D01*
G01X1523580Y238542D02*
X1525311Y240273D01*
G01X1523580Y237960D02*
Y238542D01*
G01X1485375Y264737D02*
X1469312D01*
G01X1489565Y260547D02*
X1485375Y264737D01*
G01X1489565Y255848D02*
Y260547D01*
G01X1496150Y249263D02*
X1489565Y255848D01*
G01X1496150Y229479D02*
Y249263D01*
G01X1500261Y225368D02*
X1496150Y229479D01*
G01X1500261Y224062D02*
Y225368D01*
G01X1499598Y223399D02*
X1500261Y224062D01*
G01X1479759Y224801D02*
X1479700D01*
G01X1479759Y229401D02*
Y224801D01*
G01X1507096Y218172D02*
X1507524Y218600D01*
G01X1502165Y223272D02*
X1501536Y222643D01*
G01X1502165Y226158D02*
Y223272D01*
G01X1502148Y226175D02*
X1502165Y226158D01*
G01X1502148Y233352D02*
Y226175D01*
G01X1499500Y236000D02*
X1502148Y233352D01*
G01X1499500Y250342D02*
Y236000D01*
G01X1499472Y250370D02*
X1499500Y250342D01*
G01X1478118Y218381D02*
Y229335D01*
G01X1468752Y288093D02*
Y279720D01*
G01X1468751Y288094D02*
X1468752Y288093D01*
G01X1468751Y288938D02*
Y288094D01*
G01X1465400Y320886D02*
Y318745D01*
G01X1467868Y323354D02*
X1465400Y320886D01*
G01X1469052Y323354D02*
X1467868D01*
G01X1469097Y323399D02*
X1469052Y323354D01*
G01X1469498Y323399D02*
X1469097D01*
G01X1469604Y323505D02*
X1469498Y323399D01*
G01X1471956Y323505D02*
X1469604D01*
G01X1478479Y330028D02*
X1471956Y323505D01*
G01X1478479Y345997D02*
Y330028D01*
G01X1484927Y312866D02*
X1483247Y314546D01*
G01X1484927Y310788D02*
Y312866D01*
G01X1485788Y309927D02*
X1484927Y310788D01*
G01X1487006Y309927D02*
X1485788D01*
G01X1487867Y310788D02*
X1487006Y309927D01*
G01X1487867Y311797D02*
Y310788D01*
G01X1488937Y312867D02*
X1487867Y311797D01*
G01X1496213Y312867D02*
X1488937D01*
G01X1497944Y311136D02*
X1496213Y312867D01*
G01X1497944Y308441D02*
Y311136D01*
G01X1499557Y306828D02*
X1497944Y308441D01*
G01X1499557Y302667D02*
Y306828D01*
G01X1504330Y297894D02*
X1499557Y302667D01*
G01X1504330Y291790D02*
Y297894D01*
G01X1502593Y290053D02*
X1504330Y291790D01*
G01X1502593Y286672D02*
Y290053D01*
G01X1500605Y284684D02*
X1502593Y286672D01*
G01X1500605Y283063D02*
Y284684D01*
G01X1498105Y280563D02*
X1500605Y283063D01*
G01X1470903Y320204D02*
X1469740D01*
G01X1471826Y321127D02*
X1470903Y320204D01*
G01X1471826Y321778D02*
Y321127D01*
G01X1479231Y329183D02*
X1471826Y321778D01*
G01X1479231Y346309D02*
Y329183D01*
G01X1510851Y339835D02*
Y340113D01*
G01X1519200Y331486D02*
X1510851Y339835D01*
G01X1519200Y319690D02*
Y331486D01*
G01X1518740Y319230D02*
X1519200Y319690D01*
G01X1517509Y319230D02*
X1518740D01*
G01X1516090Y317811D02*
X1517509Y319230D01*
G01X1516090Y316189D02*
Y317811D01*
G01X1519200Y313079D02*
X1516090Y316189D01*
G01X1519200Y305271D02*
Y313079D01*
G01X1519876Y304595D02*
X1519200Y305271D01*
G01X1519876Y286423D02*
Y304595D01*
G01X1519582Y286129D02*
X1519876Y286423D01*
G01X1519582Y286053D02*
Y286129D01*
G01X1518872Y285343D02*
X1519582Y286053D01*
G01X1526936Y300311D02*
X1529228Y298019D01*
G01X1526936Y307015D02*
Y300311D01*
G01X1526984Y337323D02*
X1531250Y333057D01*
G01X1526746Y337323D02*
X1526984D01*
G01X1526745Y337324D02*
X1526746Y337323D01*
G01X1526123Y337324D02*
X1526745D01*
G01X1526122Y337323D02*
X1526123Y337324D01*
G01X1524790Y337323D02*
X1526122D01*
G01X1522589Y339524D02*
X1524790Y337323D01*
G01X1522589Y341880D02*
Y339524D01*
G01X1474298Y301948D02*
X1473798D01*
G01X1475350Y303000D02*
X1474298Y301948D01*
G01X1475350Y312000D02*
Y303000D01*
G01X1479450Y316100D02*
X1475350Y312000D01*
G01X1483800Y316100D02*
X1479450D01*
G01X1484927Y314973D02*
X1483800Y316100D01*
G01X1484927Y313937D02*
Y314973D01*
G01X1485788Y313076D02*
X1484927Y313937D01*
G01X1487376Y313076D02*
X1485788D01*
G01X1488050Y313750D02*
X1487376Y313076D01*
G01X1488050Y326974D02*
Y313750D01*
G01X1490290Y329214D02*
X1488050Y326974D01*
G01X1490290Y341710D02*
Y329214D01*
G01X1495310Y341200D02*
X1495810D01*
G01X1493800Y339690D02*
X1495310Y341200D01*
G01X1493800Y334400D02*
Y339690D01*
G01X1495509Y332691D02*
X1493800Y334400D01*
G01X1495509Y317545D02*
Y332691D01*
G01X1499717Y313337D02*
X1495509Y317545D01*
G01X1499717Y308971D02*
Y313337D01*
G01X1501004Y307684D02*
X1499717Y308971D01*
G01X1501004Y302284D02*
Y307684D01*
G01X1505082Y298206D02*
X1501004Y302284D01*
G01X1505082Y291478D02*
Y298206D01*
G01X1503371Y289767D02*
X1505082Y291478D01*
G01X1503371Y286300D02*
Y289767D01*
G01X1501500Y284429D02*
X1503371Y286300D01*
G01X1501500Y281117D02*
Y284429D01*
G01X1501499Y281116D02*
X1501500Y281117D01*
G01X1501499Y280162D02*
Y281116D01*
G01X1501500Y280161D02*
X1501499Y280162D01*
G01X1501500Y280047D02*
Y280161D01*
G01X1523935Y315611D02*
Y318901D01*
G01X1522846Y314522D02*
X1523935Y315611D01*
G01X1522846Y308357D02*
Y314522D01*
G01X1525929Y305274D02*
X1522846Y308357D01*
G01X1525929Y300254D02*
Y305274D01*
G01X1528476Y297707D02*
X1525929Y300254D01*
G01X1526340Y288864D02*
X1528476Y291000D01*
G01X1526340Y284562D02*
Y288864D01*
G01X1529233Y281669D02*
X1526340Y284562D01*
G01X1469649Y334800D02*
X1472500D01*
G01X1470929Y329198D02*
X1466777D01*
G01X1475908Y334177D02*
X1470929Y329198D01*
G01X1475908Y345196D02*
Y334177D01*
G01X1491780Y293087D02*
X1487935Y289242D01*
G01X1492412Y293087D02*
X1491780D01*
G01X1493268Y293943D02*
X1492412Y293087D01*
G01X1522645Y334940D02*
X1527537Y330048D01*
G01X1521352Y334940D02*
X1522645D01*
G01X1514278Y342014D02*
X1521352Y334940D01*
G01X1521954Y282063D02*
X1523876Y280141D01*
G01X1521954Y305313D02*
Y282063D01*
G01X1520830Y306437D02*
X1521954Y305313D01*
G01X1520830Y327500D02*
Y306437D01*
G01X1523500Y330170D02*
X1520830Y327500D01*
G01X1523500Y331728D02*
Y330170D01*
G01X1513526Y341702D02*
X1523500Y331728D01*
G01X1523341Y340366D02*
Y342920D01*
G01X1525632Y338075D02*
X1523341Y340366D01*
G01X1525810Y338075D02*
X1525632D01*
G01X1525811Y338076D02*
X1525810Y338075D01*
G01X1527057Y338076D02*
X1525811D01*
G01X1527058Y338075D02*
X1527057Y338076D01*
G01X1470529Y326840D02*
X1466755D01*
G01X1477727Y334038D02*
X1470529Y326840D01*
G01X1477727Y345571D02*
Y334038D01*
G01X1492130Y282127D02*
Y280825D01*
G01X1494871Y284868D02*
X1492130Y282127D01*
G01X1499365Y284868D02*
X1494871D01*
G01X1501527Y287030D02*
X1499365Y284868D01*
G01X1501527Y287798D02*
Y287030D01*
G01X1501563Y287834D02*
X1501527Y287798D01*
G01X1501563Y289140D02*
Y287834D01*
G01X1501527Y289176D02*
X1501563Y289140D01*
G01X1501527Y290422D02*
Y289176D01*
G01X1503126Y292021D02*
X1501527Y290422D01*
G01X1503126Y294403D02*
Y292021D01*
G01X1502016Y295513D02*
X1503126Y294403D01*
G01X1491513Y295513D02*
X1502016D01*
G01X1490179Y294179D02*
X1491513Y295513D01*
G01X1481568Y294179D02*
X1490179D01*
G01X1480098Y295649D02*
X1481568Y294179D01*
G01X1520000Y334164D02*
X1512614Y341550D01*
G01X1520000Y306011D02*
Y334164D01*
G01X1520880Y305131D02*
X1520000Y306011D01*
G01X1520880Y285715D02*
Y305131D01*
G01X1519624Y284459D02*
X1520880Y285715D01*
G01X1466349Y314564D02*
Y303946D01*
G01X1470285Y318500D02*
X1466349Y314564D01*
G01X1474698Y318500D02*
X1470285D01*
G01X1479983Y323785D02*
X1474698Y318500D01*
G01X1479983Y346621D02*
Y323785D01*
G01X1491311Y290046D02*
Y280168D01*
G01X1493465Y292200D02*
X1491311Y290046D01*
G01X1500000Y292200D02*
X1493465D01*
G01X1501550Y293750D02*
X1500000Y292200D01*
G01X1512182Y292297D02*
Y293317D01*
G01X1513476Y291003D02*
X1512182Y292297D01*
G01X1513476Y286847D02*
Y291003D01*
G01X1510600Y283971D02*
X1513476Y286847D01*
G01X1525088Y291054D02*
X1526900Y292866D01*
G01X1525088Y289383D02*
Y291054D01*
G01X1525087Y289382D02*
X1525088Y289383D01*
G01X1525087Y287722D02*
Y289382D01*
G01X1525088Y287721D02*
X1525087Y287722D01*
G01X1525088Y282396D02*
Y287721D01*
G01X1525880Y281604D02*
X1525088Y282396D01*
G01X1523835Y281878D02*
X1524628Y281085D01*
G01X1523835Y282914D02*
Y281878D01*
G01X1523836Y282915D02*
X1523835Y282914D01*
G01X1523836Y287202D02*
Y282915D01*
G01X1523835Y287203D02*
X1523836Y287202D01*
G01X1523835Y289901D02*
Y287203D01*
G01X1523836Y289902D02*
X1523835Y289901D01*
G01X1523836Y291573D02*
Y289902D01*
G01X1525100Y292837D02*
X1523836Y291573D01*
G01X1525100Y305039D02*
Y292837D01*
G01X1521593Y308546D02*
X1525100Y305039D01*
G01X1521593Y321688D02*
Y308546D01*
G01X1529113Y329208D02*
X1521593Y321688D01*
G01X1526456Y335723D02*
X1529113Y333066D01*
G01X1521633Y335723D02*
X1526456D01*
G01X1515030Y342326D02*
X1521633Y335723D01*
G01X1486397Y315507D02*
Y314546D01*
G01X1484926Y316978D02*
X1486397Y315507D01*
G01X1484926Y318926D02*
Y316978D01*
G01X1486600Y320600D02*
X1484926Y318926D01*
G01X1486600Y326588D02*
Y320600D01*
G01X1489480Y329468D02*
X1486600Y326588D01*
G01X1489480Y341120D02*
Y329468D01*
G01X1482176Y348424D02*
X1489480Y341120D01*
G01X1497710Y341140D02*
Y342470D01*
G01X1500120Y338730D02*
X1497710Y341140D01*
G01X1500120Y338090D02*
Y338730D01*
G01X1501448Y336762D02*
X1500120Y338090D01*
G01X1501448Y332957D02*
Y336762D01*
G01X1497920Y329429D02*
X1501448Y332957D01*
G01X1497920Y318990D02*
Y329429D01*
G01X1502236Y314674D02*
X1497920Y318990D01*
G01X1502236Y310318D02*
Y314674D01*
G01X1503542Y309012D02*
X1502236Y310318D01*
G01X1503542Y304418D02*
Y309012D01*
G01X1507800Y300160D02*
X1503542Y304418D01*
G01X1507800Y290854D02*
Y300160D01*
G01X1505793Y288847D02*
X1507800Y290854D01*
G01X1502652Y283951D02*
Y280639D01*
G01X1504548Y285847D02*
X1502652Y283951D01*
G01X1504548Y289232D02*
Y285847D01*
G01X1506248Y290932D02*
X1504548Y289232D01*
G01X1506248Y298670D02*
Y290932D01*
G01X1502156Y302762D02*
X1506248Y298670D01*
G01X1502156Y308359D02*
Y302762D01*
G01X1501084Y309431D02*
X1502156Y308359D01*
G01X1501084Y313682D02*
Y309431D01*
G01X1496720Y318046D02*
X1501084Y313682D01*
G01X1496720Y330029D02*
Y318046D01*
G01X1500296Y333605D02*
X1496720Y330029D01*
G01X1500296Y336247D02*
Y333605D01*
G01X1497997Y338546D02*
X1500296Y336247D01*
G01X1524278Y340493D02*
Y343409D01*
G01X1525943Y338828D02*
X1524278Y340493D01*
G01X1527369Y338828D02*
X1525943D01*
G01X1473561Y332894D02*
X1469409D01*
G01X1474175Y333508D02*
X1473561Y332894D01*
G01X1474175Y344507D02*
Y333508D01*
G01X1484100Y329799D02*
Y330115D01*
G01X1481226Y326925D02*
X1484100Y329799D01*
G01X1481226Y319313D02*
Y326925D01*
G01X1474780Y312867D02*
X1481226Y319313D01*
G01X1473189Y312867D02*
X1474780D01*
G01X1472328Y312006D02*
X1473189Y312867D01*
G01X1472328Y297730D02*
Y312006D01*
G01X1472939Y297119D02*
X1472328Y297730D01*
G01X1477672Y297119D02*
X1472939D01*
G01X1478418Y296373D02*
X1477672Y297119D01*
G01X1478418Y293882D02*
Y296373D01*
G01X1481600Y290700D02*
X1478418Y293882D01*
G01X1521945Y336475D02*
X1515782Y342638D01*
G01X1526768Y336475D02*
X1521945D01*
G01X1530010Y333233D02*
X1526768Y336475D01*
G01X1525673Y323830D02*
X1530010Y328167D01*
G01X1525673Y316285D02*
Y323830D01*
G01X1523598Y314210D02*
X1525673Y316285D01*
G01X1523598Y310628D02*
Y314210D01*
G01X1524478Y309748D02*
X1523598Y310628D01*
G01X1527747Y309748D02*
X1524478D01*
G01X1478628Y286811D02*
Y279972D01*
G01X1478700Y286883D02*
X1478628Y286811D01*
G01X1478700Y290600D02*
Y286883D01*
G01X1476700Y292600D02*
X1478700Y290600D01*
G01X1468700Y292600D02*
X1476700D01*
G01X1466400Y294900D02*
X1468700Y292600D01*
G01X1466400Y299600D02*
Y294900D01*
G01X1465600Y300400D02*
X1466400Y299600D01*
G01X1510264Y285265D02*
X1509448Y284449D01*
G01X1510264Y294634D02*
Y285265D01*
G01X1513672Y298042D02*
X1510264Y294634D01*
G01X1513672Y305063D02*
Y298042D01*
G01X1510039Y308696D02*
X1513672Y305063D01*
G01X1510039Y313686D02*
Y308696D01*
G01X1508212Y315513D02*
X1510039Y313686D01*
G01X1508212Y324720D02*
Y315513D01*
G01X1507220Y325712D02*
X1508212Y324720D01*
G01X1507220Y334230D02*
Y325712D01*
G01X1505170Y336280D02*
X1507220Y334230D01*
G01X1505170Y338820D02*
Y336280D01*
G01X1506640Y340290D02*
X1505170Y338820D01*
G01X1506640Y342859D02*
Y340290D01*
G01X1503460Y340080D02*
X1498310Y345230D01*
G01X1503460Y334190D02*
Y340080D01*
G01X1506060Y331590D02*
X1503460Y334190D01*
G01X1506060Y326194D02*
Y331590D01*
G01X1504783Y324917D02*
X1506060Y326194D01*
G01X1504783Y324421D02*
Y324917D01*
G01X1503099Y322736D02*
X1504783Y324421D01*
G01X1503099Y322240D02*
Y322736D01*
G01X1503599Y321740D02*
X1503099Y322240D01*
G01X1504095Y321740D02*
X1503599D01*
G01X1505779Y323425D02*
X1504095Y321740D01*
G01X1506275Y323425D02*
X1505779D01*
G01X1506811Y322889D02*
X1506275Y323425D01*
G01X1506811Y320010D02*
Y322889D01*
G01X1506459Y319658D02*
X1506811Y320010D01*
G01X1505679Y319658D02*
X1506459D01*
G01X1505327Y319306D02*
X1505679Y319658D01*
G01X1505327Y318602D02*
Y319306D01*
G01X1505679Y318250D02*
X1505327Y318602D01*
G01X1506459Y318250D02*
X1505679D01*
G01X1506811Y317898D02*
X1506459Y318250D01*
G01X1506811Y317194D02*
Y317898D01*
G01X1506459Y316842D02*
X1506811Y317194D01*
G01X1504828Y316842D02*
X1506459D01*
G01X1504476Y316490D02*
X1504828Y316842D01*
G01X1504476Y315786D02*
Y316490D01*
G01X1504828Y315434D02*
X1504476Y315786D01*
G01X1506459Y315434D02*
X1504828D01*
G01X1506811Y315082D02*
X1506459Y315434D01*
G01X1506811Y313373D02*
Y315082D01*
G01X1506459Y313021D02*
X1506811Y313373D01*
G01X1504752Y313021D02*
X1506459D01*
G01X1504400Y312669D02*
X1504752Y313021D01*
G01X1504400Y311965D02*
Y312669D01*
G01X1504752Y311613D02*
X1504400Y311965D01*
G01X1506459Y311613D02*
X1504752D01*
G01X1508360Y309712D02*
X1506459Y311613D01*
G01X1508360Y308300D02*
Y309712D01*
G01X1509000Y307660D02*
X1508360Y308300D01*
G01X1509000Y299615D02*
Y307660D01*
G01X1509515Y299100D02*
X1509000Y299615D01*
G01X1510245Y299100D02*
X1509515D01*
G01X1510760Y299615D02*
X1510245Y299100D01*
G01X1510760Y304585D02*
Y299615D01*
G01X1511275Y305100D02*
X1510760Y304585D01*
G01X1512005Y305100D02*
X1511275D01*
G01X1512520Y304585D02*
X1512005Y305100D01*
G01X1512520Y298520D02*
Y304585D01*
G01X1509000Y295000D02*
X1512520Y298520D01*
G01X1509000Y290424D02*
Y295000D01*
G01X1506945Y288369D02*
X1509000Y290424D01*
G01X1506945Y279740D02*
Y288369D01*
G01X1509136Y335306D02*
Y349374D01*
G01X1508372Y334542D02*
X1509136Y335306D01*
G01X1508372Y327555D02*
Y334542D01*
G01X1509364Y326563D02*
X1508372Y327555D01*
G01X1509364Y315991D02*
Y326563D01*
G01X1511191Y314164D02*
X1509364Y315991D01*
G01X1511191Y309538D02*
Y314164D01*
G01X1516298Y304431D02*
X1511191Y309538D01*
G01X1516298Y291389D02*
Y304431D01*
G01X1514628Y289719D02*
X1516298Y291389D01*
G01X1514628Y286369D02*
Y289719D01*
G01X1513906Y285647D02*
X1514628Y286369D01*
G01X1472128Y352348D02*
X1478479Y345997D01*
G01X1472128Y366914D02*
Y352348D01*
G01X1473276Y368062D02*
X1472128Y366914D01*
G01X1474962Y368062D02*
X1473276D01*
G01X1484103Y377203D02*
X1474962Y368062D01*
G01X1484103Y378292D02*
Y377203D01*
G01X1488311Y382500D02*
X1484103Y378292D01*
G01X1530872Y382500D02*
X1488311D01*
G01X1523946Y348273D02*
X1529092Y343127D01*
G01X1523946Y351168D02*
Y348273D01*
G01X1529829Y357051D02*
X1523946Y351168D01*
G01X1472880Y352660D02*
X1479231Y346309D01*
G01X1472880Y366603D02*
Y352660D01*
G01X1473588Y367311D02*
X1472880Y366603D01*
G01X1475476Y367311D02*
X1473588D01*
G01X1484854Y376689D02*
X1475476Y367311D01*
G01X1484854Y377354D02*
Y376689D01*
G01X1486824Y379324D02*
X1484854Y377354D01*
G01X1533026Y379324D02*
X1486824D01*
G01X1491699Y348150D02*
X1489838Y350011D01*
G01X1498730Y348150D02*
X1491699D01*
G01X1500040Y349460D02*
X1498730Y348150D01*
G01X1500040Y365080D02*
Y349460D01*
G01X1502503Y367543D02*
X1500040Y365080D01*
G01X1520994Y367543D02*
X1502503D01*
G01X1523989Y364548D02*
X1520994Y367543D01*
G01X1534348Y364548D02*
X1523989D01*
G01X1517367Y347102D02*
X1522589Y341880D01*
G01X1517367Y349964D02*
Y347102D01*
G01X1484748Y347252D02*
X1490290Y341710D01*
G01X1484748Y355119D02*
Y347252D01*
G01X1486189Y356560D02*
X1484748Y355119D01*
G01X1486189Y365589D02*
Y356560D01*
G01X1489750Y369150D02*
X1486189Y365589D01*
G01X1553450Y369150D02*
X1489750D01*
G01X1470130Y350974D02*
X1475908Y345196D01*
G01X1470130Y367042D02*
Y350974D01*
G01X1472652Y369564D02*
X1470130Y367042D01*
G01X1473665Y369564D02*
X1472652D01*
G01X1482601Y378500D02*
X1473665Y369564D01*
G01X1482601Y380000D02*
Y378500D01*
G01X1484400Y381799D02*
X1482601Y380000D01*
G01X1484400Y384440D02*
Y381799D01*
G01X1485156Y385196D02*
X1484400Y384440D01*
G01X1514278Y352317D02*
Y342014D01*
G01X1516481Y354520D02*
X1514278Y352317D01*
G01X1516481Y358492D02*
Y354520D01*
G01X1516129Y358844D02*
X1516481Y358492D01*
G01X1514925Y358844D02*
X1516129D01*
G01X1513526Y352792D02*
Y341702D01*
G01X1514265Y353531D02*
X1513526Y352792D01*
G01X1514265Y355542D02*
Y353531D01*
G01X1520352Y354379D02*
X1520429D01*
G01X1520000Y354027D02*
X1520352Y354379D01*
G01X1520000Y346261D02*
Y354027D01*
G01X1523341Y342920D02*
X1520000Y346261D01*
G01X1471048Y352250D02*
X1477727Y345571D01*
G01X1471048Y366897D02*
Y352250D01*
G01X1472964Y368813D02*
X1471048Y366897D01*
G01X1474314Y368813D02*
X1472964D01*
G01X1483351Y377850D02*
X1474314Y368813D01*
G01X1483351Y377978D02*
Y377850D01*
G01X1483352Y377979D02*
X1483351Y377978D01*
G01X1483352Y379152D02*
Y377979D01*
G01X1485153Y380953D02*
X1483352Y379152D01*
G01X1485153Y382216D02*
Y380953D01*
G01X1485152Y382217D02*
X1485153Y382216D01*
G01X1485152Y384128D02*
Y382217D01*
G01X1485909Y384885D02*
X1485152Y384128D01*
G01X1512614Y349013D02*
X1511000Y350627D01*
G01X1512614Y341550D02*
Y349013D01*
G01X1475330Y351274D02*
X1479983Y346621D01*
G01X1475330Y363956D02*
Y351274D01*
G01X1476110Y364736D02*
X1475330Y363956D01*
G01X1476110Y366610D02*
Y364736D01*
G01X1485410Y375910D02*
X1476110Y366610D01*
G01X1539602Y375910D02*
X1485410D01*
G01X1515030Y352005D02*
Y342326D01*
G01X1517233Y354208D02*
X1515030Y352005D01*
G01X1517233Y358947D02*
Y354208D01*
G01X1515512Y360668D02*
X1517233Y358947D01*
G01X1514268Y360668D02*
X1515512D01*
G01X1509600Y356000D02*
X1514268Y360668D01*
G01X1507200Y356000D02*
X1509600D01*
G01X1480347Y348424D02*
X1482176D01*
G01X1476587Y352184D02*
X1480347Y348424D01*
G01X1476587Y363800D02*
Y352184D01*
G01X1476880Y364093D02*
X1476587Y363800D01*
G01X1476880Y366101D02*
Y364093D01*
G01X1485881Y375102D02*
X1476880Y366101D01*
G01X1549734Y375102D02*
X1485881D01*
G01X1525532Y350253D02*
X1525561D01*
G01X1525532Y348679D02*
Y350253D01*
G01X1529676Y344535D02*
X1525532Y348679D01*
G01X1483740Y360111D02*
Y359550D01*
G01X1485322Y361693D02*
X1483740Y360111D01*
G01X1485322Y367004D02*
Y361693D01*
G01X1488970Y370652D02*
X1485322Y367004D01*
G01X1557116Y370652D02*
X1488970D01*
G01X1485732Y355020D02*
X1488479Y357767D01*
G01X1485732Y348080D02*
Y355020D01*
G01X1489759Y344053D02*
X1485732Y348080D01*
G01X1496127Y344053D02*
X1489759D01*
G01X1497710Y342470D02*
X1496127Y344053D01*
G01X1522005Y361436D02*
X1522476Y361907D01*
G01X1522005Y353368D02*
Y361436D01*
G01X1521218Y352581D02*
X1522005Y353368D01*
G01X1521218Y346469D02*
Y352581D01*
G01X1524278Y343409D02*
X1521218Y346469D01*
G01X1469378Y349304D02*
X1474175Y344507D01*
G01X1469378Y367353D02*
Y349304D01*
G01X1472341Y370316D02*
X1469378Y367353D01*
G01X1473217Y370316D02*
X1472341D01*
G01X1480199Y377298D02*
X1473217Y370316D01*
G01X1480199Y384452D02*
Y377298D01*
G01X1481392Y385645D02*
X1480199Y384452D01*
G01X1482996Y385645D02*
X1481392D01*
G01X1487320Y389969D02*
X1482996Y385645D01*
G01X1487320Y391209D02*
Y389969D01*
G01X1488780Y392669D02*
X1487320Y391209D01*
G01X1497590Y392669D02*
X1488780D01*
G01X1499225Y391034D02*
X1497590Y392669D01*
G01X1488353Y372581D02*
X1554644D01*
G01X1487928Y372156D02*
X1488353Y372581D01*
G01X1487927Y372156D02*
X1487928D01*
G01X1483712Y367941D02*
X1487927Y372156D01*
G01X1482592Y367941D02*
X1483712D01*
G01X1481106Y366455D02*
X1482592Y367941D01*
G01X1481106Y361581D02*
Y366455D01*
G01X1478607Y359082D02*
X1481106Y361581D01*
G01X1510292Y361792D02*
X1507200Y358700D01*
G01X1515452Y361792D02*
X1510292D01*
G01X1517985Y359259D02*
X1515452Y361792D01*
G01X1517985Y353896D02*
Y359259D01*
G01X1515782Y351693D02*
X1517985Y353896D01*
G01X1515782Y342638D02*
Y351693D01*
G01X1524746Y353032D02*
Y354217D01*
G01X1523177Y351463D02*
X1524746Y353032D01*
G01X1523177Y347978D02*
Y351463D01*
G01X1528780Y342375D02*
X1523177Y347978D01*
G01X1495627Y352637D02*
X1489915D01*
G01X1496490Y353500D02*
X1495627Y352637D01*
G01X1496490Y367967D02*
Y353500D01*
G01X1496875Y368352D02*
X1496490Y367967D01*
G01X1531779Y368352D02*
X1496875D01*
G01X1503019Y346480D02*
X1506640Y342859D01*
G01X1490592Y346480D02*
X1503019D01*
G01X1488036Y349036D02*
X1490592Y346480D01*
G01X1488036Y353307D02*
Y349036D01*
G01X1491207Y356478D02*
X1488036Y353307D01*
G01X1491207Y360239D02*
Y356478D01*
G01X1488479Y362967D02*
X1491207Y360239D01*
G01X1490055Y358791D02*
X1488479Y360367D01*
G01X1490055Y356956D02*
Y358791D01*
G01X1486884Y353785D02*
X1490055Y356956D01*
G01X1486884Y348558D02*
Y353785D01*
G01X1490212Y345230D02*
X1486884Y348558D01*
G01X1498310Y345230D02*
X1490212D01*
G01X1507154Y351356D02*
Y353100D01*
G01X1509136Y349374D02*
X1507154Y351356D01*
G01X1480219Y363277D02*
X1478612Y361670D01*
G01X1480219Y366776D02*
Y363277D01*
G01X1487131Y373688D02*
X1480219Y366776D01*
G01X1554688Y373688D02*
X1487131D01*
G01X1488239Y371404D02*
X1556804D01*
G01X1484024Y367189D02*
X1488239Y371404D01*
G01X1482904Y367189D02*
X1484024D01*
G01X1481930Y366215D02*
X1482904Y367189D01*
G01X1481930Y364648D02*
Y366215D01*
G01X1483664Y362914D02*
X1481930Y364648D01*
G01X1522370Y347155D02*
X1527879Y341646D01*
G01X1522370Y351971D02*
Y347155D01*
G01X1523157Y352758D02*
X1522370Y351971D01*
G01X1523157Y355128D02*
Y352758D01*
G01X1524746Y356717D02*
X1523157Y355128D01*
G01X1523017Y464054D02*
G02X1523788Y465190I1558J-228D01*
G01X1523245Y463826D02*
X1523017Y464054D01*
G01X1524575Y463826D02*
X1523245D01*
G01X1480100Y448000D02*
X1474775Y442675D01*
G01X1489900Y448000D02*
X1480100D01*
G01X1490974Y446926D02*
X1489900Y448000D01*
G01X1491425Y446926D02*
X1490974D01*
G01X1522261Y464082D02*
G02X1523412Y465842I2313J-256D01*
G01X1522005Y463826D02*
X1522261Y464082D01*
G01X1520675Y463826D02*
X1522005D01*
G01X1519700Y465516D02*
X1516775Y463826D01*
G01X1475755Y490187D02*
X1470643Y495299D01*
G01X1478889Y490187D02*
X1475755D01*
G01X1482958Y486118D02*
X1478889Y490187D01*
G01X1520675Y467141D02*
G02X1519700Y465516I-1950J65D01*
G01X1520675Y467271D02*
Y467141D01*
G01X1521650Y468896D02*
G03X1520675Y467271I975J-1690D01*
G01X1522625Y470521D02*
G02X1521650Y468896I-1950J65D01*
G01X1522625Y470651D02*
Y470521D01*
G01X1493194Y555834D02*
X1536409D01*
G01X1481080Y543720D02*
X1493194Y555834D01*
G01X1494497Y553730D02*
X1537282D01*
G01X1482343Y541576D02*
X1494497Y553730D01*
G01X1493762Y554882D02*
X1536804D01*
G01X1481610Y542730D02*
X1493762Y554882D01*
G01X1534238Y624000D02*
X1467500D01*
G01X1584822Y976D02*
X1599526D01*
G01X1580398Y5400D02*
X1584822Y976D01*
G01X1571605Y-4104D02*
X1592710D01*
G01X1567701Y-200D02*
X1571605Y-4104D01*
G01X1531286Y-200D02*
X1567701D01*
G01X1531285Y-201D02*
X1531286Y-200D01*
G01X1529707Y-201D02*
X1531285D01*
G01X1529706Y-200D02*
X1529707Y-201D01*
G01X1568948Y-7495D02*
X1566377Y-4924D01*
G01X1568948Y-17795D02*
Y-7495D01*
G01X1570881Y-19728D02*
X1568948Y-17795D01*
G01X1589219Y-19728D02*
X1570881D01*
G01X1579305Y-3152D02*
X1593105D01*
G01X1575401Y752D02*
X1579305Y-3152D01*
G01X1529972Y752D02*
X1575401D01*
G01X1527600Y3124D02*
X1529972Y752D01*
G01X1527600Y3500D02*
Y3124D01*
G01X1579700Y-2200D02*
X1593500D01*
G01X1575796Y1704D02*
X1579700Y-2200D01*
G01X1530367Y1704D02*
X1575796D01*
G01X1529224Y2847D02*
X1530367Y1704D01*
G01X1529224Y4105D02*
Y2847D01*
G01X1528229Y5100D02*
X1529224Y4105D01*
G01X1571116Y-5056D02*
X1592315D01*
G01X1567728Y-1668D02*
X1571116Y-5056D01*
G01X1569900Y-7100D02*
X1566772Y-3972D01*
G01X1569900Y-17400D02*
Y-7100D01*
G01X1571276Y-18776D02*
X1569900Y-17400D01*
G01X1588824Y-18776D02*
X1571276D01*
G01X1570638Y-6208D02*
X1567250Y-2820D01*
G01X1574108Y-6208D02*
X1570638D01*
G01X1584000Y-16100D02*
X1574108Y-6208D01*
G01X1536326Y149122D02*
Y159424D01*
G01X1538750Y146698D02*
X1536326Y149122D01*
G01X1538750Y136909D02*
Y146698D01*
G01X1540737Y134922D02*
X1538750Y136909D01*
G01X1546389Y134922D02*
X1540737D01*
G01X1552043Y140576D02*
X1546389Y134922D01*
G01X1556646Y140576D02*
X1552043D01*
G01X1557328Y139894D02*
X1556646Y140576D01*
G01X1557508Y139894D02*
X1557328D01*
G01X1557585Y139817D02*
X1557508Y139894D01*
G01X1559625Y139817D02*
X1557585D01*
G01X1560179Y139263D02*
X1559625Y139817D01*
G01X1560179Y133071D02*
Y139263D01*
G01X1570582Y122668D02*
X1560179Y133071D01*
G01X1583114Y122668D02*
X1570582D01*
G01X1585642Y125196D02*
X1583114Y122668D01*
G01X1592678Y125196D02*
X1585642D01*
G01X1527505Y144994D02*
Y147983D01*
G01X1534567Y137932D02*
X1527505Y144994D01*
G01X1534567Y134668D02*
Y137932D01*
G01X1541159Y128076D02*
X1534567Y134668D01*
G01X1541623Y128076D02*
X1541159D01*
G01X1541624Y128075D02*
X1541623Y128076D01*
G01X1542925Y128075D02*
X1541624D01*
G01X1549649Y121351D02*
X1542925Y128075D01*
G01X1553149Y121351D02*
X1549649D01*
G01X1553500Y121000D02*
X1553149Y121351D01*
G01X1585500Y150195D02*
X1577945Y157750D01*
G01X1600944Y150195D02*
X1585500D01*
G01X1585879Y156021D02*
X1602468D01*
G01X1577842Y164058D02*
X1585879Y156021D01*
G01X1558769Y153960D02*
X1530878Y181851D01*
G01X1565387Y153960D02*
X1558769D01*
G01X1572547Y146800D02*
X1565387Y153960D01*
G01X1598420Y146800D02*
X1572547D01*
G01X1586999Y110752D02*
X1590025D01*
G01X1583175Y114576D02*
X1586999Y110752D01*
G01X1577229Y114576D02*
X1583175D01*
G01X1575444Y112791D02*
X1577229Y114576D01*
G01X1547649Y112791D02*
X1575444D01*
G01X1542926Y117514D02*
X1547649Y112791D01*
G01X1535730Y117514D02*
X1542926D01*
G01X1530116Y123128D02*
X1535730Y117514D01*
G01X1530116Y126043D02*
Y123128D01*
G01X1585753Y109516D02*
X1589631D01*
G01X1583664Y111605D02*
X1585753Y109516D01*
G01X1581242Y111605D02*
X1583664D01*
G01X1578041Y108404D02*
X1581242Y111605D01*
G01X1563764Y108404D02*
X1578041D01*
G01X1562136Y110032D02*
X1563764Y108404D01*
G01X1543945Y110032D02*
X1562136D01*
G01X1542977Y111000D02*
X1543945Y110032D01*
G01X1537980Y111000D02*
X1542977D01*
G01X1528289Y120691D02*
X1537980Y111000D01*
G01X1528289Y121505D02*
Y120691D01*
G01X1583919Y133138D02*
X1592084D01*
G01X1583153Y133904D02*
X1583919Y133138D01*
G01X1571632Y133904D02*
X1583153D01*
G01X1569466Y131738D02*
X1571632Y133904D01*
G01X1566907Y131738D02*
X1569466D01*
G01X1565944Y132701D02*
X1566907Y131738D01*
G01X1565944Y134007D02*
Y132701D01*
G01X1565972Y134035D02*
X1565944Y134007D01*
G01X1565972Y142288D02*
Y134035D01*
G01X1560720Y147540D02*
X1565972Y142288D01*
G01X1542570Y147540D02*
X1560720D01*
G01X1542484Y147454D02*
X1542570Y147540D01*
G01X1541178Y147454D02*
X1542484D01*
G01X1541092Y147540D02*
X1541178Y147454D01*
G01X1540740Y147540D02*
X1541092D01*
G01X1539519Y148761D02*
X1540740Y147540D01*
G01X1539519Y162802D02*
Y148761D01*
G01X1541481Y139824D02*
X1541434Y139871D01*
G01X1547165Y139824D02*
X1541481D01*
G01X1551612Y144271D02*
X1547165Y139824D01*
G01X1558674Y144271D02*
X1551612D01*
G01X1560974Y141971D02*
X1558674Y144271D01*
G01X1560974Y133340D02*
Y141971D01*
G01X1570625Y123689D02*
X1560974Y133340D01*
G01X1580784Y123689D02*
X1570625D01*
G01X1584067Y126972D02*
X1580784Y123689D01*
G01X1593028Y126972D02*
X1584067D01*
G01X1552780Y151205D02*
X1543062Y160923D01*
G01X1564882Y151205D02*
X1552780D01*
G01X1574317Y141770D02*
X1564882Y151205D01*
G01X1585721Y141770D02*
X1574317D01*
G01X1588101Y144150D02*
X1585721Y141770D01*
G01X1602225Y144150D02*
X1588101D01*
G01X1583572Y154031D02*
X1600398D01*
G01X1578479Y159124D02*
X1583572Y154031D01*
G01X1531872Y108900D02*
X1529122Y111650D01*
G01X1542383Y108900D02*
X1531872D01*
G01X1544783Y106500D02*
X1542383Y108900D01*
G01X1556527Y106500D02*
X1544783D01*
G01X1557536Y105491D02*
X1556527Y106500D01*
G01X1575476Y105491D02*
X1557536D01*
G01X1575953Y105968D02*
X1575476Y105491D01*
G01X1586385Y105968D02*
X1575953D01*
G01X1587200Y105153D02*
X1586385Y105968D01*
G01X1590814Y105153D02*
X1587200D01*
G01X1575885Y116680D02*
X1590401D01*
G01X1574877Y115672D02*
X1575885Y116680D01*
G01X1552828Y115672D02*
X1574877D01*
G01X1543900Y124600D02*
X1552828Y115672D01*
G01X1540777Y124600D02*
X1543900D01*
G01X1538977Y126400D02*
X1540777Y124600D01*
G01X1533020Y126400D02*
X1538977D01*
G01X1527573Y131847D02*
X1533020Y126400D01*
G01X1527573Y138699D02*
Y131847D01*
G01X1537186Y149797D02*
Y159628D01*
G01X1539502Y147481D02*
X1537186Y149797D01*
G01X1539502Y139000D02*
Y147481D01*
G01X1540207Y138295D02*
X1539502Y139000D01*
G01X1546700Y138295D02*
X1540207D01*
G01X1550342Y141937D02*
X1546700Y138295D01*
G01X1557514Y141937D02*
X1550342D01*
G01X1557981Y141470D02*
X1557514Y141937D01*
G01X1551000Y156014D02*
Y160099D01*
G01X1554489Y152525D02*
X1551000Y156014D01*
G01X1565192Y152525D02*
X1554489D01*
G01X1572217Y145500D02*
X1565192Y152525D01*
G01X1605954Y145500D02*
X1572217D01*
G01X1576751Y115728D02*
X1589540D01*
G01X1574966Y113943D02*
X1576751Y115728D01*
G01X1553057Y113943D02*
X1574966D01*
G01X1543352Y123648D02*
X1553057Y113943D01*
G01X1540382Y123648D02*
X1543352D01*
G01X1538582Y125448D02*
X1540382Y123648D01*
G01X1532621Y125448D02*
X1538582D01*
G01X1552262Y149952D02*
X1541810Y160404D01*
G01X1553298Y149952D02*
X1552262D01*
G01X1553299Y149953D02*
X1553298Y149952D01*
G01X1564216Y149953D02*
X1553299D01*
G01X1577210Y136959D02*
X1564216Y149953D01*
G01X1583221Y136959D02*
X1577210D01*
G01X1587825Y141563D02*
X1583221Y136959D01*
G01X1594277Y141563D02*
X1587825D01*
G01X1588613Y140111D02*
X1594123D01*
G01X1583385Y134883D02*
X1588613Y140111D01*
G01X1575880Y134883D02*
X1583385D01*
G01X1569242Y141521D02*
X1575880Y134883D01*
G01X1567803Y141521D02*
X1569242D01*
G01X1560989Y148335D02*
X1567803Y141521D01*
G01X1551863Y148335D02*
X1560989D01*
G01X1540457Y159741D02*
X1551863Y148335D01*
G01X1576104Y118246D02*
X1590655D01*
G01X1574482Y116624D02*
X1576104Y118246D01*
G01X1559376Y116624D02*
X1574482D01*
G01X1555076Y120924D02*
X1559376Y116624D01*
G01X1555076Y121653D02*
Y120924D01*
G01X1554153Y122576D02*
X1555076Y121653D01*
G01X1549924Y122576D02*
X1554153D01*
G01X1543672Y128828D02*
X1549924Y122576D01*
G01X1541471Y128828D02*
X1543672D01*
G01X1535319Y134980D02*
X1541471Y128828D01*
G01X1535319Y138244D02*
Y134980D01*
G01X1528257Y145306D02*
X1535319Y138244D01*
G01X1528257Y148295D02*
Y145306D01*
G01X1531988Y109848D02*
X1529434Y112402D01*
G01X1542499Y109848D02*
X1531988D01*
G01X1543467Y108880D02*
X1542499Y109848D01*
G01X1561409Y108880D02*
X1543467D01*
G01X1563037Y107252D02*
X1561409Y108880D01*
G01X1584016Y107252D02*
X1563037D01*
G01X1585128Y108364D02*
X1584016Y107252D01*
G01X1589153Y108364D02*
X1585128D01*
G01X1555676Y124423D02*
Y123283D01*
G01X1552099Y128000D02*
X1555676Y124423D01*
G01X1546000Y128000D02*
X1552099D01*
G01X1544000Y130000D02*
X1546000Y128000D01*
G01X1541399Y130000D02*
X1544000D01*
G01X1536071Y135328D02*
X1541399Y130000D01*
G01X1536071Y138556D02*
Y135328D01*
G01X1529009Y145618D02*
X1536071Y138556D01*
G01X1529009Y148607D02*
Y145618D01*
G01X1533517Y133918D02*
Y137461D01*
G01X1532270Y132671D02*
X1533517Y133918D01*
G01X1530101Y132671D02*
X1532270D01*
G01X1571951Y110310D02*
X1572395Y110754D01*
G01X1564119Y110310D02*
X1571951D01*
G01X1563074Y111355D02*
X1564119Y110310D01*
G01X1547449Y111355D02*
X1563074D01*
G01X1546658Y112152D02*
X1547449Y111355D01*
G01X1542461Y116349D02*
X1546658Y112152D01*
G01X1535174Y116349D02*
X1542461D01*
G01X1528844Y122679D02*
X1535174Y116349D01*
G01X1528844Y125685D02*
Y122679D01*
G01X1585366Y155134D02*
X1600966D01*
G01X1579800Y160700D02*
X1585366Y155134D01*
G01X1548178Y191585D02*
Y190880D01*
G01X1547900Y191863D02*
X1548178Y191585D01*
G01X1547900Y197145D02*
Y191863D01*
G01X1549603Y198848D02*
X1547900Y197145D01*
G01X1551300Y198848D02*
X1549603D01*
G01X1554400Y201948D02*
X1551300Y198848D01*
G01X1554400Y248100D02*
Y201948D01*
G01X1536326Y159424D02*
X1531242Y164508D01*
G01X1585386Y157600D02*
X1588176D01*
G01X1577386Y165600D02*
X1585386Y157600D01*
G01X1569500Y165600D02*
X1577386D01*
G01X1568699Y166401D02*
X1569500Y165600D01*
G01X1561860Y166401D02*
X1568699D01*
G01X1551940Y176321D02*
X1561860Y166401D01*
G01X1541945Y176321D02*
X1551940D01*
G01X1536486Y181780D02*
X1541945Y176321D01*
G01X1536486Y182580D02*
Y181780D01*
G01X1536484Y182582D02*
X1536486Y182580D01*
G01X1536484Y186318D02*
Y182582D01*
G01X1537001Y186835D02*
X1536484Y186318D01*
G01X1537001Y203931D02*
Y186835D01*
G01X1540517Y207447D02*
X1537001Y203931D01*
G01X1540517Y229163D02*
Y207447D01*
G01X1583170Y180031D02*
X1593243Y169958D01*
G01X1571501Y180031D02*
X1583170D01*
G01X1564824Y195574D02*
Y241676D01*
G01X1561925Y192675D02*
X1564824Y195574D01*
G01X1583937Y175192D02*
X1566858D01*
G01X1594281Y164848D02*
X1583937Y175192D01*
G01X1583832Y177919D02*
X1592544Y169207D01*
G01X1566531Y177919D02*
X1583832D01*
G01X1562875Y181575D02*
X1566531Y177919D01*
G01X1542011Y181575D02*
X1562875D01*
G01X1540248Y183338D02*
X1542011Y181575D01*
G01X1540248Y184760D02*
Y183338D01*
G01X1541108Y185620D02*
X1540248Y184760D01*
G01X1541108Y201843D02*
Y185620D01*
G01X1545090Y205825D02*
X1541108Y201843D01*
G01X1545090Y224833D02*
Y205825D01*
G01X1536576Y206547D02*
Y224434D01*
G01X1533700Y203671D02*
X1536576Y206547D01*
G01X1533700Y181599D02*
Y203671D01*
G01X1542030Y173269D02*
X1533700Y181599D01*
G01X1548177Y173269D02*
X1542030D01*
G01X1551678Y169768D02*
X1548177Y173269D01*
G01X1554185Y169768D02*
X1551678D01*
G01X1559016Y164937D02*
X1554185Y169768D01*
G01X1559016Y159801D02*
Y164937D01*
G01X1561067Y157750D02*
X1559016Y159801D01*
G01X1577945Y157750D02*
X1561067D01*
G01X1568488Y164058D02*
X1577842D01*
G01X1530878Y203078D02*
X1535000Y207200D01*
G01X1530878Y181851D02*
Y203078D01*
G01X1566876Y181660D02*
X1566486Y181270D01*
G01X1582790Y181660D02*
X1566876D01*
G01X1593741Y170709D02*
X1582790Y181660D01*
G01X1536309Y166012D02*
X1539519Y162802D01*
G01X1549445Y208536D02*
Y246404D01*
G01X1542300Y201391D02*
X1549445Y208536D01*
G01X1542300Y185750D02*
Y201391D01*
G01X1541860Y185310D02*
X1542300Y185750D01*
G01X1541860Y185308D02*
Y185310D01*
G01X1541000Y184448D02*
X1541860Y185308D01*
G01X1541000Y183650D02*
Y184448D01*
G01X1542250Y182400D02*
X1541000Y183650D01*
G01X1563700Y182400D02*
X1542250D01*
G01X1564496Y183196D02*
X1563700Y182400D01*
G01X1583055Y183196D02*
X1564496D01*
G01X1590777Y175474D02*
X1583055Y183196D01*
G01X1542021Y206056D02*
Y229787D01*
G01X1538852Y202887D02*
X1542021Y206056D01*
G01X1538852Y186558D02*
Y202887D01*
G01X1537991Y185697D02*
X1538852Y186558D01*
G01X1537991Y185075D02*
Y185697D01*
G01X1537990Y185074D02*
X1537991Y185075D01*
G01X1537990Y183828D02*
Y185074D01*
G01X1537989Y183827D02*
X1537990Y183828D01*
G01X1537989Y183205D02*
Y183827D01*
G01X1537991Y183203D02*
X1537989Y183205D01*
G01X1537991Y183027D02*
Y183203D01*
G01X1537990Y183026D02*
X1537991Y183027D01*
G01X1537990Y182404D02*
Y183026D01*
G01X1542126Y178268D02*
X1537990Y182404D01*
G01X1542825Y178268D02*
X1542126D01*
G01X1542827Y178266D02*
X1542825Y178268D01*
G01X1543449Y178266D02*
X1542827D01*
G01X1543450Y178267D02*
X1543449Y178266D01*
G01X1544072Y178267D02*
X1543450D01*
G01X1544073Y178268D02*
X1544072Y178267D01*
G01X1560148Y178268D02*
X1544073D01*
G01X1565786Y172630D02*
X1560148Y178268D01*
G01X1577392Y172630D02*
X1565786D01*
G01X1589322Y160700D02*
X1577392Y172630D01*
G01X1528207Y172863D02*
Y219193D01*
G01X1529201Y171869D02*
X1528207Y172863D01*
G01X1535382Y171869D02*
X1529201D01*
G01X1535385Y171866D02*
X1535382Y171869D01*
G01X1536416Y171866D02*
X1535385D01*
G01X1543062Y165220D02*
X1536416Y171866D01*
G01X1543062Y160923D02*
Y165220D01*
G01X1566328Y228060D02*
X1598006Y196382D01*
G01X1561497Y159124D02*
X1578479D01*
G01X1560331Y160290D02*
X1561497Y159124D01*
G01X1560331Y166707D02*
Y160290D01*
G01X1551469Y175569D02*
X1560331Y166707D01*
G01X1542956Y175569D02*
X1551469D01*
G01X1542955Y175568D02*
X1542956Y175569D01*
G01X1542333Y175568D02*
X1542955D01*
G01X1542332Y175569D02*
X1542333Y175568D01*
G01X1541633Y175569D02*
X1542332D01*
G01X1535734Y181468D02*
X1541633Y175569D01*
G01X1535734Y182268D02*
Y181468D01*
G01X1535732Y182270D02*
X1535734Y182268D01*
G01X1535732Y186630D02*
Y182270D01*
G01X1535734Y186632D02*
X1535732Y186630D01*
G01X1535734Y187707D02*
Y186632D01*
G01X1535425Y188016D02*
X1535734Y187707D01*
G01X1594900Y198424D02*
X1565576Y227748D01*
G01X1587473Y187037D02*
X1592210Y182300D01*
G01X1556963Y187037D02*
X1587473D01*
G01X1552800Y191200D02*
X1556963Y187037D01*
G01X1552800Y193600D02*
Y191200D01*
G01X1549693Y196707D02*
X1552800Y193600D01*
G01X1537186Y159628D02*
X1531554Y165260D01*
G01X1531935Y215923D02*
Y224160D01*
G01X1529726Y213714D02*
X1531935Y215923D01*
G01X1529726Y182329D02*
Y213714D01*
G01X1529725Y182328D02*
X1529726Y182329D01*
G01X1529725Y180675D02*
Y182328D01*
G01X1529726Y180674D02*
X1529725Y180675D01*
G01X1529726Y176274D02*
Y180674D01*
G01X1529989Y176011D02*
X1529726Y176274D01*
G01X1529989Y175992D02*
Y176011D01*
G01X1531431Y174550D02*
X1529989Y175992D01*
G01X1536549Y174550D02*
X1531431D01*
G01X1551000Y160099D02*
X1536549Y174550D01*
G01X1534863Y170617D02*
X1528682D01*
G01X1541810Y163670D02*
X1534863Y170617D01*
G01X1541810Y160404D02*
Y163670D01*
G01X1577376Y218289D02*
X1608056Y187609D01*
G01X1540457Y162928D02*
Y159741D01*
G01X1534075Y169310D02*
X1540457Y162928D01*
G01X1527222Y169310D02*
X1534075D01*
G01X1555700Y202691D02*
Y248600D01*
G01X1556201Y202190D02*
X1555700Y202691D01*
G01X1556201Y200530D02*
Y202190D01*
G01X1556200Y200529D02*
X1556201Y200530D01*
G01X1556200Y191240D02*
Y200529D01*
G01X1556860Y190580D02*
X1556200Y191240D01*
G01X1559246Y190580D02*
X1556860D01*
G01X1561188Y188638D02*
X1559246Y190580D01*
G01X1587864Y188638D02*
X1561188D01*
G01X1593202Y183300D02*
X1587864Y188638D01*
G01X1561719Y190140D02*
X1591582D01*
G01X1559623Y192236D02*
X1561719Y190140D01*
G01X1557787Y192236D02*
X1559623D01*
G01X1551349Y207746D02*
Y247194D01*
G01X1544300Y200697D02*
X1551349Y207746D01*
G01X1544300Y191834D02*
Y200697D01*
G01X1549849Y186285D02*
X1544300Y191834D01*
G01X1586640Y186285D02*
X1549849D01*
G01X1594332Y178593D02*
X1586640Y186285D01*
G01X1543280Y183948D02*
X1543100Y184128D01*
G01X1583914Y183948D02*
X1543280D01*
G01X1591860Y176002D02*
X1583914Y183948D01*
G01X1578140Y173382D02*
X1589722Y161800D01*
G01X1566098Y173382D02*
X1578140D01*
G01X1560460Y179020D02*
X1566098Y173382D01*
G01X1543761Y179020D02*
X1560460D01*
G01X1543760Y179019D02*
X1543761Y179020D01*
G01X1543138Y179019D02*
X1543760D01*
G01X1543137Y179020D02*
X1543138Y179019D01*
G01X1542438Y179020D02*
X1543137D01*
G01X1538743Y182715D02*
X1542438Y179020D01*
G01X1538743Y185385D02*
Y182715D01*
G01X1539604Y186246D02*
X1538743Y185385D01*
G01X1539604Y202575D02*
Y186246D01*
G01X1543018Y205989D02*
X1539604Y202575D01*
G01X1543018Y230530D02*
Y205989D01*
G01X1587607Y159800D02*
X1601600D01*
G01X1575607Y171800D02*
X1587607Y159800D01*
G01X1571500Y171800D02*
X1575607D01*
G01X1570331Y170631D02*
X1571500Y171800D01*
G01X1563103Y170631D02*
X1570331D01*
G01X1559710Y174024D02*
X1563103Y170631D01*
G01X1556701Y174024D02*
X1559710D01*
G01X1553209Y177516D02*
X1556701Y174024D01*
G01X1544385Y177516D02*
X1553209D01*
G01X1544384Y177515D02*
X1544385Y177516D01*
G01X1543762Y177515D02*
X1544384D01*
G01X1543761Y177514D02*
X1543762Y177515D01*
G01X1543139Y177514D02*
X1543761D01*
G01X1543138Y177513D02*
X1543139Y177514D01*
G01X1542516Y177513D02*
X1543138D01*
G01X1542513Y177516D02*
X1542516Y177513D01*
G01X1541814Y177516D02*
X1542513D01*
G01X1537238Y182092D02*
X1541814Y177516D01*
G01X1537238Y182892D02*
Y182092D01*
G01X1537237Y182893D02*
X1537238Y182892D01*
G01X1537237Y184139D02*
Y182893D01*
G01X1537238Y184140D02*
X1537237Y184139D01*
G01X1537238Y185386D02*
Y184140D01*
G01X1537239Y185387D02*
X1537238Y185386D01*
G01X1537239Y186009D02*
Y185387D01*
G01X1538100Y186870D02*
X1537239Y186009D01*
G01X1538100Y203199D02*
Y186870D01*
G01X1541269Y206368D02*
X1538100Y203199D01*
G01X1541269Y229475D02*
Y206368D01*
G01X1553596Y205793D02*
Y247804D01*
G01X1550487Y202684D02*
X1553596Y205793D01*
G01X1550487Y200796D02*
Y202684D01*
G01X1547091Y197400D02*
X1550487Y200796D01*
G01X1546000Y197400D02*
X1547091D01*
G01X1585729Y185533D02*
X1593420Y177842D01*
G01X1549537Y185533D02*
X1585729D01*
G01X1543548Y191522D02*
X1549537Y185533D01*
G01X1543548Y201009D02*
Y191522D01*
G01X1550597Y208058D02*
X1543548Y201009D01*
G01X1550597Y246882D02*
Y208058D01*
G01X1552702Y206769D02*
X1545910Y199977D01*
G01X1552702Y247498D02*
Y206769D01*
G01X1562150Y160700D02*
X1579800D01*
G01X1549328Y253172D02*
X1554400Y248100D01*
G01X1549328Y276780D02*
Y253172D01*
G01X1542634Y283474D02*
X1549328Y276780D01*
G01X1529778Y250411D02*
X1527361Y252828D01*
G01X1529778Y246805D02*
Y250411D01*
G01X1531500Y245083D02*
X1529778Y246805D01*
G01X1531500Y242644D02*
Y245083D01*
G01X1528400Y239544D02*
X1531500Y242644D01*
G01X1528400Y233410D02*
Y239544D01*
G01X1535617Y234063D02*
X1540517Y229163D01*
G01X1535617Y237033D02*
Y234063D01*
G01X1538997Y240413D02*
X1535617Y237033D01*
G01X1538997Y253343D02*
Y240413D01*
G01X1528820Y263520D02*
X1538997Y253343D01*
G01X1528820Y275671D02*
Y263520D01*
G01X1529985Y276836D02*
X1528820Y275671D01*
G01X1529985Y281981D02*
Y276836D01*
G01X1552132Y278356D02*
X1550572Y279916D01*
G01X1552132Y254368D02*
Y278356D01*
G01X1564824Y241676D02*
X1552132Y254368D01*
G01X1548464Y228207D02*
X1545090Y224833D01*
G01X1548464Y239169D02*
Y228207D01*
G01X1545495Y242138D02*
X1548464Y239169D01*
G01X1545495Y245609D02*
Y242138D01*
G01X1540501Y250603D02*
X1545495Y245609D01*
G01X1540501Y253967D02*
Y250603D01*
G01X1530324Y264144D02*
X1540501Y253967D01*
G01X1530324Y275046D02*
Y264144D01*
G01X1532241Y276963D02*
X1530324Y275046D01*
G01X1532241Y288559D02*
Y276963D01*
G01X1529233Y277148D02*
Y281669D01*
G01X1528068Y275983D02*
X1529233Y277148D01*
G01X1528068Y263208D02*
Y275983D01*
G01X1538245Y253031D02*
X1528068Y263208D01*
G01X1538245Y241025D02*
Y253031D01*
G01X1534704Y237484D02*
X1538245Y241025D01*
G01X1534704Y226306D02*
Y237484D01*
G01X1536576Y224434D02*
X1534704Y226306D01*
G01X1578128Y242392D02*
X1594981Y225539D01*
G01X1578128Y253316D02*
Y242392D01*
G01X1572692Y258752D02*
X1578128Y253316D01*
G01X1569632Y258752D02*
X1572692D01*
G01X1567840Y256960D02*
X1569632Y258752D01*
G01X1565970Y256960D02*
X1567840D01*
G01X1565140Y257790D02*
X1565970Y256960D01*
G01X1565140Y259440D02*
Y257790D01*
G01X1564080Y260500D02*
X1565140Y259440D01*
G01X1558744Y260500D02*
X1564080D01*
G01X1557396Y261848D02*
X1558744Y260500D01*
G01X1557396Y278244D02*
Y261848D01*
G01X1568331Y289179D02*
X1557396Y278244D01*
G01X1559556Y277348D02*
X1574008Y291800D01*
G01X1559556Y262936D02*
Y277348D01*
G01X1559832Y262660D02*
X1559556Y262936D01*
G01X1572380Y262660D02*
X1559832D01*
G01X1580700Y254340D02*
X1572380Y262660D01*
G01X1580700Y251300D02*
Y254340D01*
G01X1582509Y249491D02*
X1580700Y251300D01*
G01X1590491Y249491D02*
X1582509D01*
G01X1527386Y229462D02*
Y226771D01*
G01X1529905Y231981D02*
X1527386Y229462D01*
G01X1529905Y234384D02*
Y231981D01*
G01X1529904Y234385D02*
X1529905Y234384D01*
G01X1529904Y238920D02*
Y234385D01*
G01X1533837Y242853D02*
X1529904Y238920D01*
G01X1533837Y248480D02*
Y242853D01*
G01X1527985Y254332D02*
X1533837Y248480D01*
G01X1537008Y273008D02*
Y288922D01*
G01X1533568Y269568D02*
X1537008Y273008D01*
G01X1533568Y263944D02*
Y269568D01*
G01X1542653Y254859D02*
X1533568Y263944D01*
G01X1542653Y253196D02*
Y254859D01*
G01X1549445Y246404D02*
X1542653Y253196D01*
G01X1537972Y233836D02*
Y236000D01*
G01X1542021Y229787D02*
X1537972Y233836D01*
G01X1527800Y278700D02*
X1527657D01*
G01Y278557D02*
X1527800Y278700D01*
G01X1527657Y277202D02*
Y278557D01*
G01X1537093Y241503D02*
Y252536D01*
G01X1533160Y237570D02*
X1537093Y241503D01*
G01X1533160Y235735D02*
Y237570D01*
G01X1533161Y235734D02*
X1533160Y235735D01*
G01X1533161Y227690D02*
Y235734D01*
G01X1530296Y224825D02*
X1533161Y227690D01*
G01X1530296Y221282D02*
Y224825D01*
G01X1528207Y219193D02*
X1530296Y221282D01*
G01X1566328Y242429D02*
Y228060D01*
G01X1561300Y247457D02*
X1566328Y242429D01*
G01X1561300Y252400D02*
Y247457D01*
G01X1553636Y260064D02*
X1561300Y252400D01*
G01X1553636Y279804D02*
Y260064D01*
G01X1552884Y278668D02*
X1551324Y280228D01*
G01X1552884Y254716D02*
Y278668D01*
G01X1565576Y242024D02*
X1552884Y254716D01*
G01X1565576Y227748D02*
Y242024D01*
G01X1530580Y250673D02*
X1527673Y253580D01*
G01X1530580Y247146D02*
Y250673D01*
G01X1532285Y245441D02*
X1530580Y247146D01*
G01X1532285Y242365D02*
Y245441D01*
G01X1529152Y239232D02*
X1532285Y242365D01*
G01X1529152Y232740D02*
Y239232D01*
G01X1528816Y256336D02*
X1527164D01*
G01X1535841Y249311D02*
X1528816Y256336D01*
G01X1535841Y242022D02*
Y249311D01*
G01X1531908Y238089D02*
X1535841Y242022D01*
G01X1531908Y235216D02*
Y238089D01*
G01X1531909Y235215D02*
X1531908Y235216D01*
G01X1531909Y228209D02*
Y235215D01*
G01X1577376Y253004D02*
Y218289D01*
G01X1573000Y257380D02*
X1577376Y253004D01*
G01X1570071Y257380D02*
X1573000D01*
G01X1568067Y255376D02*
X1570071Y257380D01*
G01X1562800Y255376D02*
X1568067D01*
G01X1556644Y261532D02*
X1562800Y255376D01*
G01X1556644Y278556D02*
Y261532D01*
G01X1567579Y289491D02*
X1556644Y278556D01*
G01X1528254Y228703D02*
Y226575D01*
G01X1530657Y231106D02*
X1528254Y228703D01*
G01X1530657Y234696D02*
Y231106D01*
G01X1530656Y234697D02*
X1530657Y234696D01*
G01X1530656Y238608D02*
Y234697D01*
G01X1534589Y242541D02*
X1530656Y238608D01*
G01X1534589Y248792D02*
Y242541D01*
G01X1528297Y255084D02*
X1534589Y248792D01*
G01X1570500Y255800D02*
X1571876D01*
G01X1569324Y254624D02*
X1570500Y255800D01*
G01X1562488Y254624D02*
X1569324D01*
G01X1555892Y261220D02*
X1562488Y254624D01*
G01X1555892Y278868D02*
Y261220D01*
G01X1566820Y289796D02*
X1555892Y278868D01*
G01X1554388Y279492D02*
X1555332Y280436D01*
G01X1554388Y260596D02*
Y279492D01*
G01X1561864Y253120D02*
X1554388Y260596D01*
G01X1563504Y253120D02*
X1561864D01*
G01X1565688Y250936D02*
X1563504Y253120D01*
G01X1565688Y244601D02*
Y250936D01*
G01X1570318Y239971D02*
X1565688Y244601D01*
G01X1570318Y238116D02*
Y239971D01*
G01X1550580Y277712D02*
X1544042Y284250D01*
G01X1550580Y253720D02*
Y277712D01*
G01X1555700Y248600D02*
X1550580Y253720D01*
G01X1539100Y272406D02*
Y295471D01*
G01X1535472Y268778D02*
X1539100Y272406D01*
G01X1535472Y264734D02*
Y268778D01*
G01X1544562Y255644D02*
X1535472Y264734D01*
G01X1544562Y253981D02*
Y255644D01*
G01X1551349Y247194D02*
X1544562Y253981D01*
G01X1555140Y279180D02*
X1556280Y280320D01*
G01X1555140Y260908D02*
Y279180D01*
G01X1562176Y253872D02*
X1555140Y260908D01*
G01X1563816Y253872D02*
X1562176D01*
G01X1566440Y251248D02*
X1563816Y253872D01*
G01X1566440Y245660D02*
Y251248D01*
G01X1572700Y239400D02*
X1566440Y245660D01*
G01X1540846Y232702D02*
X1543018Y230530D01*
G01X1540846Y244611D02*
Y232702D01*
G01X1541325Y245090D02*
X1540846Y244611D01*
G01X1536384Y234360D02*
X1541269Y229475D01*
G01X1536384Y236660D02*
Y234360D01*
G01X1539749Y240025D02*
X1536384Y236660D01*
G01X1539749Y253655D02*
Y240025D01*
G01X1529572Y263832D02*
X1539749Y253655D01*
G01X1529572Y275359D02*
Y263832D01*
G01X1530737Y276524D02*
X1529572Y275359D01*
G01X1530737Y282293D02*
Y276524D01*
G01X1548576Y275024D02*
X1541882Y281718D01*
G01X1548576Y252824D02*
Y275024D01*
G01X1553596Y247804D02*
X1548576Y252824D01*
G01X1543810Y253669D02*
X1550597Y246882D01*
G01X1543810Y255332D02*
Y253669D01*
G01X1534720Y264422D02*
X1543810Y255332D01*
G01X1534720Y269090D02*
Y264422D01*
G01X1538160Y272530D02*
X1534720Y269090D01*
G01X1538160Y289400D02*
Y272530D01*
G01X1527226Y247825D02*
Y249353D01*
G01X1578880Y242704D02*
X1596488Y225096D01*
G01X1578880Y254120D02*
Y242704D01*
G01X1571748Y261252D02*
X1578880Y254120D01*
G01X1559248Y261252D02*
X1571748D01*
G01X1558148Y262352D02*
X1559248Y261252D01*
G01X1558148Y277932D02*
Y262352D01*
G01X1572237Y292021D02*
X1558148Y277932D01*
G01X1545714Y254486D02*
X1552702Y247498D01*
G01X1545714Y256122D02*
Y254486D01*
G01X1536747Y265089D02*
X1545714Y256122D01*
G01X1536747Y268423D02*
Y265089D01*
G01X1540400Y272076D02*
X1536747Y268423D01*
G01X1540400Y304840D02*
Y272076D01*
G01X1542634Y304734D02*
Y283474D01*
G01X1538598Y308770D02*
X1542634Y304734D01*
G01X1538598Y311923D02*
Y308770D01*
G01X1536372Y314149D02*
X1538598Y311923D01*
G01X1536372Y321372D02*
Y314149D01*
G01X1536775Y321775D02*
X1536372Y321372D01*
G01X1536775Y337350D02*
Y321775D01*
G01X1530998Y343127D02*
X1536775Y337350D01*
G01X1527092Y284874D02*
X1529985Y281981D01*
G01X1527092Y288552D02*
Y284874D01*
G01X1529228Y290688D02*
X1527092Y288552D01*
G01X1529228Y298019D02*
Y290688D01*
G01X1540402Y335013D02*
Y350107D01*
G01X1541534Y333881D02*
X1540402Y335013D01*
G01X1541534Y327120D02*
Y333881D01*
G01X1540402Y325988D02*
X1541534Y327120D01*
G01X1540402Y323199D02*
Y325988D01*
G01X1542088Y321513D02*
X1540402Y323199D01*
G01X1542088Y309557D02*
Y321513D01*
G01X1545676Y305969D02*
X1542088Y309557D01*
G01X1545676Y294759D02*
Y305969D01*
G01X1550572Y289863D02*
X1545676Y294759D01*
G01X1550572Y279916D02*
Y289863D01*
G01X1531484Y289316D02*
X1532241Y288559D01*
G01X1531484Y298212D02*
Y289316D01*
G01X1531485Y298213D02*
X1531484Y298212D01*
G01X1531485Y298835D02*
Y298213D01*
G01X1531484Y298836D02*
X1531485Y298835D01*
G01X1531484Y298955D02*
Y298836D01*
G01X1530016Y300423D02*
X1531484Y298955D01*
G01X1530016Y304985D02*
Y300423D01*
G01X1531331Y306300D02*
X1530016Y304985D01*
G01X1531331Y306922D02*
Y306300D01*
G01X1531330Y306923D02*
X1531331Y306922D01*
G01X1531330Y310623D02*
Y306923D01*
G01X1531331Y310624D02*
X1531330Y310623D01*
G01X1531331Y311246D02*
Y310624D01*
G01X1531330Y311247D02*
X1531331Y311246D01*
G01X1531330Y313509D02*
Y311247D01*
G01X1527193Y317646D02*
X1531330Y313509D01*
G01X1527193Y323322D02*
Y317646D01*
G01X1531250Y327379D02*
X1527193Y323322D01*
G01X1531250Y333057D02*
Y327379D01*
G01X1561424Y340347D02*
Y343413D01*
G01X1561600Y340171D02*
X1561424Y340347D01*
G01X1561600Y330776D02*
Y340171D01*
G01X1560024Y329200D02*
X1561600Y330776D01*
G01X1567780Y338656D02*
Y346980D01*
G01X1570868Y335568D02*
X1567780Y338656D01*
G01X1570868Y329648D02*
Y335568D01*
G01X1564411Y323191D02*
X1570868Y329648D01*
G01X1564411Y315210D02*
Y323191D01*
G01X1585472Y306569D02*
X1589670Y302371D01*
G01X1585472Y309180D02*
Y306569D01*
G01X1587884Y311592D02*
X1585472Y309180D01*
G01X1587884Y323590D02*
Y311592D01*
G01X1591554Y327260D02*
X1587884Y323590D01*
G01X1528476Y291000D02*
Y297707D01*
G01X1568331Y298901D02*
Y289179D01*
G01X1571485Y302055D02*
X1568331Y298901D01*
G01X1571485Y305593D02*
Y302055D01*
G01X1572454Y306562D02*
X1571485Y305593D01*
G01X1572454Y314624D02*
Y306562D01*
G01X1568154Y318924D02*
X1572454Y314624D01*
G01X1568154Y323446D02*
Y318924D01*
G01X1573124Y328416D02*
X1568154Y323446D01*
G01X1573124Y336647D02*
Y328416D01*
G01X1572374Y337397D02*
X1573124Y336647D01*
G01X1572374Y338703D02*
Y337397D01*
G01X1573778Y340107D02*
X1572374Y338703D01*
G01X1573778Y363536D02*
Y340107D01*
G01X1578342Y336047D02*
X1581090Y338795D01*
G01X1578342Y328410D02*
Y336047D01*
G01X1573779Y323847D02*
X1578342Y328410D01*
G01X1573779Y319474D02*
Y323847D01*
G01X1576788Y316465D02*
X1573779Y319474D01*
G01X1576788Y311067D02*
Y316465D01*
G01X1579339Y308516D02*
X1576788Y311067D01*
G01X1579339Y305343D02*
Y308516D01*
G01X1576824Y302828D02*
X1579339Y305343D01*
G01X1576824Y290374D02*
Y302828D01*
G01X1578054Y289144D02*
X1576824Y290374D01*
G01X1583356Y289144D02*
X1578054D01*
G01X1595970Y276530D02*
X1583356Y289144D01*
G01X1576074Y328310D02*
Y359600D01*
G01X1572371Y324607D02*
X1576074Y328310D01*
G01X1572371Y318890D02*
Y324607D01*
G01X1574616Y316645D02*
X1572371Y318890D01*
G01X1574616Y304604D02*
Y316645D01*
G01X1574008Y303996D02*
X1574616Y304604D01*
G01X1574008Y291800D02*
Y303996D01*
G01X1583000Y287500D02*
X1594480Y276020D01*
G01X1577500Y287500D02*
X1583000D01*
G01X1576500Y288500D02*
X1577500Y287500D01*
G01X1576500Y288706D02*
Y288500D01*
G01X1575416Y289790D02*
X1576500Y288706D01*
G01X1575416Y303412D02*
Y289790D01*
G01X1577486Y305482D02*
X1575416Y303412D01*
G01X1577486Y307621D02*
Y305482D01*
G01X1527296Y338075D02*
X1527058D01*
G01X1532002Y333369D02*
X1527296Y338075D01*
G01X1532002Y327187D02*
Y333369D01*
G01X1532001Y327186D02*
X1532002Y327187D01*
G01X1532001Y327066D02*
Y327186D01*
G01X1530748Y325813D02*
X1532001Y327066D01*
G01X1530748Y323566D02*
Y325813D01*
G01X1532082Y322232D02*
X1530748Y323566D01*
G01X1532082Y311559D02*
Y322232D01*
G01X1532083Y311558D02*
X1532082Y311559D01*
G01X1532083Y310936D02*
Y311558D01*
G01X1532084Y310935D02*
X1532083Y310936D01*
G01X1532084Y310313D02*
Y310935D01*
G01X1532082Y310311D02*
X1532084Y310313D01*
G01X1532082Y307235D02*
Y310311D01*
G01X1532083Y307234D02*
X1532082Y307235D01*
G01X1532083Y305988D02*
Y307234D01*
G01X1530768Y304673D02*
X1532083Y305988D01*
G01X1530768Y300735D02*
Y304673D01*
G01X1532236Y299267D02*
X1530768Y300735D01*
G01X1532236Y299148D02*
Y299267D01*
G01X1532238Y299146D02*
X1532236Y299148D01*
G01X1532238Y298524D02*
Y299146D01*
G01X1532237Y298523D02*
X1532238Y298524D01*
G01X1532237Y297901D02*
Y298523D01*
G01X1532236Y297900D02*
X1532237Y297901D01*
G01X1532236Y293772D02*
Y297900D01*
G01X1533248Y292760D02*
X1532236Y293772D01*
G01X1533248Y292682D02*
Y292760D01*
G01X1537008Y288922D02*
X1533248Y292682D01*
G01X1583523Y323185D02*
X1589854Y329516D01*
G01X1583523Y317998D02*
Y323185D01*
G01X1582940Y317415D02*
X1583523Y317998D01*
G01X1582940Y315632D02*
Y317415D01*
G01X1584600Y313972D02*
X1582940Y315632D01*
G01X1584600Y311600D02*
Y313972D01*
G01X1583004Y310004D02*
X1584600Y311600D01*
G01X1583004Y306469D02*
Y310004D01*
G01X1583003Y306468D02*
X1583004Y306469D01*
G01X1583003Y305846D02*
Y306468D01*
G01X1587370Y301479D02*
X1583003Y305846D01*
G01X1587370Y294086D02*
Y301479D01*
G01X1589921Y291535D02*
X1587370Y294086D01*
G01X1554580Y280748D02*
X1553636Y279804D01*
G01X1554580Y284504D02*
Y280748D01*
G01X1558800Y288724D02*
X1554580Y284504D01*
G01X1560153Y288724D02*
X1558800D01*
G01X1561332Y289903D02*
X1560153Y288724D01*
G01X1561332Y297984D02*
Y289903D01*
G01X1557265Y302051D02*
X1561332Y297984D01*
G01X1557265Y311961D02*
Y302051D01*
G01X1558920Y313616D02*
X1557265Y311961D01*
G01X1558920Y323754D02*
Y313616D01*
G01X1555737Y326937D02*
X1558920Y323754D01*
G01X1555737Y330237D02*
Y326937D01*
G01X1559800Y334300D02*
X1555737Y330237D01*
G01X1559800Y347071D02*
Y334300D01*
G01X1554752Y295328D02*
X1554775D01*
G01X1551324Y291900D02*
X1554752Y295328D01*
G01X1551324Y280228D02*
Y291900D01*
G01X1588636Y316235D02*
X1597868Y325467D01*
G01X1588636Y311280D02*
Y316235D01*
G01X1586224Y308868D02*
X1588636Y311280D01*
G01X1586224Y306881D02*
Y308868D01*
G01X1590440Y302665D02*
X1586224Y306881D01*
G01X1586474Y289459D02*
X1606090Y269843D01*
G01X1586474Y290726D02*
Y289459D01*
G01X1584289Y292911D02*
X1586474Y290726D01*
G01X1584289Y295831D02*
Y292911D01*
G01X1582680Y297440D02*
X1584289Y295831D01*
G01X1582110Y297440D02*
X1582680D01*
G01X1580290Y299260D02*
X1582110Y297440D01*
G01X1580290Y303238D02*
Y299260D01*
G01X1581500Y304448D02*
X1580290Y303238D01*
G01X1581500Y305221D02*
Y304448D01*
G01X1581499Y305222D02*
X1581500Y305221D01*
G01X1581499Y307092D02*
Y305222D01*
G01X1581500Y307093D02*
X1581499Y307092D01*
G01X1581500Y310107D02*
Y307093D01*
G01X1578970Y312637D02*
X1581500Y310107D01*
G01X1578970Y322952D02*
Y312637D01*
G01X1586122Y330104D02*
X1578970Y322952D01*
G01X1586122Y341378D02*
Y330104D01*
G01X1567579Y299213D02*
Y289491D01*
G01X1570344Y301978D02*
X1567579Y299213D01*
G01X1570344Y305626D02*
Y301978D01*
G01X1571702Y306984D02*
X1570344Y305626D01*
G01X1571702Y314312D02*
Y306984D01*
G01X1567402Y318612D02*
X1571702Y314312D01*
G01X1567402Y323758D02*
Y318612D01*
G01X1572372Y328728D02*
X1567402Y323758D01*
G01X1572372Y336192D02*
Y328728D01*
G01X1571622Y336942D02*
X1572372Y336192D01*
G01X1571622Y339062D02*
Y336942D01*
G01X1573026Y340466D02*
X1571622Y339062D01*
G01X1573026Y363774D02*
Y340466D01*
G01X1588345Y330268D02*
X1590829D01*
G01X1579750Y321673D02*
X1588345Y330268D01*
G01X1579750Y312921D02*
Y321673D01*
G01X1582252Y310419D02*
X1579750Y312921D01*
G01X1582252Y306781D02*
Y310419D01*
G01X1582251Y306780D02*
X1582252Y306781D01*
G01X1582251Y305534D02*
Y306780D01*
G01X1582252Y305533D02*
X1582251Y305534D01*
G01X1582252Y304136D02*
Y305533D01*
G01X1581050Y302934D02*
X1582252Y304136D01*
G01X1581050Y299619D02*
Y302934D01*
G01X1582476Y298193D02*
X1581050Y299619D01*
G01X1583047Y298193D02*
X1582476D01*
G01X1585041Y296199D02*
X1583047Y298193D01*
G01X1585041Y293223D02*
Y296199D01*
G01X1587456Y290808D02*
X1585041Y293223D01*
G01X1587456Y289541D02*
Y290808D01*
G01X1606860Y270137D02*
X1587456Y289541D01*
G01X1584599Y306378D02*
X1588910Y302067D01*
G01X1584599Y307000D02*
Y306378D01*
G01X1584600Y307001D02*
X1584599Y307000D01*
G01X1584600Y309372D02*
Y307001D01*
G01X1587132Y311904D02*
X1584600Y309372D01*
G01X1587132Y317920D02*
Y311904D01*
G01X1585962Y319090D02*
X1587132Y317920D01*
G01X1585962Y323496D02*
Y319090D01*
G01X1590478Y328012D02*
X1585962Y323496D01*
G01X1529113Y333066D02*
Y329208D01*
G01X1566820Y308690D02*
Y289796D01*
G01X1564427Y311083D02*
X1566820Y308690D01*
G01X1562072Y327003D02*
X1569211Y334142D01*
G01X1562072Y300390D02*
Y327003D01*
G01X1562084Y300378D02*
X1562072Y300390D01*
G01X1562084Y289591D02*
Y300378D01*
G01X1560207Y287714D02*
X1562084Y289591D01*
G01X1558900Y287714D02*
X1560207D01*
G01X1555332Y284146D02*
X1558900Y287714D01*
G01X1555332Y280436D02*
Y284146D01*
G01X1538477Y337640D02*
X1531582Y344535D01*
G01X1538477Y334742D02*
Y337640D01*
G01X1539982Y333237D02*
X1538477Y334742D01*
G01X1539982Y328020D02*
Y333237D01*
G01X1538477Y326515D02*
X1539982Y328020D01*
G01X1538477Y321706D02*
Y326515D01*
G01X1537824Y321053D02*
X1538477Y321706D01*
G01X1537824Y317927D02*
Y321053D01*
G01X1540500Y315251D02*
X1537824Y317927D01*
G01X1540500Y308950D02*
Y315251D01*
G01X1544042Y305408D02*
X1540500Y308950D01*
G01X1544042Y284250D02*
Y305408D01*
G01X1553600Y282400D02*
X1552900Y281700D01*
G01X1553600Y284600D02*
Y282400D01*
G01X1557457Y288457D02*
X1553600Y284600D01*
G01X1557457Y299432D02*
Y288457D01*
G01X1548807Y308082D02*
X1557457Y299432D01*
G01X1548807Y308381D02*
Y308082D01*
G01X1548668Y308520D02*
X1548807Y308381D01*
G01X1548668Y310965D02*
Y308520D01*
G01X1550799Y313096D02*
X1548668Y310965D01*
G01X1550799Y317702D02*
Y313096D01*
G01X1549573Y318928D02*
X1550799Y317702D01*
G01X1549573Y320920D02*
Y318928D01*
G01X1550493Y321840D02*
X1549573Y320920D01*
G01X1550493Y326436D02*
Y321840D01*
G01X1549900Y327029D02*
X1550493Y326436D01*
G01X1549900Y343000D02*
Y327029D01*
G01X1527370Y338827D02*
X1527369Y338828D01*
G01X1527608Y338827D02*
X1527370D01*
G01X1532754Y333681D02*
X1527608Y338827D01*
G01X1532754Y326875D02*
Y333681D01*
G01X1532753Y326874D02*
X1532754Y326875D01*
G01X1532753Y326754D02*
Y326874D01*
G01X1531500Y325501D02*
X1532753Y326754D01*
G01X1531500Y323878D02*
Y325501D01*
G01X1532834Y322544D02*
X1531500Y323878D01*
G01X1532834Y311871D02*
Y322544D01*
G01X1532835Y311870D02*
X1532834Y311871D01*
G01X1532835Y311248D02*
Y311870D01*
G01X1532836Y311247D02*
X1532835Y311248D01*
G01X1532836Y310001D02*
Y311247D01*
G01X1532834Y309999D02*
X1532836Y310001D01*
G01X1532834Y307851D02*
Y309999D01*
G01X1534426Y306259D02*
X1532834Y307851D01*
G01X1534426Y300145D02*
Y306259D01*
G01X1539100Y295471D02*
X1534426Y300145D01*
G01X1586975Y336125D02*
X1590176Y332924D01*
G01X1586975Y341589D02*
Y336125D01*
G01X1562824Y325155D02*
X1569211Y331542D01*
G01X1562824Y300800D02*
Y325155D01*
G01X1562836Y300788D02*
X1562824Y300800D01*
G01X1562836Y289259D02*
Y300788D01*
G01X1560453Y286876D02*
X1562836Y289259D01*
G01X1559147Y286876D02*
X1560453D01*
G01X1556280Y284009D02*
X1559147Y286876D01*
G01X1556280Y280320D02*
Y284009D01*
G01X1584655Y323253D02*
X1590166Y328764D01*
G01X1584655Y318015D02*
Y323253D01*
G01X1583903Y317263D02*
X1584655Y318015D01*
G01X1583903Y315890D02*
Y317263D01*
G01X1585352Y314441D02*
X1583903Y315890D01*
G01X1585352Y311196D02*
Y314441D01*
G01X1585356Y311192D02*
X1585352Y311196D01*
G01X1583756Y309592D02*
X1585356Y311192D01*
G01X1583756Y306157D02*
Y309592D01*
G01X1588140Y301773D02*
X1583756Y306157D01*
G01X1588140Y294380D02*
Y301773D01*
G01X1590673Y291847D02*
X1588140Y294380D01*
G01X1530010Y328167D02*
Y333233D01*
G01X1528512Y308983D02*
X1527747Y309748D01*
G01X1528512Y299799D02*
Y308983D01*
G01X1529980Y298331D02*
X1528512Y299799D01*
G01X1529980Y288220D02*
Y298331D01*
G01X1530500Y287700D02*
X1529980Y288220D01*
G01X1530500Y282530D02*
X1530737Y282293D01*
G01X1530500Y287700D02*
Y282530D01*
G01X1536023Y337038D02*
X1530686Y342375D01*
G01X1536023Y322087D02*
Y337038D01*
G01X1535620Y321684D02*
X1536023Y322087D01*
G01X1535620Y313837D02*
Y321684D01*
G01X1537846Y311611D02*
X1535620Y313837D01*
G01X1537846Y308458D02*
Y311611D01*
G01X1541882Y304422D02*
X1537846Y308458D01*
G01X1541882Y281718D02*
Y304422D01*
G01X1587800Y308200D02*
X1591788Y312188D01*
G01X1534400Y293160D02*
X1538160Y289400D01*
G01X1534400Y296029D02*
Y293160D01*
G01X1566910Y318040D02*
Y315117D01*
G01X1566650Y318300D02*
X1566910Y318040D01*
G01X1566650Y324070D02*
Y318300D01*
G01X1571620Y329040D02*
X1566650Y324070D01*
G01X1571620Y335880D02*
Y329040D01*
G01X1568545Y338955D02*
X1571620Y335880D01*
G01X1568545Y356745D02*
Y338955D01*
G01X1572237Y305281D02*
Y292021D01*
G01X1573208Y306252D02*
X1572237Y305281D01*
G01X1573208Y314934D02*
Y306252D01*
G01X1568906Y319236D02*
X1573208Y314934D01*
G01X1568906Y323134D02*
Y319236D01*
G01X1573977Y328205D02*
X1568906Y323134D01*
G01X1573977Y338023D02*
Y328205D01*
G01X1573950Y338050D02*
X1573977Y338023D01*
G01X1585370Y341066D02*
X1579186Y347250D01*
G01X1585370Y330416D02*
Y341066D01*
G01X1578196Y323242D02*
X1585370Y330416D01*
G01X1578196Y312347D02*
Y323242D01*
G01X1580748Y309795D02*
X1578196Y312347D01*
G01X1580748Y307405D02*
Y309795D01*
G01X1580747Y307404D02*
X1580748Y307405D01*
G01X1580747Y304910D02*
Y307404D01*
G01X1580748Y304909D02*
X1580747Y304910D01*
G01X1580748Y304760D02*
Y304909D01*
G01X1579510Y303522D02*
X1580748Y304760D01*
G01X1579510Y296021D02*
Y303522D01*
G01X1581287Y294244D02*
X1579510Y296021D01*
G01X1581287Y293582D02*
Y294244D01*
G01X1603784Y271085D02*
X1581287Y293582D01*
G01X1581924Y301544D02*
X1583500Y303120D01*
G01X1581924Y299828D02*
Y301544D01*
G01X1582806Y298946D02*
X1581924Y299828D01*
G01X1583358Y298946D02*
X1582806D01*
G01X1585793Y296511D02*
X1583358Y298946D01*
G01X1585793Y293535D02*
Y296511D01*
G01X1588388Y290940D02*
X1585793Y293535D01*
G01X1588388Y289673D02*
Y290940D01*
G01X1607630Y270431D02*
X1588388Y289673D01*
G01X1583500Y299965D02*
Y300560D01*
G01X1586545Y296920D02*
X1583500Y299965D01*
G01X1586545Y293847D02*
Y296920D01*
G01X1589169Y291223D02*
X1586545Y293847D01*
G01X1536995Y308245D02*
X1540400Y304840D01*
G01X1536995Y311398D02*
Y308245D01*
G01X1534868Y313525D02*
X1536995Y311398D01*
G01X1534868Y322167D02*
Y313525D01*
G01X1535271Y322570D02*
X1534868Y322167D01*
G01X1535271Y333054D02*
Y322570D01*
G01X1527879Y340446D02*
X1535271Y333054D01*
G01X1527879Y341646D02*
Y340446D01*
G01X1551124Y327088D02*
Y342712D01*
G01X1553256Y324956D02*
X1551124Y327088D01*
G01X1553256Y314489D02*
Y324956D01*
G01X1549420Y310653D02*
X1553256Y314489D01*
G01X1549420Y308832D02*
Y310653D01*
G01X1559500Y298752D02*
X1549420Y308832D01*
G01X1559500Y290300D02*
Y298752D01*
G01X1532755Y384383D02*
X1530872Y382500D01*
G01X1532755Y384925D02*
Y384383D01*
G01X1533674Y385844D02*
X1532755Y384925D01*
G01X1534465Y385844D02*
X1533674D01*
G01X1536275Y387654D02*
X1534465Y385844D01*
G01X1529092Y343127D02*
X1530998D01*
G01X1529829Y362655D02*
Y357051D01*
G01X1563575Y379577D02*
Y380894D01*
G01X1563195Y379197D02*
X1563575Y379577D01*
G01X1563195Y376863D02*
Y379197D01*
G01X1563044Y376712D02*
X1563195Y376863D01*
G01X1563044Y373683D02*
Y376712D01*
G01X1560867Y371506D02*
X1563044Y373683D01*
G01X1560867Y363513D02*
Y371506D01*
G01X1560866Y363512D02*
X1560867Y363513D01*
G01X1560866Y358953D02*
Y363512D01*
G01X1559593Y357680D02*
X1560866Y358953D01*
G01X1554140Y357680D02*
X1559593D01*
G01X1551906Y355446D02*
X1554140Y357680D01*
G01X1546182Y355446D02*
X1551906D01*
G01X1534300Y380598D02*
X1533026Y379324D01*
G01X1534300Y382000D02*
Y380598D01*
G01X1536655Y384355D02*
X1534300Y382000D01*
G01X1536655Y385555D02*
Y384355D01*
G01X1538100Y387000D02*
X1536655Y385555D01*
G01X1538100Y387800D02*
Y387000D01*
G01X1539524Y389224D02*
X1538100Y387800D01*
G01X1540826Y389224D02*
X1539524D01*
G01X1542400Y387650D02*
X1540826Y389224D01*
G01X1542400Y387108D02*
Y387650D01*
G01X1543424Y386084D02*
X1542400Y387108D01*
G01X1546405Y386084D02*
X1543424D01*
G01X1547975Y387654D02*
X1546405Y386084D01*
G01X1585348Y399749D02*
X1587683Y397414D01*
G01X1585348Y404577D02*
Y399749D01*
G01X1536600Y366800D02*
X1534348Y364548D01*
G01X1539900Y366800D02*
X1536600D01*
G01X1540700Y366000D02*
X1539900Y366800D01*
G01X1540700Y350405D02*
Y366000D01*
G01X1540402Y350107D02*
X1540700Y350405D01*
G01X1557426Y365174D02*
X1553450Y369150D01*
G01X1557426Y365166D02*
Y365174D01*
G01X1558950Y363642D02*
X1557426Y365166D01*
G01X1558950Y363050D02*
Y363642D01*
G01X1588823Y363792D02*
X1587684Y362653D01*
G01X1568370Y401174D02*
X1567475D01*
G01X1571372Y398172D02*
X1568370Y401174D01*
G01X1571372Y396938D02*
Y398172D01*
G01X1569866Y395432D02*
X1571372Y396938D01*
G01X1569866Y395126D02*
Y395432D01*
G01X1569805Y395065D02*
X1569866Y395126D01*
G01X1569805Y393763D02*
Y395065D01*
G01X1571430Y392138D02*
X1569805Y393763D01*
G01X1571430Y390210D02*
Y392138D01*
G01X1569805Y388585D02*
X1571430Y390210D01*
G01X1569805Y386935D02*
Y388585D01*
G01X1570680Y386060D02*
X1569805Y386935D01*
G01X1571521Y386060D02*
X1570680D01*
G01X1574228Y383353D02*
X1571521Y386060D01*
G01X1574228Y377871D02*
Y383353D01*
G01X1565287Y368930D02*
X1574228Y377871D01*
G01X1565287Y357213D02*
Y368930D01*
G01X1567041Y355459D02*
X1565287Y357213D01*
G01X1567041Y349030D02*
Y355459D01*
G01X1561424Y343413D02*
X1567041Y349030D01*
G01X1573136Y387654D02*
X1571375D01*
G01X1575162Y385628D02*
X1573136Y387654D01*
G01X1575162Y377378D02*
Y385628D01*
G01X1568810Y371026D02*
X1575162Y377378D01*
G01X1568810Y358450D02*
Y371026D01*
G01X1567793Y357433D02*
X1568810Y358450D01*
G01X1567793Y346993D02*
Y357433D01*
G01X1567780Y346980D02*
X1567793Y346993D01*
G01X1584924Y350875D02*
X1589467Y346332D01*
G01X1584924Y363174D02*
Y350875D01*
G01X1588071Y366321D02*
X1584924Y363174D01*
G01X1588071Y393835D02*
Y366321D01*
G01X1590580Y396344D02*
X1588071Y393835D01*
G01X1576664Y366422D02*
X1573778Y363536D01*
G01X1576664Y391077D02*
Y366422D01*
G01X1574507Y393234D02*
X1576664Y391077D01*
G01X1574507Y416941D02*
Y393234D01*
G01X1580434Y396855D02*
Y406283D01*
G01X1580406Y396827D02*
X1580434Y396855D01*
G01X1580406Y394095D02*
Y396827D01*
G01X1584215Y390286D02*
X1580406Y394095D01*
G01X1584215Y365942D02*
Y390286D01*
G01X1582194Y363921D02*
X1584215Y365942D01*
G01X1582194Y348498D02*
Y363921D01*
G01X1586616Y344076D02*
X1582194Y348498D01*
G01X1589178Y344076D02*
X1586616D01*
G01X1587911Y350996D02*
X1587032D01*
G01X1589565Y352650D02*
X1587911Y350996D01*
G01X1564274Y351545D02*
X1559800Y347071D01*
G01X1564274Y369304D02*
Y351545D01*
G01X1573155Y378185D02*
X1564274Y369304D01*
G01X1573155Y382881D02*
Y378185D01*
G01X1571668Y384368D02*
X1573155Y382881D01*
G01X1570289Y384368D02*
X1571668D01*
G01X1539979Y376287D02*
X1539602Y375910D01*
G01X1539979Y377680D02*
Y376287D01*
G01X1542100Y379801D02*
X1539979Y377680D01*
G01X1542100Y381700D02*
Y379801D01*
G01X1540175Y383625D02*
X1542100Y381700D01*
G01X1540175Y387654D02*
Y383625D01*
G01X1579938Y347562D02*
X1586122Y341378D01*
G01X1579938Y362617D02*
Y347562D01*
G01X1578570Y363985D02*
X1579938Y362617D01*
G01X1578570Y391472D02*
Y363985D01*
G01X1576457Y393585D02*
X1578570Y391472D01*
G01X1576457Y415460D02*
Y393585D01*
G01X1571951Y364849D02*
X1573026Y363774D01*
G01X1571951Y372868D02*
Y364849D01*
G01X1575913Y376830D02*
X1571951Y372868D01*
G01X1575913Y390469D02*
Y376830D01*
G01X1572945Y393437D02*
X1575913Y390469D01*
G01X1572945Y403255D02*
Y393437D01*
G01X1578063Y394185D02*
Y413828D01*
G01X1580078Y392170D02*
X1578063Y394185D01*
G01X1580078Y364604D02*
Y392170D01*
G01X1581442Y363240D02*
X1580078Y364604D01*
G01X1581442Y348186D02*
Y363240D01*
G01X1586305Y343323D02*
X1581442Y348186D01*
G01X1588867Y343323D02*
X1586305D01*
G01X1587240Y345580D02*
X1589991D01*
G01X1583698Y349122D02*
X1587240Y345580D01*
G01X1583698Y363012D02*
Y349122D01*
G01X1585719Y365033D02*
X1583698Y363012D01*
G01X1585719Y391081D02*
Y365033D01*
G01X1584400Y392400D02*
X1585719Y391081D01*
G01X1584400Y394400D02*
Y392400D01*
G01X1585700Y395700D02*
X1584400Y394400D01*
G01X1588198Y395700D02*
X1585700D01*
G01X1589259Y396761D02*
X1588198Y395700D01*
G01X1588194Y360094D02*
X1589223D01*
G01X1586500Y358400D02*
X1588194Y360094D01*
G01X1552000Y377368D02*
X1549734Y375102D01*
G01X1552000Y378798D02*
Y377368D01*
G01X1553445Y380243D02*
X1552000Y378798D01*
G01X1553445Y380785D02*
Y380243D01*
G01X1555395Y382735D02*
X1553445Y380785D01*
G01X1555395Y385505D02*
Y382735D01*
G01X1554000Y386900D02*
X1555395Y385505D01*
G01X1554000Y388200D02*
Y386900D01*
G01X1552870Y389330D02*
X1554000Y388200D01*
G01X1548740Y389330D02*
X1552870D01*
G01X1547800Y390270D02*
X1548740Y389330D01*
G01X1547800Y391860D02*
Y390270D01*
G01X1546405Y393255D02*
X1547800Y391860D01*
G01X1546405Y395065D02*
Y393255D01*
G01X1547390Y396050D02*
X1546405Y395065D01*
G01X1550830Y396050D02*
X1547390D01*
G01X1551875Y397095D02*
X1550830Y396050D01*
G01X1551875Y401174D02*
Y397095D01*
G01X1531582Y344535D02*
X1529676D01*
G01X1557117Y370653D02*
X1557116Y370652D01*
G01X1557541Y370653D02*
X1557117D01*
G01X1560051Y373163D02*
X1557541Y370653D01*
G01X1560051Y377562D02*
Y373163D01*
G01X1560838Y378878D02*
G03X1560051Y377562I787J-1364D01*
G01X1562001Y380813D02*
G02X1560838Y378878I-2326J81D01*
G01X1562001Y380975D02*
Y380813D01*
G01X1560838Y382910D02*
G02X1562001Y380975I-1163J-2016D01*
G01X1560051Y384226D02*
G03X1560838Y382910I1574J48D01*
G01X1560051Y384322D02*
Y384226D01*
G01X1560838Y385638D02*
G03X1560051Y384322I787J-1364D01*
G01X1562543Y386622D02*
X1560838Y385638D01*
G01X1563575Y387654D02*
X1562543Y386622D01*
G01X1553200Y346300D02*
X1549900Y343000D01*
G01X1553200Y348600D02*
Y346300D01*
G01X1555300Y350700D02*
X1553200Y348600D01*
G01X1555300Y354189D02*
Y350700D01*
G01X1556634Y355523D02*
X1555300Y354189D01*
G01X1560910Y355523D02*
X1556634D01*
G01X1562770Y357383D02*
X1560910Y355523D01*
G01X1562770Y371283D02*
Y357383D01*
G01X1567123Y375636D02*
X1562770Y371283D01*
G01X1567123Y378564D02*
Y375636D01*
G01X1565901Y379786D02*
X1567123Y378564D01*
G01X1565901Y380975D02*
Y379786D01*
G01X1564738Y382910D02*
G02X1565901Y380975I-1163J-2016D01*
G01X1564738Y385638D02*
G03Y382910I787J-1364D01*
G01X1565860Y387209D02*
G02X1564738Y385638I-2283J445D01*
G01X1565901Y387735D02*
G02X1565860Y387209I-2303J-85D01*
G01X1564738Y389670D02*
G02X1565901Y387735I-1163J-2016D01*
G01X1564738Y392398D02*
G03Y389670I787J-1364D01*
G01X1565901Y394333D02*
G02X1564738Y392398I-2326J81D01*
G01X1565901Y394462D02*
Y394333D01*
G01X1566688Y395778D02*
G03X1565901Y394462I787J-1364D01*
G01X1567470Y396229D02*
X1566688Y395778D01*
G01X1567476Y396229D02*
X1567470D01*
G01X1568132Y396501D02*
G02X1567476Y396229I-656J655D01*
G01X1569425Y397794D02*
X1568132Y396501D01*
G01X1550972Y352446D02*
X1543528D01*
G01X1555201Y356675D02*
X1550972Y352446D01*
G01X1560133Y356675D02*
X1555201D01*
G01X1561618Y358160D02*
X1560133Y356675D01*
G01X1561618Y371194D02*
Y358160D01*
G01X1563955Y373531D02*
X1561618Y371194D01*
G01X1563955Y378498D02*
Y373531D01*
G01X1565149Y379692D02*
X1563955Y378498D01*
G01X1565149Y380894D02*
Y379692D01*
G01X1564803Y381881D02*
G02X1565149Y380894I-1235J-987D01*
G01X1564362Y382259D02*
G02X1564803Y381881I-788J-1365D01*
G01X1564363Y386289D02*
G03X1564362Y382259I1162J-2015D01*
G01X1565122Y387353D02*
G02X1564363Y386289I-1546J300D01*
G01X1565150Y387708D02*
G02X1565122Y387353I-1552J-56D01*
G01X1564362Y389019D02*
G02X1565150Y387708I-787J-1365D01*
G01X1564362Y393050D02*
G03Y389019I1163J-2015D01*
G01X1565149Y394366D02*
G02X1564362Y393050I-1574J48D01*
G01X1565149Y394495D02*
Y394366D01*
G01X1566312Y396430D02*
G03X1565149Y394495I1163J-2016D01*
G01X1566755Y396686D02*
X1566312Y396430D01*
G01X1567454Y397895D02*
G02X1566755Y396686I-1395J0D01*
G01X1567454Y398304D02*
Y397895D01*
G01X1567283Y398717D02*
G02X1567454Y398304I-413J-413D01*
G01X1565145Y400855D02*
X1567283Y398717D01*
G01X1565145Y401887D02*
Y400855D01*
G01X1580690Y347874D02*
X1586975Y341589D01*
G01X1580690Y362929D02*
Y347874D01*
G01X1579322Y364297D02*
X1580690Y362929D01*
G01X1579322Y391862D02*
Y364297D01*
G01X1577311Y393873D02*
X1579322Y391862D01*
G01X1577311Y414411D02*
Y393873D01*
G01X1581638Y402686D02*
Y405592D01*
G01X1581639Y402685D02*
X1581638Y402686D01*
G01X1581639Y402061D02*
Y402685D01*
G01X1583580Y400120D02*
X1581639Y402061D01*
G01X1583580Y392021D02*
Y400120D01*
G01X1584967Y390634D02*
X1583580Y392021D01*
G01X1584967Y365345D02*
Y390634D01*
G01X1582946Y363324D02*
X1584967Y365345D01*
G01X1582946Y348810D02*
Y363324D01*
G01X1586928Y344828D02*
X1582946Y348810D01*
G01X1589679Y344828D02*
X1586928D01*
G01X1578902Y394426D02*
Y410730D01*
G01X1580830Y392498D02*
X1578902Y394426D01*
G01X1580830Y391070D02*
Y392498D01*
G01X1582600Y389300D02*
X1580830Y391070D01*
G01X1557725Y375662D02*
Y377514D01*
G01X1556752Y374689D02*
X1557725Y375662D01*
G01X1556752Y374688D02*
Y374689D01*
G01X1555000Y372936D02*
X1556752Y374688D01*
G01X1554999Y372936D02*
X1555000D01*
G01X1554644Y372581D02*
X1554999Y372936D01*
G01X1530686Y342375D02*
X1528780D01*
G01X1533589Y366542D02*
X1531779Y368352D01*
G01X1533589Y366361D02*
Y366542D01*
G01X1555981Y402810D02*
X1557725Y404554D01*
G01X1539210Y402810D02*
X1555981D01*
G01X1538370Y401970D02*
X1539210Y402810D01*
G01X1538370Y400600D02*
Y401970D01*
G01X1536275Y398505D02*
X1538370Y400600D01*
G01X1536275Y394414D02*
Y398505D01*
G01X1557896Y402011D02*
X1559160Y403275D01*
G01X1557896Y400640D02*
Y402011D01*
G01X1555600Y398344D02*
X1557896Y400640D01*
G01X1555600Y396800D02*
Y398344D01*
G01X1553850Y395050D02*
X1555600Y396800D01*
G01X1553850Y393450D02*
Y395050D01*
G01X1553200Y392800D02*
X1553850Y393450D01*
G01X1549830Y392800D02*
X1553200D01*
G01X1548216Y394414D02*
X1549830Y392800D01*
G01X1547975Y394414D02*
X1548216D01*
G01X1571450Y359650D02*
X1568545Y356745D01*
G01X1588276Y356676D02*
X1586500Y354900D01*
G01X1589911Y356676D02*
X1588276D01*
G01X1575258Y393754D02*
Y415740D01*
G01X1575705Y393307D02*
X1575258Y393754D01*
G01X1575705Y393273D02*
Y393307D01*
G01X1577818Y391160D02*
X1575705Y393273D01*
G01X1577818Y363673D02*
Y391160D01*
G01X1579186Y362305D02*
X1577818Y363673D01*
G01X1579186Y347250D02*
Y362305D01*
G01X1556000Y375000D02*
X1554688Y373688D01*
G01X1556000Y378500D02*
Y375000D01*
G01X1557500Y380000D02*
X1556000Y378500D01*
G01X1557500Y382000D02*
Y380000D01*
G01X1556151Y383349D02*
X1557500Y382000D01*
G01X1556151Y385151D02*
Y383349D01*
G01X1557500Y386500D02*
X1556151Y385151D01*
G01X1557500Y388500D02*
Y386500D01*
G01X1556000Y390000D02*
X1557500Y388500D01*
G01X1556000Y392000D02*
Y390000D01*
G01X1557500Y393500D02*
X1556000Y392000D01*
G01X1557500Y395000D02*
Y393500D01*
G01X1558500Y396000D02*
X1557500Y395000D01*
G01X1559000Y396000D02*
X1558500D01*
G01X1559675Y396675D02*
X1559000Y396000D01*
G01X1559675Y401174D02*
Y396675D01*
G01X1564294Y397794D02*
X1565525D01*
G01X1562000Y395500D02*
X1564294Y397794D01*
G01X1562000Y394000D02*
Y395500D01*
G01X1560000Y392000D02*
X1562000Y394000D01*
G01X1560000Y390000D02*
Y392000D01*
G01X1561500Y388500D02*
X1560000Y390000D01*
G01X1561500Y386889D02*
Y388500D01*
G01X1560462Y386290D02*
X1561500Y386889D01*
G01X1559299Y384355D02*
G02X1560462Y386290I2326J-81D01*
G01X1559299Y384193D02*
Y384355D01*
G01X1560462Y382258D02*
G02X1559299Y384193I1163J2016D01*
G01X1561249Y380942D02*
G03X1560462Y382258I-1574J-48D01*
G01X1561249Y380846D02*
Y380942D01*
G01X1560462Y379530D02*
G03X1561249Y380846I-787J1364D01*
G01X1559299Y377595D02*
G02X1560462Y379530I2326J-81D01*
G01X1559299Y377514D02*
Y377595D01*
G01X1559295Y377518D02*
X1559299Y377514D01*
G01X1559295Y373895D02*
Y377518D01*
G01X1556804Y371404D02*
X1559295Y373895D01*
G01X1566316Y391034D02*
X1565525D01*
G01X1569045Y388305D02*
X1566316Y391034D01*
G01X1569045Y385774D02*
Y388305D01*
G01X1568719Y385448D02*
X1569045Y385774D01*
G01X1568719Y382738D02*
Y385448D01*
G01X1569045Y382412D02*
X1568719Y382738D01*
G01X1569045Y379684D02*
Y382412D01*
G01X1568014Y378653D02*
X1569045Y379684D01*
G01X1568014Y374107D02*
Y378653D01*
G01X1563523Y369616D02*
X1568014Y374107D01*
G01X1563523Y368635D02*
Y369616D01*
G01X1563522Y368635D02*
X1563523D01*
G01X1563522Y356082D02*
Y368635D01*
G01X1554696Y347256D02*
X1563522Y356082D01*
G01X1554696Y346284D02*
Y347256D01*
G01X1551124Y342712D02*
X1554696Y346284D01*
G01X1574126Y458520D02*
X1584385Y468779D01*
G01X1574126Y453575D02*
Y458520D01*
G01X1587671Y406900D02*
X1585348Y404577D01*
G01X1591200Y406900D02*
X1587671D01*
G01X1573150Y454526D02*
X1571949Y453325D01*
G01X1573150Y458608D02*
Y454526D01*
G01X1584073Y469531D02*
X1573150Y458608D01*
G01X1539246Y460446D02*
X1538225D01*
G01X1542100Y463300D02*
X1539246Y460446D01*
G01X1542100Y464400D02*
Y463300D01*
G01X1544100Y466400D02*
X1542100Y464400D01*
G01X1584233Y426667D02*
X1574507Y416941D01*
G01X1584233Y427947D02*
Y426667D01*
G01X1582825Y448975D02*
X1592175D01*
G01X1576425Y442575D02*
X1582825Y448975D01*
G01X1586127Y411976D02*
X1587000D01*
G01X1580434Y406283D02*
X1586127Y411976D01*
G01X1582321Y421324D02*
X1576457Y415460D01*
G01X1585560Y421324D02*
X1582321D01*
G01X1570021Y406179D02*
X1572945Y403255D01*
G01X1562786Y406179D02*
X1570021D01*
G01X1561031Y407934D02*
X1562786Y406179D01*
G01X1559675Y407934D02*
X1561031D01*
G01X1573568Y418223D02*
X1581939Y426594D01*
G01X1573568Y412869D02*
Y418223D01*
G01X1570232Y409533D02*
X1573568Y412869D01*
G01X1561274Y409533D02*
X1570232D01*
G01X1559675Y407934D02*
X1561274Y409533D01*
G01X1588112Y418948D02*
X1594976Y425812D01*
G01X1583183Y418948D02*
X1588112D01*
G01X1578063Y413828D02*
X1583183Y418948D01*
G01X1585418Y464538D02*
X1596430D01*
G01X1584200Y463320D02*
X1585418Y464538D01*
G01X1584200Y462610D02*
Y463320D01*
G01X1564998Y434450D02*
X1563950Y433402D01*
G01X1588102Y434450D02*
X1564998D01*
G01X1590037Y432515D02*
X1588102Y434450D01*
G01X1582600Y419700D02*
X1577311Y414411D01*
G01X1587800Y419700D02*
X1582600D01*
G01X1591824Y423724D02*
X1587800Y419700D01*
G01X1587814Y408120D02*
X1591147Y411453D01*
G01X1584166Y408120D02*
X1587814D01*
G01X1581638Y405592D02*
X1584166Y408120D01*
G01X1586400Y417300D02*
X1588984D01*
G01X1584282Y415182D02*
X1586400Y417300D01*
G01X1583354Y415182D02*
X1584282D01*
G01X1578902Y410730D02*
X1583354Y415182D01*
G01X1583250Y450500D02*
X1575750Y443000D01*
G01X1591939Y450500D02*
X1583250D01*
G01X1583353Y423835D02*
X1587559D01*
G01X1575258Y415740D02*
X1583353Y423835D01*
G01X1578550Y454483D02*
X1573317Y449250D01*
G01X1578550Y460270D02*
Y454483D01*
G01X1580370Y462090D02*
X1578550Y460270D01*
G01X1584385Y468779D02*
X1598537D01*
G01X1534020Y514051D02*
Y511930D01*
G01X1534275Y514306D02*
X1534020Y514051D01*
G01X1534276Y514306D02*
X1534275D01*
G01X1541494Y521524D02*
X1534276Y514306D01*
G01X1581567Y521524D02*
X1541494D01*
G01X1585635Y517456D02*
X1581567Y521524D01*
G01X1604449Y517456D02*
X1585635D01*
G01X1548615Y490266D02*
X1547600Y489251D01*
G01X1548615Y490267D02*
Y490266D01*
G01X1553224Y494876D02*
X1548615Y490267D01*
G01X1553225Y494876D02*
X1553224D01*
G01X1553341Y494992D02*
X1553225Y494876D01*
G01X1555858Y494992D02*
X1553341D01*
G01X1558280Y497414D02*
X1555858Y494992D01*
G01X1558280Y509531D02*
Y497414D01*
G01X1560857Y512108D02*
X1558280Y509531D01*
G01X1577421Y512108D02*
X1560857D01*
G01X1581655Y507874D02*
X1577421Y512108D01*
G01X1615508Y507874D02*
X1581655D01*
G01X1598225Y469531D02*
X1584073D01*
G01X1544100Y468000D02*
Y466400D01*
G01X1546200Y470100D02*
X1544100Y468000D01*
G01X1546200Y471700D02*
Y470100D01*
G01X1548200Y473700D02*
X1546200Y471700D01*
G01X1548200Y475000D02*
Y473700D01*
G01X1550100Y476900D02*
X1548200Y475000D01*
G01X1550100Y478100D02*
Y476900D01*
G01X1551600Y479600D02*
X1550100Y478100D01*
G01X1551600Y480800D02*
Y479600D01*
G01X1553700Y482900D02*
X1551600Y480800D01*
G01X1553700Y484500D02*
Y482900D01*
G01X1555900Y486700D02*
X1553700Y484500D01*
G01X1555900Y488900D02*
Y486700D01*
G01X1566200Y499200D02*
X1555900Y488900D01*
G01X1566200Y500800D02*
Y499200D01*
G01X1566800Y501400D02*
X1566200Y500800D01*
G01X1566800Y506800D02*
Y501400D01*
G01X1569700Y509700D02*
X1566800Y506800D01*
G01X1575900Y509700D02*
X1569700D01*
G01X1582700Y502900D02*
X1575900Y509700D01*
G01X1653556Y502900D02*
X1582700D01*
G01X1584201Y514000D02*
X1606263D01*
G01X1580133Y518068D02*
X1584201Y514000D01*
G01X1543368Y518068D02*
X1580133D01*
G01X1538400Y513100D02*
X1543368Y518068D01*
G01X1538400Y493787D02*
Y513100D01*
G01X1533159Y488546D02*
X1538400Y493787D01*
G01X1583682Y512748D02*
X1606782D01*
G01X1579614Y516816D02*
X1583682Y512748D01*
G01X1543887Y516816D02*
X1579614D01*
G01X1539730Y512659D02*
X1543887Y516816D01*
G01X1539730Y491749D02*
Y512659D01*
G01X1536794Y488813D02*
X1539730Y491749D01*
G01X1530425Y471392D02*
X1531063Y472030D01*
G01X1530425Y467206D02*
Y471392D01*
G01X1581177Y506722D02*
X1616210D01*
G01X1576943Y510956D02*
X1581177Y506722D01*
G01X1561335Y510956D02*
X1576943D01*
G01X1559480Y509101D02*
X1561335Y510956D01*
G01X1559480Y497550D02*
Y509101D01*
G01X1556054Y494124D02*
X1559480Y497550D01*
G01X1553536Y494124D02*
X1556054D01*
G01X1549368Y489956D02*
X1553536Y494124D01*
G01X1582775Y510254D02*
X1608457D01*
G01X1578617Y514412D02*
X1582775Y510254D01*
G01X1554097Y514412D02*
X1578617D01*
G01X1551229Y511544D02*
X1554097Y514412D01*
G01X1551229Y510590D02*
Y511544D01*
G01X1551230Y510589D02*
X1551229Y510590D01*
G01X1551230Y498830D02*
Y510589D01*
G01X1543700Y491300D02*
X1551230Y498830D01*
G01X1543700Y488770D02*
Y491300D01*
G01X1584679Y515152D02*
X1605405D01*
G01X1580611Y519220D02*
X1584679Y515152D01*
G01X1542890Y519220D02*
X1580611D01*
G01X1537100Y513430D02*
X1542890Y519220D01*
G01X1537100Y493551D02*
Y513430D01*
G01X1532675Y489126D02*
X1537100Y493551D01*
G01X1583063Y511596D02*
X1607260D01*
G01X1579095Y515564D02*
X1583063Y511596D01*
G01X1549552Y515564D02*
X1579095D01*
G01X1545710Y511722D02*
X1549552Y515564D01*
G01X1545710Y494577D02*
Y511722D01*
G01X1541215Y490082D02*
X1545710Y494577D01*
G01X1534325Y470864D02*
X1535179Y471718D01*
G01X1534325Y467206D02*
Y470864D01*
G01X1535800Y495619D02*
X1528994Y488813D01*
G01X1535800Y514200D02*
Y495619D01*
G01X1541972Y520372D02*
X1535800Y514200D01*
G01X1581089Y520372D02*
X1541972D01*
G01X1585157Y516304D02*
X1581089Y520372D01*
G01X1604927Y516304D02*
X1585157D01*
G01X1586829Y470511D02*
X1597858D01*
G01X1584970Y472370D02*
X1586829Y470511D01*
G01X1582297Y509102D02*
X1608935D01*
G01X1578139Y513260D02*
X1582297Y509102D01*
G01X1560379Y513260D02*
X1578139D01*
G01X1557128Y510009D02*
X1560379Y513260D01*
G01X1557128Y497899D02*
Y510009D01*
G01X1555946Y496717D02*
X1557128Y497899D01*
G01X1551958Y496717D02*
X1555946D01*
G01X1545418Y490177D02*
X1551958Y496717D01*
G01X1545418Y489353D02*
Y490177D01*
G01X1573233Y587500D02*
X1592399D01*
G01X1569595Y583862D02*
X1573233Y587500D01*
G01X1560947Y583862D02*
X1569595D01*
G01X1555744Y578659D02*
X1560947Y583862D01*
G01X1555744Y562572D02*
Y578659D01*
G01X1553380Y560208D02*
X1555744Y562572D01*
G01X1540783Y560208D02*
X1553380D01*
G01X1536409Y555834D02*
X1540783Y560208D01*
G01X1564393Y584725D02*
X1565389Y585721D01*
G01X1549475Y584725D02*
X1564393D01*
G01X1545640Y588560D02*
X1549475Y584725D01*
G01X1574213Y582313D02*
X1594733D01*
G01X1568800Y576900D02*
X1574213Y582313D01*
G01X1568800Y562300D02*
Y576900D01*
G01X1564604Y558104D02*
X1568800Y562300D01*
G01X1541656Y558104D02*
X1564604D01*
G01X1537282Y553730D02*
X1541656Y558104D01*
G01X1573699Y583500D02*
X1593700D01*
G01X1573099Y582900D02*
X1573699Y583500D01*
G01X1561332Y582900D02*
X1573099D01*
G01X1556696Y578264D02*
X1561332Y582900D01*
G01X1556696Y562177D02*
Y578264D01*
G01X1553775Y559256D02*
X1556696Y562177D01*
G01X1541178Y559256D02*
X1553775D01*
G01X1536804Y554882D02*
X1541178Y559256D01*
G01X1537930Y620308D02*
X1534238Y624000D01*
G01X1540477Y620308D02*
X1537930D01*
G01X1537225Y588560D02*
X1545640D01*
G01X1535565Y590220D02*
X1537225Y588560D01*
G01X1535565Y591658D02*
Y590220D01*
G01X1599526Y976D02*
X1601102Y-600D01*
G01X1597362Y-8756D02*
X1656892D01*
G01X1592710Y-4104D02*
X1597362Y-8756D01*
G01X1599646Y-15204D02*
X1597504Y-17346D01*
G01X1611510Y-15204D02*
X1599646D01*
G01X1615974Y-19668D02*
X1611510Y-15204D01*
G01X1649152Y-19668D02*
X1615974D01*
G01X1649153Y-19669D02*
X1649152Y-19668D01*
G01X1649941Y-19669D02*
X1649153D01*
G01X1649942Y-19670D02*
X1649941Y-19669D01*
G01X1650730Y-19670D02*
X1649942D01*
G01X1594695Y-14252D02*
X1589219Y-19728D01*
G01X1611905Y-14252D02*
X1594695D01*
G01X1616369Y-18716D02*
X1611905Y-14252D01*
G01X1649547Y-18716D02*
X1616369D01*
G01X1649548Y-18717D02*
X1649547Y-18716D01*
G01X1650336Y-18717D02*
X1649548D01*
G01X1650337Y-18716D02*
X1650336Y-18717D01*
G01X1650973Y-18716D02*
X1650337D01*
G01X1597757Y-7804D02*
X1656497D01*
G01X1593105Y-3152D02*
X1597757Y-7804D01*
G01X1598152Y-6852D02*
X1656102D01*
G01X1593500Y-2200D02*
X1598152Y-6852D01*
G01X1599257Y-9708D02*
X1657287D01*
G01X1599256Y-9709D02*
X1599257Y-9708D01*
G01X1598468Y-9709D02*
X1599256D01*
G01X1598467Y-9708D02*
X1598468Y-9709D01*
G01X1596967Y-9708D02*
X1598467D01*
G01X1592315Y-5056D02*
X1596967Y-9708D01*
G01X1594300Y-13300D02*
X1588824Y-18776D01*
G01X1612300Y-13300D02*
X1594300D01*
G01X1616764Y-17764D02*
X1612300Y-13300D01*
G01X1650578Y-17764D02*
X1616764D01*
G01X1623900Y-4059D02*
Y4600D01*
G01X1625541Y-5700D02*
X1623900Y-4059D01*
G01X1655624Y-5700D02*
X1625541D01*
G01X1631405Y92641D02*
X1622046Y102000D01*
G01X1656059Y92641D02*
X1631405D01*
G01X1594874Y123000D02*
X1592678Y125196D01*
G01X1598999Y123000D02*
X1594874D01*
G01X1600345Y121654D02*
X1598999Y123000D01*
G01X1600345Y118522D02*
Y121654D01*
G01X1598300Y116477D02*
X1600345Y118522D01*
G01X1646880Y155570D02*
Y157170D01*
G01X1647490Y154960D02*
X1646880Y155570D01*
G01X1648998Y154960D02*
X1647490D01*
G01X1650061Y156023D02*
X1648998Y154960D01*
G01X1650061Y157209D02*
Y156023D01*
G01X1602551Y148588D02*
X1600944Y150195D01*
G01X1611768Y148588D02*
X1602551D01*
G01X1612157Y148977D02*
X1611768Y148588D01*
G01X1612157Y150639D02*
Y148977D01*
G01X1613246Y151728D02*
X1612157Y150639D01*
G01X1616285Y151728D02*
X1613246D01*
G01X1616288Y151725D02*
X1616285Y151728D01*
G01X1617512Y151725D02*
X1616288D01*
G01X1617515Y151728D02*
X1617512Y151725D01*
G01X1620702Y151728D02*
X1617515D01*
G01X1621651Y152677D02*
X1620702Y151728D01*
G01X1621651Y156254D02*
Y152677D01*
G01X1646618Y151710D02*
X1640500Y157828D01*
G01X1652090Y151710D02*
X1646618D01*
G01X1618468Y154932D02*
X1620100Y153300D01*
G01X1603557Y154932D02*
X1618468D01*
G01X1602468Y156021D02*
X1603557Y154932D01*
G01X1600182Y148562D02*
X1598420Y146800D01*
G01X1645487Y103110D02*
X1648000Y100597D01*
G01X1628151Y103110D02*
X1645487D01*
G01X1626695Y104566D02*
X1628151Y103110D01*
G01X1613031Y104566D02*
X1626695D01*
G01X1608806Y108791D02*
X1613031Y104566D01*
G01X1603016Y108791D02*
X1608806D01*
G01X1601725Y107500D02*
X1603016Y108791D01*
G01X1598463Y107500D02*
X1601725D01*
G01X1597405Y106442D02*
X1598463Y107500D01*
G01X1594335Y106442D02*
X1597405D01*
G01X1590025Y110752D02*
X1594335Y106442D01*
G01X1647988Y97925D02*
X1655634D01*
G01X1643701Y102212D02*
X1647988Y97925D01*
G01X1627985Y102212D02*
X1643701D01*
G01X1626383Y103814D02*
X1627985Y102212D01*
G01X1612719Y103814D02*
X1626383D01*
G01X1608569Y107964D02*
X1612719Y103814D01*
G01X1603256Y107964D02*
X1608569D01*
G01X1601891Y106599D02*
X1603256Y107964D01*
G01X1598677Y106599D02*
X1601891D01*
G01X1597595Y105517D02*
X1598677Y106599D01*
G01X1593630Y105517D02*
X1597595D01*
G01X1589631Y109516D02*
X1593630Y105517D01*
G01X1592084Y133138D02*
X1593241Y134295D01*
G01X1596000Y124000D02*
X1593028Y126972D01*
G01X1601018Y124000D02*
X1596000D01*
G01X1603256Y121762D02*
X1601018Y124000D01*
G01X1603256Y118717D02*
Y121762D01*
G01X1604876Y117097D02*
X1603256Y118717D01*
G01X1617793Y117097D02*
X1604876D01*
G01X1620874Y114016D02*
X1617793Y117097D01*
G01X1634086Y114016D02*
X1620874D01*
G01X1637327Y110775D02*
X1634086Y114016D01*
G01X1649970Y110775D02*
X1637327D01*
G01X1651536Y112341D02*
X1649970Y110775D01*
G01X1605687Y140688D02*
X1602225Y144150D01*
G01X1610591Y140688D02*
X1605687D01*
G01X1600398Y154031D02*
X1604292Y150137D01*
G01X1592133Y103834D02*
X1590814Y105153D01*
G01X1596766Y103834D02*
X1592133D01*
G01X1597932Y102668D02*
X1596766Y103834D01*
G01X1599346Y102668D02*
X1597932D01*
G01X1599347Y102667D02*
X1599346Y102668D01*
G01X1600653Y102667D02*
X1599347D01*
G01X1600654Y102668D02*
X1600653Y102667D01*
G01X1600899Y102668D02*
X1600654D01*
G01X1601946Y103715D02*
X1600899Y102668D01*
G01X1602104Y103715D02*
X1601946D01*
G01X1602105Y103716D02*
X1602104Y103715D01*
G01X1610063Y103716D02*
X1602105D01*
G01X1611779Y102000D02*
X1610063Y103716D01*
G01X1622046Y102000D02*
X1611779D01*
G01X1630984Y107697D02*
X1632574Y106107D01*
G01X1630984Y110345D02*
Y107697D01*
G01X1630504Y110825D02*
X1630984Y110345D01*
G01X1625688Y110825D02*
X1630504D01*
G01X1625647Y110866D02*
X1625688Y110825D01*
G01X1622457Y110866D02*
X1625647D01*
G01X1619407Y113916D02*
X1622457Y110866D01*
G01X1605806Y113916D02*
X1619407D01*
G01X1600894Y109004D02*
X1605806Y113916D01*
G01X1597841Y109004D02*
X1600894D01*
G01X1596832Y107995D02*
X1597841Y109004D01*
G01X1595606Y107995D02*
X1596832D01*
G01X1592877Y110724D02*
X1595606Y107995D01*
G01X1592877Y112030D02*
Y110724D01*
G01X1592880Y112033D02*
X1592877Y112030D01*
G01X1592880Y114201D02*
Y112033D01*
G01X1590401Y116680D02*
X1592880Y114201D01*
G01X1633682Y104999D02*
X1662189D01*
G01X1632574Y106107D02*
X1633682Y104999D01*
G01X1607401Y146947D02*
X1605954Y145500D01*
G01X1648444Y103902D02*
X1652200Y100146D01*
G01X1628423Y103902D02*
X1648444D01*
G01X1622210Y110115D02*
X1628423Y103902D01*
G01X1622145Y110115D02*
X1622210D01*
G01X1621573Y110687D02*
X1622145Y110115D01*
G01X1603676Y110687D02*
X1621573D01*
G01X1601241Y108252D02*
X1603676Y110687D01*
G01X1598152Y108252D02*
X1601241D01*
G01X1597144Y107244D02*
X1598152Y108252D01*
G01X1595163Y107244D02*
X1597144D01*
G01X1591500Y110907D02*
X1595163Y107244D01*
G01X1591500Y113768D02*
Y110907D01*
G01X1589540Y115728D02*
X1591500Y113768D01*
G01X1632006Y94500D02*
X1655830D01*
G01X1604396Y131444D02*
X1594277Y141563D01*
G01X1604396Y122142D02*
Y131444D01*
G01X1606223Y120315D02*
X1604396Y122142D01*
G01X1617286Y120315D02*
X1606223D01*
G01X1617485Y120116D02*
X1617286Y120315D01*
G01X1617502Y120116D02*
X1617485D01*
G01X1618365Y119253D02*
X1617502Y120116D01*
G01X1618365Y119236D02*
Y119253D01*
G01X1620436Y117165D02*
X1618365Y119236D01*
G01X1633970Y117165D02*
X1620436D01*
G01X1637119Y114016D02*
X1633970Y117165D01*
G01X1651948Y114016D02*
X1637119D01*
G01X1599785Y133015D02*
X1600900Y131900D01*
G01X1599785Y134449D02*
Y133015D01*
G01X1594123Y140111D02*
X1599785Y134449D01*
G01X1590655Y118246D02*
X1598190Y110711D01*
G01X1592824Y104693D02*
X1589153Y108364D01*
G01X1597974Y104693D02*
X1592824D01*
G01X1599100Y105819D02*
X1597974Y104693D01*
G01X1600803Y105819D02*
X1599100D01*
G01X1602069Y104553D02*
X1600803Y105819D01*
G01X1610514Y104553D02*
X1602069D01*
G01X1612126Y102941D02*
X1610514Y104553D01*
G01X1625885Y102941D02*
X1612126D01*
G01X1627465Y101361D02*
X1625885Y102941D01*
G01X1640989Y101361D02*
X1627465D01*
G01X1645601Y96749D02*
X1640989Y101361D01*
G01X1655050Y96749D02*
X1645601D01*
G01X1612255Y151800D02*
X1613741Y153286D01*
G01X1604300Y151800D02*
X1612255D01*
G01X1600966Y155134D02*
X1604300Y151800D01*
G01X1640002Y165884D02*
X1638938D01*
G01X1641477Y164409D02*
X1640002Y165884D01*
G01X1658500Y164409D02*
X1641477D01*
G01X1623791Y171761D02*
X1624966Y172936D01*
G01X1621416Y171761D02*
X1623791D01*
G01X1621241Y171936D02*
X1621416Y171761D01*
G01X1619995Y171936D02*
X1621241D01*
G01X1619993Y171934D02*
X1619995Y171936D01*
G01X1618636Y171934D02*
X1619993D01*
G01X1617102Y170400D02*
X1618636Y171934D01*
G01X1602508Y170400D02*
X1617102D01*
G01X1602066Y169958D02*
X1602508Y170400D01*
G01X1593243Y169958D02*
X1602066D01*
G01X1600921Y164848D02*
X1594281D01*
G01X1601306Y165233D02*
X1600921Y164848D01*
G01X1604254Y165233D02*
X1601306D01*
G01X1606381Y167360D02*
X1604254Y165233D01*
G01X1632226Y167360D02*
X1606381D01*
G01X1635176Y164410D02*
X1632226Y167360D01*
G01X1636199Y164410D02*
X1635176D01*
G01X1637351Y163258D02*
X1636199Y164410D01*
G01X1637351Y162236D02*
Y163258D01*
G01X1638527Y161060D02*
X1637351Y162236D01*
G01X1639549Y161060D02*
X1638527D01*
G01X1640413Y160196D02*
X1639549Y161060D01*
G01X1640413Y159173D02*
Y160196D01*
G01X1641586Y158000D02*
X1640413Y159173D01*
G01X1646050Y158000D02*
X1641586D01*
G01X1646880Y157170D02*
X1646050Y158000D01*
G01X1650852D02*
X1650061Y157209D01*
G01X1637074Y206806D02*
X1635621Y208259D01*
G01X1653975Y206806D02*
X1637074D01*
G01X1650060Y167360D02*
X1651536Y165884D01*
G01X1646540Y167360D02*
X1650060D01*
G01X1644866Y169034D02*
X1646540Y167360D01*
G01X1637566Y169034D02*
X1644866D01*
G01X1635591Y171009D02*
X1637566Y169034D01*
G01X1621104Y171009D02*
X1635591D01*
G01X1620929Y171184D02*
X1621104Y171009D01*
G01X1620307Y171184D02*
X1620929D01*
G01X1620305Y171182D02*
X1620307Y171184D01*
G01X1619572Y171182D02*
X1620305D01*
G01X1619571Y171183D02*
X1619572Y171182D01*
G01X1618949Y171183D02*
X1619571D01*
G01X1617678Y169912D02*
X1618949Y171183D01*
G01X1617677Y169912D02*
X1617678D01*
G01X1617414Y169649D02*
X1617677Y169912D01*
G01X1602820Y169649D02*
X1617414D01*
G01X1602378Y169207D02*
X1602820Y169649D01*
G01X1592544Y169207D02*
X1602378D01*
G01X1633556Y217408D02*
X1650688D01*
G01X1631545Y215397D02*
X1633556Y217408D01*
G01X1622674Y215397D02*
X1631545D01*
G01X1614582Y223489D02*
X1622674Y215397D01*
G01X1623225Y157828D02*
X1621651Y156254D01*
G01X1640500Y157828D02*
X1623225D01*
G01X1613593Y186868D02*
X1615553Y184908D01*
G01X1613403Y186868D02*
X1613593D01*
G01X1594981Y205290D02*
X1613403Y186868D01*
G01X1594981Y225539D02*
Y205290D01*
G01X1650104Y216000D02*
X1651884Y214220D01*
G01X1634500Y216000D02*
X1650104D01*
G01X1629726Y211226D02*
X1634500Y216000D01*
G01X1614577Y211226D02*
X1629726D01*
G01X1613537Y212266D02*
X1614577Y211226D01*
G01X1613537Y217771D02*
Y212266D01*
G01X1612398Y218910D02*
X1613537Y217771D01*
G01X1649876Y202880D02*
X1654956Y197800D01*
G01X1608778Y202880D02*
X1649876D01*
G01X1600690Y210968D02*
X1608778Y202880D01*
G01X1600690Y228898D02*
Y210968D01*
G01X1595730Y165984D02*
X1595291Y166423D01*
G01X1603942Y165984D02*
X1595730D01*
G01X1606856Y168898D02*
X1603942Y165984D01*
G01X1617726Y168898D02*
X1606856D01*
G01X1617829Y169001D02*
X1617726Y168898D01*
G01X1617830Y169001D02*
X1617829D01*
G01X1619260Y170431D02*
X1617830Y169001D01*
G01X1620618Y170431D02*
X1619260D01*
G01X1620842Y170207D02*
X1620618Y170431D01*
G01X1633552Y170207D02*
X1620842D01*
G01X1637263Y166496D02*
X1633552Y170207D01*
G01X1637263Y165473D02*
Y166496D01*
G01X1638327Y164409D02*
X1637263Y165473D01*
G01X1639350Y164409D02*
X1638327D01*
G01X1640600Y163159D02*
X1639350Y164409D01*
G01X1640600Y162164D02*
Y163159D01*
G01X1641590Y161174D02*
X1640600Y162164D01*
G01X1649611Y161174D02*
X1641590D01*
G01X1651172Y162735D02*
X1649611Y161174D01*
G01X1649930Y193067D02*
X1669849D01*
G01X1642269Y200728D02*
X1649930Y193067D01*
G01X1608079Y200728D02*
X1642269D01*
G01X1597961Y210846D02*
X1608079Y200728D01*
G01X1597961Y226891D02*
Y210846D01*
G01X1645241Y172609D02*
X1643662D01*
G01X1647045Y170805D02*
X1645241Y172609D01*
G01X1659495Y170805D02*
X1647045D01*
G01X1601754Y170709D02*
X1593741D01*
G01X1602370Y171325D02*
X1601754Y170709D01*
G01X1616825Y171325D02*
X1602370D01*
G01X1620300Y174800D02*
X1616825Y171325D01*
G01X1635400Y174800D02*
X1620300D01*
G01X1639600Y170600D02*
X1635400Y174800D01*
G01X1644950Y170600D02*
X1639600D01*
G01X1646411Y169139D02*
X1644950Y170600D01*
G01X1651432Y169139D02*
X1646411D01*
G01X1591324Y175474D02*
X1590777D01*
G01X1591548Y175250D02*
X1591324Y175474D01*
G01X1592436Y175250D02*
X1591548D01*
G01X1592437Y175251D02*
X1592436Y175250D01*
G01X1614400Y175251D02*
X1592437D01*
G01X1615363Y174288D02*
X1614400Y175251D01*
G01X1615985Y174288D02*
X1615363D01*
G01X1615986Y174289D02*
X1615985Y174288D01*
G01X1616586Y174289D02*
X1615986D01*
G01X1616587Y174288D02*
X1616586Y174289D01*
G01X1617209Y174288D02*
X1616587D01*
G01X1617210Y174289D02*
X1617209Y174288D01*
G01X1618690Y174289D02*
X1617210D01*
G01X1619934Y175533D02*
X1618690Y174289D01*
G01X1619970Y175533D02*
X1619934D01*
G01X1619988Y175551D02*
X1619970Y175533D01*
G01X1646083Y175551D02*
X1619988D01*
G01X1646101Y175533D02*
X1646083Y175551D01*
G01X1648942Y175533D02*
X1646101D01*
G01X1648943Y175532D02*
X1648942Y175533D01*
G01X1656858Y175532D02*
X1648943D01*
G01X1611761Y216250D02*
X1607338Y220673D01*
G01X1630836Y196102D02*
Y197560D01*
G01X1630814Y196080D02*
X1630836Y196102D01*
G01X1630814Y194608D02*
Y196080D01*
G01X1630836Y194586D02*
X1630814Y194608D01*
G01X1630836Y192677D02*
Y194586D01*
G01X1628321Y190162D02*
X1630836Y192677D01*
G01X1628321Y183754D02*
Y190162D01*
G01X1627326Y182759D02*
X1628321Y183754D01*
G01X1602600Y160700D02*
X1589322D01*
G01X1603153Y161253D02*
X1602600Y160700D01*
G01X1620753Y161253D02*
X1603153D01*
G01X1621600Y162100D02*
X1620753Y161253D01*
G01X1621600Y163300D02*
Y162100D01*
G01X1623276Y164976D02*
X1621600Y163300D01*
G01X1623276Y165798D02*
Y164976D01*
G01X1598006Y196382D02*
Y192421D01*
G01X1594900Y191998D02*
Y198424D01*
G01X1596938Y189960D02*
X1594900Y191998D01*
G01X1601959Y189960D02*
X1596938D01*
G01X1605500Y186419D02*
X1601959Y189960D01*
G01X1605500Y183762D02*
Y186419D01*
G01X1606067Y183195D02*
X1605500Y183762D01*
G01X1616069Y183195D02*
X1606067D01*
G01X1617925Y185051D02*
X1616069Y183195D01*
G01X1617925Y185597D02*
Y185051D01*
G01X1619123Y186795D02*
X1617925Y185597D01*
G01X1622741Y186795D02*
X1619123D01*
G01X1623823Y185713D02*
X1622741Y186795D01*
G01X1623823Y183757D02*
Y185713D01*
G01X1626396Y181184D02*
X1623823Y183757D01*
G01X1628978Y181184D02*
X1626396D01*
G01X1632288Y184494D02*
X1628978Y181184D01*
G01X1632288Y188287D02*
Y184494D01*
G01X1637870Y193869D02*
X1632288Y188287D01*
G01X1637870Y195077D02*
Y193869D01*
G01X1642121Y187284D02*
X1642457Y186948D01*
G01X1638204Y187284D02*
X1642121D01*
G01X1636952Y186032D02*
X1638204Y187284D01*
G01X1636952Y181491D02*
Y186032D01*
G01X1635143Y179682D02*
X1636952Y181491D01*
G01X1625772Y179682D02*
X1635143D01*
G01X1624504Y180950D02*
X1625772Y179682D01*
G01X1619999Y180950D02*
X1624504D01*
G01X1619293Y180244D02*
X1619999Y180950D01*
G01X1619292Y180244D02*
X1619293D01*
G01X1619153Y180105D02*
X1619292Y180244D01*
G01X1617847Y180105D02*
X1619153D01*
G01X1616324Y181628D02*
X1617847Y180105D01*
G01X1611936Y181628D02*
X1616324D01*
G01X1609652Y179344D02*
X1611936Y181628D01*
G01X1605957Y179344D02*
X1609652D01*
G01X1603001Y182300D02*
X1605957Y179344D01*
G01X1592210Y182300D02*
X1603001D01*
G01X1622986Y216149D02*
X1615334Y223801D01*
G01X1631233Y216149D02*
X1622986D01*
G01X1634760Y219676D02*
X1631233Y216149D01*
G01X1647405Y197374D02*
X1647852D01*
G01X1643151Y201628D02*
X1647405Y197374D01*
G01X1608243Y201628D02*
X1643151D01*
G01X1599282Y210589D02*
X1608243Y201628D01*
G01X1599282Y228314D02*
Y210589D01*
G01X1613384Y205061D02*
X1652268D01*
G01X1606176Y212269D02*
X1613384Y205061D01*
G01X1606176Y216269D02*
Y212269D01*
G01X1602850Y219595D02*
X1606176Y216269D01*
G01X1608056Y187609D02*
Y184771D01*
G01X1607023Y216486D02*
X1604068Y219441D01*
G01X1607023Y212486D02*
Y216486D01*
G01X1613696Y205813D02*
X1607023Y212486D01*
G01X1653471Y205813D02*
X1613696D01*
G01X1615362Y217938D02*
Y213507D01*
G01X1603300Y183300D02*
X1593202D01*
G01X1604227Y182373D02*
X1603300Y183300D01*
G01X1605825Y182373D02*
X1604227D01*
G01X1605826Y182372D02*
X1605825Y182373D01*
G01X1611377Y182372D02*
X1605826D01*
G01X1611378Y182373D02*
X1611377Y182372D01*
G01X1611617Y182373D02*
X1611378D01*
G01X1611628Y182384D02*
X1611617Y182373D01*
G01X1616463Y182384D02*
X1611628D01*
G01X1617334Y183255D02*
X1616463Y182384D01*
G01X1623262Y183255D02*
X1617334D01*
G01X1626084Y180433D02*
X1623262Y183255D01*
G01X1629290Y180433D02*
X1626084D01*
G01X1633161Y184304D02*
X1629290Y180433D01*
G01X1633161Y184362D02*
Y184304D01*
G01X1633540Y184741D02*
X1633161Y184362D01*
G01X1633540Y187768D02*
Y184741D01*
G01X1634846Y189074D02*
X1633540Y187768D01*
G01X1672233Y189074D02*
X1634846D01*
G01X1591582Y190140D02*
X1593218Y191776D01*
G01X1629595Y217725D02*
X1627008Y220312D01*
G01X1609965Y178593D02*
X1594332D01*
G01X1612249Y180877D02*
X1609965Y178593D01*
G01X1616012Y180877D02*
X1612249D01*
G01X1617535Y179354D02*
X1616012Y180877D01*
G01X1619465Y179354D02*
X1617535D01*
G01X1619466Y179355D02*
X1619465Y179354D01*
G01X1619467Y179355D02*
X1619466D01*
G01X1620311Y180199D02*
X1619467Y179355D01*
G01X1624192Y180199D02*
X1620311D01*
G01X1625460Y178931D02*
X1624192Y180199D01*
G01X1647232Y178931D02*
X1625460D01*
G01X1651044Y182743D02*
X1647232Y178931D01*
G01X1614712Y176002D02*
X1591860D01*
G01X1615674Y175040D02*
X1614712Y176002D01*
G01X1616898Y175040D02*
X1615674D01*
G01X1618142Y176284D02*
X1616898Y175040D01*
G01X1619658Y176284D02*
X1618142D01*
G01X1619676Y176302D02*
X1619658Y176284D01*
G01X1646395Y176302D02*
X1619676D01*
G01X1646413Y176284D02*
X1646395Y176302D01*
G01X1649254Y176284D02*
X1646413D01*
G01X1649255Y176283D02*
X1649254Y176284D01*
G01X1656546Y176283D02*
X1649255D01*
G01X1648707Y191078D02*
X1670089D01*
G01X1644290Y195495D02*
X1648707Y191078D01*
G01X1644290Y196383D02*
Y195495D01*
G01X1615306Y164300D02*
X1616891Y165885D01*
G01X1602664Y164300D02*
X1615306D01*
G01X1600164Y161800D02*
X1602664Y164300D01*
G01X1589722Y161800D02*
X1600164D01*
G01X1631073Y164300D02*
X1635788Y159585D01*
G01X1625802Y164300D02*
X1631073D01*
G01X1624782Y163280D02*
X1625802Y164300D01*
G01X1624782Y161982D02*
Y163280D01*
G01X1623900Y161100D02*
X1624782Y161982D01*
G01X1622300Y161100D02*
X1623900D01*
G01X1621700Y160500D02*
X1622300Y161100D01*
G01X1621700Y158900D02*
Y160500D01*
G01X1620800Y158000D02*
X1621700Y158900D01*
G01X1603400Y158000D02*
X1620800D01*
G01X1601600Y159800D02*
X1603400Y158000D01*
G01X1650000Y160500D02*
X1650660Y161160D01*
G01X1650000Y158967D02*
Y160500D01*
G01X1648386Y157353D02*
X1650000Y158967D01*
G01X1648386Y156435D02*
Y157353D01*
G01X1650113Y179515D02*
X1651000Y178628D01*
G01X1648879Y179515D02*
X1650113D01*
G01X1647544Y178180D02*
X1648879Y179515D01*
G01X1625148Y178180D02*
X1647544D01*
G01X1623912Y179416D02*
X1625148Y178180D01*
G01X1620591Y179416D02*
X1623912D01*
G01X1619778Y178603D02*
X1620591Y179416D01*
G01X1617223Y178603D02*
X1619778D01*
G01X1615700Y180126D02*
X1617223Y178603D01*
G01X1612562Y180126D02*
X1615700D01*
G01X1610278Y177842D02*
X1612562Y180126D01*
G01X1593420Y177842D02*
X1610278D01*
G01X1646346Y190326D02*
X1671714D01*
G01X1640850Y195822D02*
X1646346Y190326D01*
G01X1640850Y198950D02*
Y195822D01*
G01X1639824Y199976D02*
X1640850Y198950D01*
G01X1606645Y199976D02*
X1639824D01*
G01X1596488Y210133D02*
X1606645Y199976D01*
G01X1596488Y225096D02*
Y210133D01*
G01X1602098Y213574D02*
Y234344D01*
G01X1611540Y204132D02*
X1602098Y213574D01*
G01X1651872Y204132D02*
X1611540D01*
G01X1608175Y216964D02*
X1605220Y219919D01*
G01X1608175Y212964D02*
Y216964D01*
G01X1612273Y208866D02*
X1608175Y212964D01*
G01X1630705Y208866D02*
X1612273D01*
G01X1633139Y211300D02*
X1630705Y208866D01*
G01X1654849Y211300D02*
X1633139D01*
G01X1609127Y217359D02*
X1606172Y220314D01*
G01X1609127Y213359D02*
Y217359D01*
G01X1612668Y209818D02*
X1609127Y213359D01*
G01X1630310Y209818D02*
X1612668D01*
G01X1632744Y212252D02*
X1630310Y209818D01*
G01X1655033Y212252D02*
X1632744D01*
G01X1645034Y278913D02*
X1644121Y279826D01*
G01X1645034Y254761D02*
Y278913D01*
G01X1645035Y254760D02*
X1645034Y254761D01*
G01X1645035Y250385D02*
Y254760D01*
G01X1665964Y229456D02*
X1645035Y250385D01*
G01X1649922Y243360D02*
X1665676Y227606D01*
G01X1649922Y243370D02*
Y243360D01*
G01X1643530Y249762D02*
X1649922Y243370D01*
G01X1643530Y251017D02*
Y249762D01*
G01X1643531Y251018D02*
X1643530Y251017D01*
G01X1643531Y254136D02*
Y251018D01*
G01X1643530Y254137D02*
X1643531Y254136D01*
G01X1643530Y278289D02*
Y254137D01*
G01X1642617Y279202D02*
X1643530Y278289D01*
G01X1642617Y291752D02*
Y279202D01*
G01X1620199Y221064D02*
X1655628D01*
G01X1616838Y224425D02*
X1620199Y221064D01*
G01X1616838Y269735D02*
Y224425D01*
G01X1594434Y292139D02*
X1616838Y269735D01*
G01X1633348Y276123D02*
X1629724Y279747D01*
G01X1633348Y271029D02*
Y276123D01*
G01X1634918Y269459D02*
X1633348Y271029D01*
G01X1634918Y244381D02*
Y269459D01*
G01X1637996Y241303D02*
X1634918Y244381D01*
G01X1645595Y241303D02*
X1637996D01*
G01X1664451Y222447D02*
X1645595Y241303D01*
G01X1639609Y277954D02*
Y280216D01*
G01X1640522Y277041D02*
X1639609Y277954D01*
G01X1640522Y252889D02*
Y277041D01*
G01X1640523Y252888D02*
X1640522Y252889D01*
G01X1640523Y252266D02*
Y252888D01*
G01X1636422Y248165D02*
X1640523Y252266D01*
G01X1636422Y245039D02*
Y248165D01*
G01X1638654Y242807D02*
X1636422Y245039D01*
G01X1646219Y242807D02*
X1638654D01*
G01X1665068Y223958D02*
X1646219Y242807D01*
G01X1638920Y262561D02*
X1637281Y260922D01*
G01X1638920Y271940D02*
Y262561D01*
G01X1638030Y272830D02*
X1638920Y271940D01*
G01X1635752Y272830D02*
X1638030D01*
G01X1634852Y273730D02*
X1635752Y272830D01*
G01X1634852Y278083D02*
Y273730D01*
G01X1634052Y278883D02*
X1634852Y278083D01*
G01X1634052Y281415D02*
Y278883D01*
G01X1614582Y268799D02*
Y223489D01*
G01X1592177Y291204D02*
X1614582Y268799D01*
G01X1650047Y252642D02*
X1664660Y238029D01*
G01X1650047Y256839D02*
Y252642D01*
G01X1650046Y256840D02*
X1650047Y256839D01*
G01X1650046Y280992D02*
Y256840D01*
G01X1612398Y235661D02*
Y218910D01*
G01X1606849Y241210D02*
X1612398Y235661D01*
G01X1595970Y265911D02*
Y276530D01*
G01X1597112Y264769D02*
X1595970Y265911D01*
G01X1597112Y264706D02*
Y264769D01*
G01X1600537Y261281D02*
X1597112Y264706D01*
G01X1600552Y261281D02*
X1600537D01*
G01X1597200Y232388D02*
X1600690Y228898D01*
G01X1597200Y238188D02*
Y232388D01*
G01X1597201Y238188D02*
X1597200D01*
G01X1597422Y256422D02*
X1590491Y249491D01*
G01X1598028Y256422D02*
X1597422D01*
G01X1615481Y278743D02*
X1596790Y297434D01*
G01X1617129Y278743D02*
X1615481D01*
G01X1620609Y275263D02*
X1617129Y278743D01*
G01X1620609Y274017D02*
Y275263D01*
G01X1620608Y274016D02*
X1620609Y274017D01*
G01X1620608Y271285D02*
Y274016D01*
G01X1621898Y269995D02*
X1620608Y271285D01*
G01X1621898Y266253D02*
Y269995D01*
G01X1621897Y266252D02*
X1621898Y266253D01*
G01X1621897Y261983D02*
Y266252D01*
G01X1625380Y258500D02*
X1621897Y261983D01*
G01X1625380Y255031D02*
Y258500D01*
G01X1627024Y253387D02*
X1625380Y255031D01*
G01X1594648Y230204D02*
X1597961Y226891D01*
G01X1594648Y251648D02*
Y230204D01*
G01X1596000Y253000D02*
X1594648Y251648D01*
G01X1597118Y253000D02*
X1596000D01*
G01X1600000Y255882D02*
X1597118Y253000D01*
G01X1600000Y258552D02*
Y255882D01*
G01X1594480Y264072D02*
X1600000Y258552D01*
G01X1594480Y276020D02*
Y264072D01*
G01X1644035Y237543D02*
X1662988Y218590D01*
G01X1638932Y237543D02*
X1644035D01*
G01X1638931Y237542D02*
X1638932Y237543D01*
G01X1636437Y237542D02*
X1638931D01*
G01X1631120Y242859D02*
X1636437Y237542D01*
G01X1631120Y267380D02*
Y242859D01*
G01X1628500Y270000D02*
X1631120Y267380D01*
G01X1628500Y275651D02*
Y270000D01*
G01X1625964Y278187D02*
X1628500Y275651D01*
G01X1625964Y280741D02*
Y278187D01*
G01X1634804Y279195D02*
X1636684Y277315D01*
G01X1634804Y281727D02*
Y279195D01*
G01X1611870Y268319D02*
X1589921Y290268D01*
G01X1611870Y263908D02*
Y268319D01*
G01X1611466Y263504D02*
X1611870Y263908D01*
G01X1611466Y248106D02*
Y263504D01*
G01X1608950Y245590D02*
X1611466Y248106D01*
G01X1607850Y245590D02*
X1608950D01*
G01X1604300Y242040D02*
X1607850Y245590D01*
G01X1604300Y238877D02*
Y242040D01*
G01X1607338Y235839D02*
X1604300Y238877D01*
G01X1607338Y220673D02*
Y235839D01*
G01X1617590Y270047D02*
X1595186Y292451D01*
G01X1617590Y224737D02*
Y270047D01*
G01X1620511Y221816D02*
X1617590Y224737D01*
G01X1622690Y221816D02*
X1620511D01*
G01X1626124Y225250D02*
X1622690Y221816D01*
G01X1615169Y277991D02*
X1595990Y297170D01*
G01X1616817Y277991D02*
X1615169D01*
G01X1619857Y274951D02*
X1616817Y277991D01*
G01X1619857Y274329D02*
Y274951D01*
G01X1619856Y274328D02*
X1619857Y274329D01*
G01X1619856Y270973D02*
Y274328D01*
G01X1621146Y269683D02*
X1619856Y270973D01*
G01X1621146Y266565D02*
Y269683D01*
G01X1621145Y266564D02*
X1621146Y266565D01*
G01X1621145Y262543D02*
Y266564D01*
G01X1621143Y262541D02*
X1621145Y262543D01*
G01X1621143Y261657D02*
Y262541D01*
G01X1624590Y258210D02*
X1621143Y261657D01*
G01X1624590Y253211D02*
Y258210D01*
G01X1629596Y248205D02*
X1624590Y253211D01*
G01X1629596Y243319D02*
Y248205D01*
G01X1636129Y236786D02*
X1629596Y243319D01*
G01X1643728Y236786D02*
X1636129D01*
G01X1662721Y217793D02*
X1643728Y236786D01*
G01X1615334Y269111D02*
X1592930Y291515D01*
G01X1615334Y223801D02*
Y269111D01*
G01X1655952Y219676D02*
X1634760D01*
G01X1624460Y276855D02*
Y280117D01*
G01X1621500Y273895D02*
X1624460Y276855D01*
G01X1621500Y271620D02*
Y273895D01*
G01X1622918Y270202D02*
X1621500Y271620D01*
G01X1622918Y262052D02*
Y270202D01*
G01X1627043Y257927D02*
X1622918Y262052D01*
G01X1627043Y256900D02*
Y257927D01*
G01X1595400Y232196D02*
X1599282Y228314D01*
G01X1595400Y239651D02*
Y232196D01*
G01X1602414Y246665D02*
X1595400Y239651D01*
G01X1602414Y261992D02*
Y246665D01*
G01X1598983Y265423D02*
X1602414Y261992D01*
G01X1598983Y267583D02*
Y265423D01*
G01X1601870Y270470D02*
X1598983Y267583D01*
G01X1602850Y234656D02*
Y219595D01*
G01X1600292Y237214D02*
X1602850Y234656D01*
G01X1600292Y242415D02*
Y237214D01*
G01X1604186Y246309D02*
X1600292Y242415D01*
G01X1604186Y259928D02*
Y246309D01*
G01X1606090Y261832D02*
X1604186Y259928D01*
G01X1606090Y269843D02*
Y261832D01*
G01X1606860Y261538D02*
Y270137D01*
G01X1604938Y259616D02*
X1606860Y261538D01*
G01X1604938Y245975D02*
Y259616D01*
G01X1601044Y242081D02*
X1604938Y245975D01*
G01X1601044Y237526D02*
Y242081D01*
G01X1604068Y234502D02*
X1601044Y237526D01*
G01X1604068Y219441D02*
Y234502D01*
G01X1645787Y250697D02*
X1666276Y230208D01*
G01X1645787Y255072D02*
Y250697D01*
G01X1645786Y255073D02*
X1645787Y255072D01*
G01X1645786Y279225D02*
Y255073D01*
G01X1644873Y280138D02*
X1645786Y279225D01*
G01X1613806Y219494D02*
X1615362Y217938D01*
G01X1613806Y268511D02*
Y219494D01*
G01X1591425Y290892D02*
X1613806Y268511D01*
G01X1637192Y227999D02*
X1643106Y233913D01*
G01X1627053Y227999D02*
X1637192D01*
G01X1622668Y232384D02*
X1627053Y227999D01*
G01X1622668Y250200D02*
Y232384D01*
G01X1623780Y251312D02*
X1622668Y250200D01*
G01X1623780Y256580D02*
Y251312D01*
G01X1623773Y256587D02*
X1623780Y256580D01*
G01X1623773Y257957D02*
Y256587D01*
G01X1620391Y261339D02*
X1623773Y257957D01*
G01X1620391Y262853D02*
Y261339D01*
G01X1620393Y262855D02*
X1620391Y262853D01*
G01X1620393Y266876D02*
Y262855D01*
G01X1620394Y266877D02*
X1620393Y266876D01*
G01X1620394Y269371D02*
Y266877D01*
G01X1619104Y270661D02*
X1620394Y269371D01*
G01X1619104Y274396D02*
Y270661D01*
G01X1616261Y277239D02*
X1619104Y274396D01*
G01X1614857Y277239D02*
X1616261D01*
G01X1595140Y296956D02*
X1614857Y277239D01*
G01X1644907Y233913D02*
X1643106D01*
G01X1661779Y217041D02*
X1644907Y233913D01*
G01X1616086Y269423D02*
X1593682Y291827D01*
G01X1616086Y224113D02*
Y269423D01*
G01X1619887Y220312D02*
X1616086Y224113D01*
G01X1627008Y220312D02*
X1619887D01*
G01X1647291Y251321D02*
X1664947Y233665D01*
G01X1647291Y255696D02*
Y251321D01*
G01X1647290Y255697D02*
X1647291Y255696D01*
G01X1647290Y279849D02*
Y255697D01*
G01X1635670Y255933D02*
X1637281Y254322D01*
G01X1635670Y269771D02*
Y255933D01*
G01X1634100Y271341D02*
X1635670Y269771D01*
G01X1634100Y277771D02*
Y271341D01*
G01X1633300Y278571D02*
X1634100Y277771D01*
G01X1633300Y278842D02*
Y278571D01*
G01X1633299Y278843D02*
X1633300Y278842D01*
G01X1633299Y279465D02*
Y278843D01*
G01X1633300Y279466D02*
X1633299Y279465D01*
G01X1633300Y281103D02*
Y279466D01*
G01X1648043Y251633D02*
X1663993Y235683D01*
G01X1648043Y256008D02*
Y251633D01*
G01X1648042Y256009D02*
X1648043Y256008D01*
G01X1648042Y280161D02*
Y256009D01*
G01X1628972Y279435D02*
Y282988D01*
G01X1632596Y275811D02*
X1628972Y279435D01*
G01X1632596Y270717D02*
Y275811D01*
G01X1634166Y269147D02*
X1632596Y270717D01*
G01X1634166Y244069D02*
Y269147D01*
G01X1637684Y240551D02*
X1634166Y244069D01*
G01X1645283Y240551D02*
X1637684D01*
G01X1664193Y221641D02*
X1645283Y240551D01*
G01X1625212Y277875D02*
Y280429D01*
G01X1626291Y276796D02*
X1625212Y277875D01*
G01X1626291Y273309D02*
Y276796D01*
G01X1641113Y278578D02*
Y283643D01*
G01X1642026Y277665D02*
X1641113Y278578D01*
G01X1642026Y253513D02*
Y277665D01*
G01X1642027Y253512D02*
X1642026Y253513D01*
G01X1642027Y251642D02*
Y253512D01*
G01X1641113Y250728D02*
X1642027Y251642D01*
G01X1641113Y245404D02*
Y250728D01*
G01X1641956Y244561D02*
X1641113Y245404D01*
G01X1646593Y244561D02*
X1641956D01*
G01X1665286Y225868D02*
X1646593Y244561D01*
G01X1612690Y268563D02*
X1590673Y290580D01*
G01X1612690Y263664D02*
Y268563D01*
G01X1612218Y263192D02*
X1612690Y263664D01*
G01X1612218Y246582D02*
Y263192D01*
G01X1609051Y243415D02*
X1612218Y246582D01*
G01X1628220Y279123D02*
Y283300D01*
G01X1631844Y275499D02*
X1628220Y279123D01*
G01X1631844Y270405D02*
Y275499D01*
G01X1633414Y268835D02*
X1631844Y270405D01*
G01X1633414Y243757D02*
Y268835D01*
G01X1637373Y239798D02*
X1633414Y243757D01*
G01X1637995Y239798D02*
X1637373D01*
G01X1637996Y239799D02*
X1637995Y239798D01*
G01X1644971Y239799D02*
X1637996D01*
G01X1663924Y220846D02*
X1644971Y239799D01*
G01X1626917Y227071D02*
X1650685D01*
G01X1621916Y232072D02*
X1626917Y227071D01*
G01X1621916Y250596D02*
Y232072D01*
G01X1623020Y251700D02*
X1621916Y250596D01*
G01X1623020Y257550D02*
Y251700D01*
G01X1619639Y260931D02*
X1623020Y257550D01*
G01X1619639Y263165D02*
Y260931D01*
G01X1619641Y263167D02*
X1619639Y263165D01*
G01X1619641Y267188D02*
Y263167D01*
G01X1619642Y267189D02*
X1619641Y267188D01*
G01X1619642Y269059D02*
Y267189D01*
G01X1595938Y292763D02*
X1619642Y269059D01*
G01X1641865Y278890D02*
Y289903D01*
G01X1642778Y277977D02*
X1641865Y278890D01*
G01X1642778Y253825D02*
Y277977D01*
G01X1642779Y253824D02*
X1642778Y253825D01*
G01X1642779Y251330D02*
Y253824D01*
G01X1642778Y251329D02*
X1642779Y251330D01*
G01X1642778Y249450D02*
Y251329D01*
G01X1649170Y243058D02*
X1642778Y249450D01*
G01X1649170Y243048D02*
Y243058D01*
G01X1665525Y226693D02*
X1649170Y243048D01*
G01X1618674Y228400D02*
X1621164Y225910D01*
G01X1618674Y256276D02*
Y228400D01*
G01X1620058Y257660D02*
X1618674Y256276D01*
G01X1620240Y257660D02*
X1620058D01*
G01X1615793Y279495D02*
X1597560Y297728D01*
G01X1622000Y279495D02*
X1615793D01*
G01X1596690Y294241D02*
X1617498Y273433D01*
G01X1646538Y279537D02*
X1645625Y280450D01*
G01X1646538Y255385D02*
Y279537D01*
G01X1646539Y255384D02*
X1646538Y255385D01*
G01X1646539Y251009D02*
Y255384D01*
G01X1665486Y232062D02*
X1646539Y251009D01*
G01X1648795Y252123D02*
X1664418Y236500D01*
G01X1648795Y256320D02*
Y252123D01*
G01X1648794Y256321D02*
X1648795Y256320D01*
G01X1648794Y280473D02*
Y256321D01*
G01X1603784Y269988D02*
Y271085D01*
G01X1602353Y268557D02*
X1603784Y269988D01*
G01X1602353Y266724D02*
Y268557D01*
G01X1603167Y265910D02*
X1602353Y266724D01*
G01X1603167Y246354D02*
Y265910D01*
G01X1599540Y242727D02*
X1603167Y246354D01*
G01X1599540Y236902D02*
Y242727D01*
G01X1602098Y234344D02*
X1599540Y236902D01*
G01X1607630Y260880D02*
Y270431D01*
G01X1605730Y258980D02*
X1607630Y260880D01*
G01X1605730Y245598D02*
Y258980D01*
G01X1602396Y242264D02*
X1605730Y245598D01*
G01X1602396Y242195D02*
Y242264D01*
G01X1602196Y241995D02*
X1602396Y242195D01*
G01X1602196Y238004D02*
Y241995D01*
G01X1605220Y234980D02*
X1602196Y238004D01*
G01X1605220Y219919D02*
Y234980D01*
G01X1622740Y224968D02*
X1621164Y223392D01*
G01X1622740Y226759D02*
Y224968D01*
G01X1620000Y229499D02*
X1622740Y226759D01*
G01X1620000Y253887D02*
Y229499D01*
G01X1620250Y254137D02*
X1620000Y253887D01*
G01X1620250Y254741D02*
Y254137D01*
G01X1639770Y276729D02*
X1636684Y279815D01*
G01X1639770Y252577D02*
Y276729D01*
G01X1635670Y248477D02*
X1639770Y252577D01*
G01X1635670Y244694D02*
Y248477D01*
G01X1638309Y242055D02*
X1635670Y244694D01*
G01X1645907Y242055D02*
X1638309D01*
G01X1664763Y223199D02*
X1645907Y242055D01*
G01X1608400Y270725D02*
X1589169Y289956D01*
G01X1608400Y257190D02*
Y270725D01*
G01X1610540Y255050D02*
X1608400Y257190D01*
G01X1610540Y248244D02*
Y255050D01*
G01X1608638Y246342D02*
X1610540Y248244D01*
G01X1607538Y246342D02*
X1608638D01*
G01X1603148Y241952D02*
X1607538Y246342D01*
G01X1603148Y238399D02*
Y241952D01*
G01X1606172Y235375D02*
X1603148Y238399D01*
G01X1606172Y220314D02*
Y235375D01*
G01X1640361Y278266D02*
Y282581D01*
G01X1641274Y277353D02*
X1640361Y278266D01*
G01X1641274Y253201D02*
Y277353D01*
G01X1641275Y253200D02*
X1641274Y253201D01*
G01X1641275Y251954D02*
Y253200D01*
G01X1640361Y251040D02*
X1641275Y251954D01*
G01X1640361Y244999D02*
Y251040D01*
G01X1641800Y243560D02*
X1640361Y244999D01*
G01X1646530Y243560D02*
X1641800D01*
G01X1665185Y224905D02*
X1646530Y243560D01*
G01X1644282Y250074D02*
X1665998Y228358D01*
G01X1644282Y250705D02*
Y250074D01*
G01X1644283Y250706D02*
X1644282Y250705D01*
G01X1644283Y254448D02*
Y250706D01*
G01X1644282Y254449D02*
X1644283Y254448D01*
G01X1644282Y278601D02*
Y254449D01*
G01X1643369Y279514D02*
X1644282Y278601D01*
G01X1643369Y296141D02*
Y279514D01*
G01X1644347Y238295D02*
X1663300Y219342D01*
G01X1638620Y238295D02*
X1644347D01*
G01X1638619Y238294D02*
X1638620Y238295D01*
G01X1636749Y238294D02*
X1638619D01*
G01X1631910Y243133D02*
X1636749Y238294D01*
G01X1631910Y268211D02*
Y243133D01*
G01X1630340Y269781D02*
X1631910Y268211D01*
G01X1630340Y274875D02*
Y269781D01*
G01X1626716Y278499D02*
X1630340Y274875D01*
G01X1626716Y281053D02*
Y278499D01*
G01X1644659Y239047D02*
X1663612Y220094D01*
G01X1638308Y239047D02*
X1644659D01*
G01X1638307Y239046D02*
X1638308Y239047D01*
G01X1637061Y239046D02*
X1638307D01*
G01X1632662Y243445D02*
X1637061Y239046D01*
G01X1632662Y268523D02*
Y243445D01*
G01X1631092Y270093D02*
X1632662Y268523D01*
G01X1631092Y275187D02*
Y270093D01*
G01X1627468Y278811D02*
X1631092Y275187D01*
G01X1627468Y281365D02*
Y278811D01*
G01X1644121Y297831D02*
X1636861Y305091D01*
G01X1644121Y279826D02*
Y297831D01*
G01X1636925Y297444D02*
X1642617Y291752D01*
G01X1594434Y293406D02*
Y292139D01*
G01X1592010Y295830D02*
X1594434Y293406D01*
G01X1592010Y309554D02*
Y295830D01*
G01X1593988Y311532D02*
X1592010Y309554D01*
G01X1593988Y312640D02*
Y311532D01*
G01X1593987Y312641D02*
X1593988Y312640D01*
G01X1593987Y316383D02*
Y312641D01*
G01X1602500Y324896D02*
X1593987Y316383D01*
G01X1602500Y331028D02*
Y324896D01*
G01X1602776Y331304D02*
X1602500Y331028D01*
G01X1623819Y339017D02*
Y384281D01*
G01X1633348Y329488D02*
X1623819Y339017D01*
G01X1633348Y327012D02*
Y329488D01*
G01X1631048Y324712D02*
X1633348Y327012D01*
G01X1631048Y317188D02*
Y324712D01*
G01X1632548Y315688D02*
X1631048Y317188D01*
G01X1632548Y294913D02*
Y315688D01*
G01X1630574Y292939D02*
X1632548Y294913D01*
G01X1630574Y283526D02*
Y292939D01*
G01X1629724Y282676D02*
X1630574Y283526D01*
G01X1629724Y279747D02*
Y282676D01*
G01X1639609Y280216D02*
X1636684Y283141D01*
G01X1632078Y283389D02*
X1634052Y281415D01*
G01X1632078Y292315D02*
Y283389D01*
G01X1634052Y294289D02*
X1632078Y292315D01*
G01X1634052Y316312D02*
Y294289D01*
G01X1632552Y317812D02*
X1634052Y316312D01*
G01X1632552Y324088D02*
Y317812D01*
G01X1634852Y326388D02*
X1632552Y324088D01*
G01X1634852Y330112D02*
Y326388D01*
G01X1625323Y339641D02*
X1634852Y330112D01*
G01X1625323Y381423D02*
Y339641D01*
G01X1592177Y291826D02*
Y291204D01*
G01X1592178Y291827D02*
X1592177Y291826D01*
G01X1592178Y292470D02*
Y291827D01*
G01X1589670Y294978D02*
X1592178Y292470D01*
G01X1589670Y302371D02*
Y294978D01*
G01X1592077Y327260D02*
X1591554D01*
G01X1594760Y329943D02*
X1592077Y327260D01*
G01X1594760Y341875D02*
Y329943D01*
G01X1649133Y281905D02*
X1650046Y280992D01*
G01X1649133Y295839D02*
Y281905D01*
G01X1649134Y295840D02*
X1649133Y295839D01*
G01X1649134Y296462D02*
Y295840D01*
G01X1649135Y296463D02*
X1649134Y296462D01*
G01X1649135Y299371D02*
Y296463D01*
G01X1649133Y299373D02*
X1649135Y299371D01*
G01X1649133Y299910D02*
Y299373D01*
G01X1646760Y302283D02*
X1649133Y299910D01*
G01X1646760Y323889D02*
Y302283D01*
G01X1646761Y323890D02*
X1646760Y323889D01*
G01X1646761Y327422D02*
Y323890D01*
G01X1646760Y327423D02*
X1646761Y327422D01*
G01X1646760Y336070D02*
Y327423D01*
G01X1640199Y342631D02*
X1646760Y336070D01*
G01X1625400Y330412D02*
Y327667D01*
G01X1622070Y333742D02*
X1625400Y330412D01*
G01X1618796Y333742D02*
X1622070D01*
G01X1617561Y334977D02*
X1618796Y333742D01*
G01X1617561Y341917D02*
Y334977D01*
G01X1608764Y322761D02*
Y322440D01*
G01X1607596Y323929D02*
X1608764Y322761D01*
G01X1607596Y342581D02*
Y323929D01*
G01X1612253Y322072D02*
Y344251D01*
G01X1612254Y322071D02*
X1612253Y322072D01*
G01X1612254Y321449D02*
Y322071D01*
G01X1612253Y321448D02*
X1612254Y321449D01*
G01X1612253Y321253D02*
Y321448D01*
G01X1610360Y319360D02*
X1612253Y321253D01*
G01X1603348Y319360D02*
X1610360D01*
G01X1598500Y314512D02*
X1603348Y319360D01*
G01X1598500Y309660D02*
Y314512D01*
G01X1596790Y307950D02*
X1598500Y309660D01*
G01X1596790Y297434D02*
Y307950D01*
G01X1648764Y303114D02*
X1651137Y300741D01*
G01X1648764Y323058D02*
Y303114D01*
G01X1648765Y323059D02*
X1648764Y323058D01*
G01X1648765Y328253D02*
Y323059D01*
G01X1648764Y328254D02*
X1648765Y328253D01*
G01X1648764Y341910D02*
Y328254D01*
G01X1625963Y280742D02*
X1625964Y280741D01*
G01X1625963Y282612D02*
Y280742D01*
G01X1625964Y282613D02*
X1625963Y282612D01*
G01X1625964Y286036D02*
Y282613D01*
G01X1625846Y286154D02*
X1625964Y286036D01*
G01X1650385Y282424D02*
X1651298Y281511D01*
G01X1650385Y295320D02*
Y282424D01*
G01X1650386Y295321D02*
X1650385Y295320D01*
G01X1650386Y295943D02*
Y295321D01*
G01X1650387Y295944D02*
X1650386Y295943D01*
G01X1650387Y299890D02*
Y295944D01*
G01X1650385Y299892D02*
X1650387Y299890D01*
G01X1650385Y300429D02*
Y299892D01*
G01X1648012Y302802D02*
X1650385Y300429D01*
G01X1648012Y323370D02*
Y302802D01*
G01X1648013Y323371D02*
X1648012Y323370D01*
G01X1648013Y327941D02*
Y323371D01*
G01X1648012Y327942D02*
X1648013Y327941D01*
G01X1648012Y341539D02*
Y327942D01*
G01X1590212Y316366D02*
Y315425D01*
G01X1598620Y324774D02*
X1590212Y316366D01*
G01X1598620Y355257D02*
Y324774D01*
G01X1632830Y283701D02*
X1634804Y281727D01*
G01X1632830Y292003D02*
Y283701D01*
G01X1634804Y293977D02*
X1632830Y292003D01*
G01X1634804Y321448D02*
Y293977D01*
G01X1636931Y323575D02*
X1634804Y321448D01*
G01X1636931Y324881D02*
Y323575D01*
G01X1635604Y326208D02*
X1636931Y324881D01*
G01X1635604Y330424D02*
Y326208D01*
G01X1626075Y339953D02*
X1635604Y330424D01*
G01X1626075Y379775D02*
Y339953D01*
G01X1592504Y340750D02*
X1589178Y344076D01*
G01X1592504Y330879D02*
Y340750D01*
G01X1591141Y329516D02*
X1592504Y330879D01*
G01X1589854Y329516D02*
X1591141D01*
G01X1589921Y290268D02*
Y291535D01*
G01X1604464Y325796D02*
Y343974D01*
G01X1594739Y316071D02*
X1604464Y325796D01*
G01X1594739Y312953D02*
Y316071D01*
G01X1594740Y312952D02*
X1594739Y312953D01*
G01X1594740Y311220D02*
Y312952D01*
G01X1592780Y309260D02*
X1594740Y311220D01*
G01X1592780Y296124D02*
Y309260D01*
G01X1595186Y293718D02*
X1592780Y296124D01*
G01X1595186Y292451D02*
Y293718D01*
G01X1611501Y321760D02*
Y344563D01*
G01X1609853Y320112D02*
X1611501Y321760D01*
G01X1603660Y320112D02*
X1609853D01*
G01X1603659Y320113D02*
X1603660Y320112D01*
G01X1603037Y320113D02*
X1603659D01*
G01X1597747Y314823D02*
X1603037Y320113D01*
G01X1597747Y314201D02*
Y314823D01*
G01X1597748Y314200D02*
X1597747Y314201D01*
G01X1597748Y309972D02*
Y314200D01*
G01X1595990Y308214D02*
X1597748Y309972D01*
G01X1595990Y297170D02*
Y308214D01*
G01X1597868Y325467D02*
Y355569D01*
G01X1590440Y295272D02*
Y302665D01*
G01X1592930Y292782D02*
X1590440Y295272D01*
G01X1592930Y291515D02*
Y292782D01*
G01X1616809Y339462D02*
Y341605D01*
G01X1616794Y339447D02*
X1616809Y339462D01*
G01X1616794Y325058D02*
Y339447D01*
G01X1628036Y313816D02*
X1616794Y325058D01*
G01X1628036Y312684D02*
Y313816D01*
G01X1628035Y312683D02*
X1628036Y312684D01*
G01X1628035Y310189D02*
Y312683D01*
G01X1628036Y310188D02*
X1628035Y310189D01*
G01X1628036Y306784D02*
Y310188D01*
G01X1628035Y306783D02*
X1628036Y306784D01*
G01X1628035Y303665D02*
Y306783D01*
G01X1628036Y303664D02*
X1628035Y303665D01*
G01X1628036Y298884D02*
Y303664D01*
G01X1628035Y298883D02*
X1628036Y298884D01*
G01X1628035Y296869D02*
Y298883D01*
G01X1623518Y292352D02*
X1628035Y296869D01*
G01X1623518Y287424D02*
Y292352D01*
G01X1623517Y287423D02*
X1623518Y287424D01*
G01X1623517Y286801D02*
Y287423D01*
G01X1623518Y286800D02*
X1623517Y286801D01*
G01X1623518Y282670D02*
Y286800D01*
G01X1623517Y282669D02*
X1623518Y282670D01*
G01X1623517Y282047D02*
Y282669D01*
G01X1624459Y281105D02*
X1623517Y282047D01*
G01X1624459Y280118D02*
Y281105D01*
G01X1624460Y280117D02*
X1624459Y280118D01*
G01X1591752Y340438D02*
X1588867Y343323D01*
G01X1591752Y331191D02*
Y340438D01*
G01X1590829Y330268D02*
X1591752Y331191D01*
G01X1644873Y298143D02*
Y280138D01*
G01X1642500Y300516D02*
X1644873Y298143D01*
G01X1642500Y325656D02*
Y300516D01*
G01X1632115Y336041D02*
X1642500Y325656D01*
G01X1632115Y340827D02*
Y336041D01*
G01X1630927Y342015D02*
X1632115Y340827D01*
G01X1591425Y292159D02*
Y290892D01*
G01X1588910Y294674D02*
X1591425Y292159D01*
G01X1588910Y302067D02*
Y294674D01*
G01X1591765Y328012D02*
X1590478D01*
G01X1594008Y330255D02*
X1591765Y328012D01*
G01X1594008Y341563D02*
Y330255D01*
G01X1595140Y308428D02*
Y296956D01*
G01X1596996Y310284D02*
X1595140Y308428D01*
G01X1596996Y313888D02*
Y310284D01*
G01X1596995Y313889D02*
X1596996Y313888D01*
G01X1596995Y315135D02*
Y313889D01*
G01X1602725Y320865D02*
X1596995Y315135D01*
G01X1603971Y320865D02*
X1602725D01*
G01X1603972Y320864D02*
X1603971Y320865D01*
G01X1609417Y320864D02*
X1603972D01*
G01X1610749Y322196D02*
X1609417Y320864D01*
G01X1610749Y344931D02*
Y322196D01*
G01X1649516Y303426D02*
X1651889Y301053D01*
G01X1649516Y322746D02*
Y303426D01*
G01X1649517Y322747D02*
X1649516Y322746D01*
G01X1649517Y328565D02*
Y322747D01*
G01X1649516Y328566D02*
X1649517Y328565D01*
G01X1649516Y341598D02*
Y328566D01*
G01X1600524Y323984D02*
Y342521D01*
G01X1593235Y316695D02*
X1600524Y323984D01*
G01X1593235Y312329D02*
Y316695D01*
G01X1593236Y312328D02*
X1593235Y312329D01*
G01X1593236Y311844D02*
Y312328D01*
G01X1591230Y309838D02*
X1593236Y311844D01*
G01X1591230Y295546D02*
Y309838D01*
G01X1593682Y293094D02*
X1591230Y295546D01*
G01X1593682Y291827D02*
Y293094D01*
G01X1646377Y280762D02*
X1647290Y279849D01*
G01X1646377Y296982D02*
Y280762D01*
G01X1646378Y296983D02*
X1646377Y296982D01*
G01X1646378Y297605D02*
Y296983D01*
G01X1646379Y297606D02*
X1646378Y297605D01*
G01X1646379Y298228D02*
Y297606D01*
G01X1646377Y298230D02*
X1646379Y298228D01*
G01X1646377Y298767D02*
Y298230D01*
G01X1644004Y301140D02*
X1646377Y298767D01*
G01X1644004Y325032D02*
Y301140D01*
G01X1644005Y325033D02*
X1644004Y325032D01*
G01X1644005Y326279D02*
Y325033D01*
G01X1644004Y326280D02*
X1644005Y326279D01*
G01X1644004Y333388D02*
Y326280D01*
G01X1637257Y340135D02*
X1644004Y333388D01*
G01X1637257Y346966D02*
Y340135D01*
G01X1631326Y283077D02*
X1633300Y281103D01*
G01X1631326Y292627D02*
Y283077D01*
G01X1633300Y294601D02*
X1631326Y292627D01*
G01X1633300Y316000D02*
Y294601D01*
G01X1631800Y317500D02*
X1633300Y316000D01*
G01X1631800Y324400D02*
Y317500D01*
G01X1634100Y326700D02*
X1631800Y324400D01*
G01X1634100Y329800D02*
Y326700D01*
G01X1624571Y339329D02*
X1634100Y329800D01*
G01X1624571Y383570D02*
Y339329D01*
G01X1647129Y281074D02*
X1648042Y280161D01*
G01X1647129Y296670D02*
Y281074D01*
G01X1647130Y296671D02*
X1647129Y296670D01*
G01X1647130Y297293D02*
Y296671D01*
G01X1647131Y297294D02*
X1647130Y297293D01*
G01X1647131Y298540D02*
Y297294D01*
G01X1647129Y298542D02*
X1647131Y298540D01*
G01X1647129Y299079D02*
Y298542D01*
G01X1644756Y301452D02*
X1647129Y299079D01*
G01X1644756Y324720D02*
Y301452D01*
G01X1644757Y324721D02*
X1644756Y324720D01*
G01X1644757Y326591D02*
Y324721D01*
G01X1644756Y326592D02*
X1644757Y326591D01*
G01X1644756Y334482D02*
Y326592D01*
G01X1638017Y341221D02*
X1644756Y334482D01*
G01X1638017Y347270D02*
Y341221D01*
G01X1623067Y338527D02*
Y380233D01*
G01X1632591Y329003D02*
X1623067Y338527D01*
G01X1632591Y327591D02*
Y329003D01*
G01X1630296Y325296D02*
X1632591Y327591D01*
G01X1630296Y316876D02*
Y325296D01*
G01X1631796Y315376D02*
X1630296Y316876D01*
G01X1631796Y295225D02*
Y315376D01*
G01X1629822Y293251D02*
X1631796Y295225D01*
G01X1629822Y283838D02*
Y293251D01*
G01X1628972Y282988D02*
X1629822Y283838D01*
G01X1590176Y332924D02*
Y331844D01*
G01X1620159Y332000D02*
Y332004D01*
G01X1623824Y328335D02*
X1620159Y332000D01*
G01X1623824Y319092D02*
Y328335D01*
G01X1628788Y314128D02*
X1623824Y319092D01*
G01X1628788Y312372D02*
Y314128D01*
G01X1628787Y312371D02*
X1628788Y312372D01*
G01X1628787Y310501D02*
Y312371D01*
G01X1628788Y310500D02*
X1628787Y310501D01*
G01X1628788Y306472D02*
Y310500D01*
G01X1628787Y306471D02*
X1628788Y306472D01*
G01X1628787Y303977D02*
Y306471D01*
G01X1628788Y303976D02*
X1628787Y303977D01*
G01X1628788Y298572D02*
Y303976D01*
G01X1628787Y298571D02*
X1628788Y298572D01*
G01X1628787Y296557D02*
Y298571D01*
G01X1624270Y292040D02*
X1628787Y296557D01*
G01X1624270Y282358D02*
Y292040D01*
G01X1625211Y281417D02*
X1624270Y282358D01*
G01X1625211Y280430D02*
Y281417D01*
G01X1625212Y280429D02*
X1625211Y280430D01*
G01X1641113Y283643D02*
X1636800Y287956D01*
G01X1593256Y341251D02*
X1589679Y344828D01*
G01X1593256Y330567D02*
Y341251D01*
G01X1591453Y328764D02*
X1593256Y330567D01*
G01X1590166Y328764D02*
X1591453D01*
G01X1590673Y290580D02*
Y291847D01*
G01X1619897Y340865D02*
Y341136D01*
G01X1621600Y339162D02*
X1619897Y340865D01*
G01X1621600Y338508D02*
Y339162D01*
G01X1628687Y331421D02*
X1621600Y338508D01*
G01X1628687Y331418D02*
Y331421D01*
G01X1628803Y331302D02*
X1628687Y331418D01*
G01X1628803Y317305D02*
Y331302D01*
G01X1631044Y315064D02*
X1628803Y317305D01*
G01X1631044Y305536D02*
Y315064D01*
G01X1631043Y305535D02*
X1631044Y305536D01*
G01X1631043Y304913D02*
Y305535D01*
G01X1631044Y304912D02*
X1631043Y304913D01*
G01X1631044Y295537D02*
Y304912D01*
G01X1629070Y293563D02*
X1631044Y295537D01*
G01X1629070Y284150D02*
Y293563D01*
G01X1628220Y283300D02*
X1629070Y284150D01*
G01X1595938Y294030D02*
Y292763D01*
G01X1593570Y296398D02*
X1595938Y294030D01*
G01X1593570Y308986D02*
Y296398D01*
G01X1595492Y310908D02*
X1593570Y308986D01*
G01X1595492Y313264D02*
Y310908D01*
G01X1595491Y313265D02*
X1595492Y313264D01*
G01X1595491Y315759D02*
Y313265D01*
G01X1605380Y325648D02*
X1595491Y315759D01*
G01X1605380Y343826D02*
Y325648D01*
G01X1599372Y324462D02*
Y352855D01*
G01X1591788Y316878D02*
X1599372Y324462D01*
G01X1591788Y312188D02*
Y316878D01*
G01X1641865Y289903D02*
X1636822Y294946D01*
G01X1613500Y321000D02*
Y344400D01*
G01X1611000Y318500D02*
X1613500Y321000D01*
G01X1603552Y318500D02*
X1611000D01*
G01X1599526Y314474D02*
X1603552Y318500D01*
G01X1599526Y309622D02*
Y314474D01*
G01X1597560Y307656D02*
X1599526Y309622D01*
G01X1597560Y297728D02*
Y307656D01*
G01X1596690Y294342D02*
Y294241D01*
G01X1594360Y296672D02*
X1596690Y294342D01*
G01X1594360Y308712D02*
Y296672D01*
G01X1596244Y310596D02*
X1594360Y308712D01*
G01X1596244Y313576D02*
Y310596D01*
G01X1596243Y313577D02*
X1596244Y313576D01*
G01X1596243Y315447D02*
Y313577D01*
G01X1606254Y325458D02*
X1596243Y315447D01*
G01X1606254Y343636D02*
Y325458D01*
G01X1633927Y335293D02*
Y341877D01*
G01X1643253Y325967D02*
X1633927Y335293D01*
G01X1643253Y325345D02*
Y325967D01*
G01X1643252Y325344D02*
X1643253Y325345D01*
G01X1643252Y300828D02*
Y325344D01*
G01X1645625Y298455D02*
X1643252Y300828D01*
G01X1645625Y297918D02*
Y298455D01*
G01X1645626Y297917D02*
X1645625Y297918D01*
G01X1645626Y297295D02*
Y297917D01*
G01X1645625Y297294D02*
X1645626Y297295D01*
G01X1645625Y280450D02*
Y297294D01*
G01X1627927Y339165D02*
Y357554D01*
G01X1638063Y329029D02*
X1627927Y339165D01*
G01X1638063Y326504D02*
Y329029D01*
G01X1647881Y281386D02*
X1648794Y280473D01*
G01X1647881Y296358D02*
Y281386D01*
G01X1647882Y296359D02*
X1647881Y296358D01*
G01X1647882Y296981D02*
Y296359D01*
G01X1647883Y296982D02*
X1647882Y296981D01*
G01X1647883Y298852D02*
Y296982D01*
G01X1647881Y298854D02*
X1647883Y298852D01*
G01X1647881Y299391D02*
Y298854D01*
G01X1645508Y301764D02*
X1647881Y299391D01*
G01X1645508Y324408D02*
Y301764D01*
G01X1645509Y324409D02*
X1645508Y324408D01*
G01X1645509Y326903D02*
Y324409D01*
G01X1645508Y326904D02*
X1645509Y326903D01*
G01X1645508Y335551D02*
Y326904D01*
G01X1638871Y342188D02*
X1645508Y335551D01*
G01X1650268Y328878D02*
Y341286D01*
G01X1650269Y328877D02*
X1650268Y328878D01*
G01X1650269Y322435D02*
Y328877D01*
G01X1650268Y322434D02*
X1650269Y322435D01*
G01X1650268Y303738D02*
Y322434D01*
G01X1652641Y301365D02*
X1650268Y303738D01*
G01X1589169Y289956D02*
Y291223D01*
G01X1635224Y290848D02*
X1636822Y292446D01*
G01X1635224Y286347D02*
Y290848D01*
G01X1636578Y284993D02*
X1635224Y286347D01*
G01X1637949Y284993D02*
X1636578D01*
G01X1640361Y282581D02*
X1637949Y284993D01*
G01X1636922Y302588D02*
X1643369Y296141D01*
G01X1626715Y281054D02*
X1626716Y281053D01*
G01X1626715Y282300D02*
Y281054D01*
G01X1626716Y282301D02*
X1626715Y282300D01*
G01X1626716Y283924D02*
Y282301D01*
G01X1627566Y284774D02*
X1626716Y283924D01*
G01X1627566Y294187D02*
Y284774D01*
G01X1629540Y296161D02*
X1627566Y294187D01*
G01X1629540Y297012D02*
Y296161D01*
G01X1629539Y297013D02*
X1629540Y297012D01*
G01X1629539Y298259D02*
Y297013D01*
G01X1629540Y298260D02*
X1629539Y298259D01*
G01X1629540Y304288D02*
Y298260D01*
G01X1629539Y304289D02*
X1629540Y304288D01*
G01X1629539Y306159D02*
Y304289D01*
G01X1629540Y306160D02*
X1629539Y306159D01*
G01X1629540Y310812D02*
Y306160D01*
G01X1629539Y310813D02*
X1629540Y310812D01*
G01X1629539Y312059D02*
Y310813D01*
G01X1629540Y312060D02*
X1629539Y312059D01*
G01X1629540Y314440D02*
Y312060D01*
G01X1627299Y316681D02*
X1629540Y314440D01*
G01X1627299Y330678D02*
Y316681D01*
G01X1623483Y334494D02*
X1627299Y330678D01*
G01X1619108Y334494D02*
X1623483D01*
G01X1618314Y335288D02*
X1619108Y334494D01*
G01X1618314Y337263D02*
Y335288D01*
G01X1618313Y337264D02*
X1618314Y337263D01*
G01X1618313Y342229D02*
Y337264D01*
G01X1627467Y281366D02*
X1627468Y281365D01*
G01X1627467Y281988D02*
Y281366D01*
G01X1627468Y281989D02*
X1627467Y281988D01*
G01X1627468Y283612D02*
Y281989D01*
G01X1628318Y284462D02*
X1627468Y283612D01*
G01X1628318Y293875D02*
Y284462D01*
G01X1630292Y295849D02*
X1628318Y293875D01*
G01X1630292Y297324D02*
Y295849D01*
G01X1630291Y297325D02*
X1630292Y297324D01*
G01X1630291Y297947D02*
Y297325D01*
G01X1630292Y297948D02*
X1630291Y297947D01*
G01X1630292Y304600D02*
Y297948D01*
G01X1630291Y304601D02*
X1630292Y304600D01*
G01X1630291Y305847D02*
Y304601D01*
G01X1630292Y305848D02*
X1630291Y305847D01*
G01X1630292Y311124D02*
Y305848D01*
G01X1630291Y311125D02*
X1630292Y311124D01*
G01X1630291Y311747D02*
Y311125D01*
G01X1630292Y311748D02*
X1630291Y311747D01*
G01X1630292Y314752D02*
Y311748D01*
G01X1628051Y316993D02*
X1630292Y314752D01*
G01X1628051Y330990D02*
Y316993D01*
G01X1627935Y331106D02*
X1628051Y330990D01*
G01X1627935Y331109D02*
Y331106D01*
G01X1620408Y338636D02*
X1627935Y331109D01*
G01X1619897Y338636D02*
X1620408D01*
G01X1649528Y375351D02*
Y447031D01*
G01X1657295Y367584D02*
X1649528Y375351D01*
G01X1632378Y367237D02*
X1630240Y365099D01*
G01X1632378Y370358D02*
Y367237D01*
G01X1633965Y371945D02*
X1632378Y370358D01*
G01X1633965Y374071D02*
Y371945D01*
G01X1635894Y376000D02*
X1633965Y374071D01*
G01X1635894Y409515D02*
Y376000D01*
G01X1623819Y384281D02*
X1621800Y386300D01*
G01X1629300Y385400D02*
X1625323Y381423D01*
G01X1588823Y393041D02*
Y363792D01*
G01X1591332Y395550D02*
X1588823Y393041D01*
G01X1591332Y400006D02*
Y395550D01*
G01X1594200Y402874D02*
X1591332Y400006D01*
G01X1594200Y406600D02*
Y402874D01*
G01X1623777Y397424D02*
X1621727Y395374D01*
G01X1623777Y427006D02*
Y397424D01*
G01X1590303Y346332D02*
X1594760Y341875D01*
G01X1589467Y346332D02*
X1590303D01*
G01X1590580Y400381D02*
Y396344D01*
G01X1593400Y403201D02*
X1590580Y400381D01*
G01X1640199Y349832D02*
Y342631D01*
G01X1640872Y350505D02*
X1640199Y349832D01*
G01X1640872Y354244D02*
Y350505D01*
G01X1637183Y357933D02*
X1640872Y354244D01*
G01X1637183Y369136D02*
Y357933D01*
G01X1638225Y370178D02*
X1637183Y369136D01*
G01X1638225Y372304D02*
Y370178D01*
G01X1640154Y374233D02*
X1638225Y372304D01*
G01X1640154Y405747D02*
Y374233D01*
G01X1617560Y341918D02*
X1617561Y341917D01*
G01X1617560Y342540D02*
Y341918D01*
G01X1621563Y346543D02*
X1617560Y342540D01*
G01X1621563Y354100D02*
Y346543D01*
G01X1618800Y356863D02*
X1621563Y354100D01*
G01X1618800Y384136D02*
Y356863D01*
G01X1619016Y384352D02*
X1618800Y384136D01*
G01X1619016Y389316D02*
Y384352D01*
G01X1625281Y395581D02*
X1619016Y389316D01*
G01X1625281Y426382D02*
Y395581D01*
G01X1608850Y343835D02*
X1607596Y342581D01*
G01X1634486Y382186D02*
X1630800Y378500D01*
G01X1634486Y407113D02*
Y382186D01*
G01X1616700Y385483D02*
Y404200D01*
G01X1616300Y385083D02*
X1616700Y385483D01*
G01X1616300Y348298D02*
Y385083D01*
G01X1612253Y344251D02*
X1616300Y348298D01*
G01X1648765Y341911D02*
X1648764Y341910D01*
G01X1648765Y344765D02*
Y341911D01*
G01X1654400Y350400D02*
X1648765Y344765D01*
G01X1645848Y375400D02*
X1654400Y366848D01*
G01X1645848Y406478D02*
Y375400D01*
G01X1642467Y347084D02*
X1648012Y341539D01*
G01X1642374Y347084D02*
X1642467D01*
G01X1641451Y348007D02*
X1642374Y347084D01*
G01X1641451Y349313D02*
Y348007D01*
G01X1642124Y349986D02*
X1641451Y349313D01*
G01X1642124Y355380D02*
Y349986D01*
G01X1638435Y359069D02*
X1642124Y355380D01*
G01X1638435Y366712D02*
Y359069D01*
G01X1641290Y369567D02*
X1638435Y366712D01*
G01X1641310Y369567D02*
X1641290D01*
G01X1642028Y370285D02*
X1641310Y369567D01*
G01X1642028Y373150D02*
Y370285D01*
G01X1641406Y373772D02*
X1642028Y373150D01*
G01X1641406Y405228D02*
Y373772D01*
G01X1613156Y369793D02*
X1598620Y355257D01*
G01X1613156Y383900D02*
Y369793D01*
G01X1611876Y385180D02*
X1613156Y383900D01*
G01X1611876Y392876D02*
Y385180D01*
G01X1614401Y395401D02*
X1611876Y392876D01*
G01X1614401Y427049D02*
Y395401D01*
G01X1633078Y386778D02*
X1626075Y379775D01*
G01X1633078Y406521D02*
Y386778D01*
G01X1590535Y352650D02*
X1589565D01*
G01X1592619Y354734D02*
X1590535Y352650D01*
G01X1592619Y386337D02*
Y354734D01*
G01X1595092Y388810D02*
X1592619Y386337D01*
G01X1595092Y398446D02*
Y388810D01*
G01X1601672Y405026D02*
X1595092Y398446D01*
G01X1608656Y348166D02*
X1609271D01*
G01X1604464Y343974D02*
X1608656Y348166D01*
G01X1615905Y385804D02*
Y436439D01*
G01X1615505Y385404D02*
X1615905Y385804D01*
G01X1615505Y348567D02*
Y385404D01*
G01X1611501Y344563D02*
X1615505Y348567D01*
G01X1592836Y399382D02*
X1600736Y407282D01*
G01X1592836Y394606D02*
Y399382D01*
G01X1590327Y392097D02*
X1592836Y394606D01*
G01X1590327Y358752D02*
Y392097D01*
G01X1589975Y358400D02*
X1590327Y358752D01*
G01X1589100Y358400D02*
X1589975D01*
G01X1610887Y385105D02*
Y407036D01*
G01X1612404Y383588D02*
X1610887Y385105D01*
G01X1612404Y370105D02*
Y383588D01*
G01X1597868Y355569D02*
X1612404Y370105D01*
G01X1624529Y395929D02*
Y426694D01*
G01X1618264Y389664D02*
X1624529Y395929D01*
G01X1618264Y384664D02*
Y389664D01*
G01X1618000Y384400D02*
X1618264Y384664D01*
G01X1618000Y344044D02*
Y384400D01*
G01X1616807Y342851D02*
X1618000Y344044D01*
G01X1616807Y342229D02*
Y342851D01*
G01X1616808Y342228D02*
X1616807Y342229D01*
G01X1616808Y341606D02*
Y342228D01*
G01X1616809Y341605D02*
X1616808Y341606D01*
G01X1650280Y377293D02*
Y448761D01*
G01X1659200Y368373D02*
X1650280Y377293D01*
G01X1630927Y344277D02*
Y342015D01*
G01X1632110Y345460D02*
X1630927Y344277D01*
G01X1632110Y355901D02*
Y345460D01*
G01X1630408Y357603D02*
X1632110Y355901D01*
G01X1589991Y345580D02*
X1594008Y341563D01*
G01X1589259Y400159D02*
Y396761D01*
G01X1592600Y403500D02*
X1589259Y400159D01*
G01X1633175Y365438D02*
X1630337Y362600D01*
G01X1633175Y370091D02*
Y365438D01*
G01X1634717Y371633D02*
X1633175Y370091D01*
G01X1634717Y373759D02*
Y371633D01*
G01X1636646Y375688D02*
X1634717Y373759D01*
G01X1636646Y409203D02*
Y375688D01*
G01X1592084Y399694D02*
X1600424Y408034D01*
G01X1592084Y394926D02*
Y399694D01*
G01X1589575Y392417D02*
X1592084Y394926D01*
G01X1589575Y360446D02*
Y392417D01*
G01X1589223Y360094D02*
X1589575Y360446D01*
G01X1610805Y344931D02*
X1610749D01*
G01X1614753Y348879D02*
X1610805Y344931D01*
G01X1614753Y385753D02*
Y348879D01*
G01X1615153Y386153D02*
X1614753Y385753D01*
G01X1615153Y432597D02*
Y386153D01*
G01X1591867Y356475D02*
X1590154Y354762D01*
G01X1591867Y386649D02*
Y356475D01*
G01X1594340Y389122D02*
X1591867Y386649D01*
G01X1594340Y398758D02*
Y389122D01*
G01X1601360Y405778D02*
X1594340Y398758D01*
G01X1649517Y341599D02*
X1649516Y341598D01*
G01X1649517Y343170D02*
Y341599D01*
G01X1655791Y349444D02*
X1649517Y343170D01*
G01X1647766Y374985D02*
X1655791Y366960D01*
G01X1647766Y422081D02*
Y374985D01*
G01X1610370Y361489D02*
Y361890D01*
G01X1606272Y357391D02*
X1610370Y361489D01*
G01X1606272Y348269D02*
Y357391D01*
G01X1600524Y342521D02*
X1606272Y348269D01*
G01X1634679Y349544D02*
X1637257Y346966D01*
G01X1634679Y369467D02*
Y349544D01*
G01X1636221Y371009D02*
X1634679Y369467D01*
G01X1636221Y373135D02*
Y371009D01*
G01X1638150Y375064D02*
X1636221Y373135D01*
G01X1638150Y408080D02*
Y375064D01*
G01X1632326Y391325D02*
X1624571Y383570D01*
G01X1632326Y403224D02*
Y391325D01*
G01X1635431Y349856D02*
X1638017Y347270D01*
G01X1635431Y369155D02*
Y349856D01*
G01X1636973Y370697D02*
X1635431Y369155D01*
G01X1636973Y372823D02*
Y370697D01*
G01X1638902Y374752D02*
X1636973Y372823D01*
G01X1638902Y407471D02*
Y374752D01*
G01X1623067Y380233D02*
X1621800Y381500D01*
G01X1607989Y346435D02*
X1605380Y343826D01*
G01X1610181Y346435D02*
X1607989D01*
G01X1612040Y348294D02*
X1610181Y346435D01*
G01X1612040Y356195D02*
Y348294D01*
G01X1610140Y358095D02*
X1612040Y356195D01*
G01X1610140Y358350D02*
Y358095D01*
G01X1599372Y352855D02*
X1607412Y360895D01*
G01X1617500Y384984D02*
Y403936D01*
G01X1617161Y384645D02*
X1617500Y384984D01*
G01X1617161Y348061D02*
Y384645D01*
G01X1613500Y344400D02*
X1617161Y348061D01*
G01X1595844Y398134D02*
X1601984Y404274D01*
G01X1595844Y388270D02*
Y398134D01*
G01X1593495Y385921D02*
X1595844Y388270D01*
G01X1593495Y354546D02*
Y385921D01*
G01X1590218Y351269D02*
X1593495Y354546D01*
G01X1590218Y350995D02*
Y351269D01*
G01X1608301Y345683D02*
X1606254Y343636D01*
G01X1610493Y345683D02*
X1608301D01*
G01X1613908Y349098D02*
X1610493Y345683D01*
G01X1613908Y386642D02*
Y349098D01*
G01X1613452Y387098D02*
X1613908Y386642D01*
G01X1637398Y375376D02*
Y408672D01*
G01X1635469Y373447D02*
X1637398Y375376D01*
G01X1635469Y371321D02*
Y373447D01*
G01X1633927Y369779D02*
X1635469Y371321D01*
G01X1633927Y353036D02*
Y369779D01*
G01X1633926Y353035D02*
X1633927Y353036D01*
G01X1633926Y351789D02*
Y353035D01*
G01X1633927Y351788D02*
X1633926Y351789D01*
G01X1633927Y345011D02*
Y351788D01*
G01X1634079Y344859D02*
X1633927Y345011D01*
G01X1634079Y342029D02*
Y344859D01*
G01X1633927Y341877D02*
X1634079Y342029D01*
G01X1627927Y357554D02*
X1630476Y360103D01*
G01X1591115Y357880D02*
X1589911Y356676D01*
G01X1591115Y386961D02*
Y357880D01*
G01X1593588Y389434D02*
X1591115Y386961D01*
G01X1593588Y399070D02*
Y389434D01*
G01X1601048Y406530D02*
X1593588Y399070D01*
G01X1638871Y351917D02*
Y342188D01*
G01X1638991Y352037D02*
X1638871Y351917D01*
G01X1643700Y351361D02*
Y351667D01*
G01X1644694Y350367D02*
X1643700Y351361D01*
G01X1645431Y350367D02*
X1644694D01*
G01X1646203Y351139D02*
X1645431Y350367D01*
G01X1646203Y356307D02*
Y351139D01*
G01X1642927Y359583D02*
X1646203Y356307D01*
G01X1642927Y366424D02*
Y359583D01*
G01X1644417Y367914D02*
X1642927Y366424D01*
G01X1644417Y371825D02*
Y367914D01*
G01X1642158Y374084D02*
X1644417Y371825D01*
G01X1642158Y404916D02*
Y374084D01*
G01X1648776Y375039D02*
Y445339D01*
G01X1656543Y367272D02*
X1648776Y375039D01*
G01X1650268Y341286D02*
X1656543Y347561D01*
G01X1622315Y346231D02*
X1618313Y342229D01*
G01X1622315Y374800D02*
Y346231D01*
G01X1619768Y377347D02*
X1622315Y374800D01*
G01X1619768Y388968D02*
Y377347D01*
G01X1625827Y395027D02*
X1619768Y388968D01*
G01X1625827Y395063D02*
Y395027D01*
G01X1626033Y395269D02*
X1625827Y395063D01*
G01X1626033Y423546D02*
Y395269D01*
G01X1642910Y374396D02*
Y404604D01*
G01X1645170Y372136D02*
X1642910Y374396D01*
G01X1645170Y371514D02*
Y372136D01*
G01X1645169Y371513D02*
X1645170Y371514D01*
G01X1645169Y367602D02*
Y371513D01*
G01X1643679Y366112D02*
X1645169Y367602D01*
G01X1643679Y359895D02*
Y366112D01*
G01X1646955Y356619D02*
X1643679Y359895D01*
G01X1646955Y350827D02*
Y356619D01*
G01X1645743Y349615D02*
X1646955Y350827D01*
G01X1644073Y349615D02*
X1645743D01*
G01X1643150Y348692D02*
X1644073Y349615D01*
G01X1649528Y447031D02*
X1646469Y450090D01*
G01X1637684Y411305D02*
X1635894Y409515D01*
G01X1637684Y417885D02*
Y411305D01*
G01X1634542Y421027D02*
X1637684Y417885D01*
G01X1634542Y429484D02*
Y421027D01*
G01X1633664Y430362D02*
X1634542Y429484D01*
G01X1633664Y440948D02*
Y430362D01*
G01X1633663Y440949D02*
X1633664Y440948D01*
G01X1633663Y442195D02*
Y440949D01*
G01X1634738Y443270D02*
X1633663Y442195D01*
G01X1634738Y457631D02*
Y443270D01*
G01X1641230Y464123D02*
X1634738Y457631D01*
G01X1663677Y464123D02*
X1641230D01*
G01X1593050Y408750D02*
X1591200Y406900D01*
G01X1593050Y410850D02*
Y408750D01*
G01X1592000Y411900D02*
X1593050Y410850D01*
G01X1592000Y417600D02*
Y411900D01*
G01X1598920Y424520D02*
X1592000Y417600D01*
G01X1598920Y438378D02*
Y424520D01*
G01X1604176Y443634D02*
X1598920Y438378D01*
G01X1604176Y452182D02*
Y443634D01*
G01X1613218Y461224D02*
X1604176Y452182D01*
G01X1613218Y462904D02*
Y461224D01*
G01X1609178Y466944D02*
X1613218Y462904D01*
G01X1598000Y410400D02*
X1594200Y406600D01*
G01X1604348Y410400D02*
X1598000D01*
G01X1605328Y411380D02*
X1604348Y410400D01*
G01X1605328Y431114D02*
Y411380D01*
G01X1605752Y431538D02*
X1605328Y431114D01*
G01X1605752Y439779D02*
Y431538D01*
G01X1605751Y439780D02*
X1605752Y439779D01*
G01X1605751Y442515D02*
Y439780D01*
G01X1606080Y442844D02*
X1605751Y442515D01*
G01X1606080Y445033D02*
Y442844D01*
G01X1606079Y445034D02*
X1606080Y445033D01*
G01X1606079Y447528D02*
Y445034D01*
G01X1606080Y447529D02*
X1606079Y447528D01*
G01X1606080Y451616D02*
Y447529D01*
G01X1617500Y463036D02*
X1606080Y451616D01*
G01X1617500Y465601D02*
Y463036D01*
G01X1626600Y429829D02*
X1623777Y427006D01*
G01X1626600Y456696D02*
Y429829D01*
G01X1633789Y463885D02*
X1626600Y456696D01*
G01X1635682Y463885D02*
X1633789D01*
G01X1639229Y467432D02*
X1635682Y463885D01*
G01X1593400Y406864D02*
Y403201D01*
G01X1601304Y414768D02*
X1593400Y406864D01*
G01X1601304Y430777D02*
Y414768D01*
G01X1603050Y432523D02*
X1601304Y430777D01*
G01X1642222Y407815D02*
X1640154Y405747D01*
G01X1642222Y409020D02*
Y407815D01*
G01X1642223Y409021D02*
X1642222Y409020D01*
G01X1642223Y410057D02*
Y409021D01*
G01X1642222Y410058D02*
X1642223Y410057D01*
G01X1642222Y419435D02*
Y410058D01*
G01X1638802Y422855D02*
X1642222Y419435D01*
G01X1638802Y431251D02*
Y422855D01*
G01X1637924Y432129D02*
X1638802Y431251D01*
G01X1637924Y440429D02*
Y432129D01*
G01X1641367Y443872D02*
X1637924Y440429D01*
G01X1641367Y446381D02*
Y443872D01*
G01X1638246Y449502D02*
X1641367Y446381D01*
G01X1638246Y453793D02*
Y449502D01*
G01X1639169Y454716D02*
X1638246Y453793D01*
G01X1640475Y454716D02*
X1639169D01*
G01X1647878Y462119D02*
X1640475Y454716D01*
G01X1662846Y462119D02*
X1647878D01*
G01X1628300Y429401D02*
X1625281Y426382D01*
G01X1628300Y447541D02*
Y429401D01*
G01X1630276Y449517D02*
X1628300Y447541D01*
G01X1628201Y413398D02*
X1634486Y407113D01*
G01X1628201Y420427D02*
Y413398D01*
G01X1633134Y425360D02*
X1628201Y420427D01*
G01X1633134Y428900D02*
Y425360D01*
G01X1632256Y429778D02*
X1633134Y428900D01*
G01X1632256Y440364D02*
Y429778D01*
G01X1632255Y440365D02*
X1632256Y440364D01*
G01X1632255Y442779D02*
Y440365D01*
G01X1633330Y443854D02*
X1632255Y442779D01*
G01X1633330Y457047D02*
Y443854D01*
G01X1633329Y457048D02*
X1633330Y457047D01*
G01X1633329Y458214D02*
Y457048D01*
G01X1640646Y465531D02*
X1633329Y458214D01*
G01X1615775Y439031D02*
X1612183Y442623D01*
G01X1615775Y437633D02*
Y439031D01*
G01X1616657Y436751D02*
X1615775Y437633D01*
G01X1616657Y414244D02*
Y436751D01*
G01X1619700Y411201D02*
X1616657Y414244D01*
G01X1619700Y407200D02*
Y411201D01*
G01X1616700Y404200D02*
X1619700Y407200D01*
G01X1645850Y406480D02*
X1645848Y406478D01*
G01X1645850Y407726D02*
Y406480D01*
G01X1645849Y407727D02*
X1645850Y407726D01*
G01X1645849Y408349D02*
Y407727D01*
G01X1645848Y408350D02*
X1645849Y408349D01*
G01X1645848Y421022D02*
Y408350D01*
G01X1644875Y421995D02*
X1645848Y421022D01*
G01X1644875Y453243D02*
Y421995D01*
G01X1649881Y458249D02*
X1644875Y453243D01*
G01X1659158Y458249D02*
X1649881D01*
G01X1594562Y459538D02*
X1606841Y471817D01*
G01X1594562Y451362D02*
Y459538D01*
G01X1592175Y448975D02*
X1594562Y451362D01*
G01X1615061Y461702D02*
Y463157D01*
G01X1605328Y451969D02*
X1615061Y461702D01*
G01X1605328Y447841D02*
Y451969D01*
G01X1605327Y447840D02*
X1605328Y447841D01*
G01X1605327Y444722D02*
Y447840D01*
G01X1605328Y444721D02*
X1605327Y444722D01*
G01X1605328Y443156D02*
Y444721D01*
G01X1604850Y442678D02*
X1605328Y443156D01*
G01X1604850Y431750D02*
Y442678D01*
G01X1604500Y431400D02*
X1604850Y431750D01*
G01X1604500Y424471D02*
Y431400D01*
G01X1603000Y422971D02*
X1604500Y424471D01*
G01X1643592Y407414D02*
X1641406Y405228D01*
G01X1643592Y419836D02*
Y407414D01*
G01X1642216Y421212D02*
X1643592Y419836D01*
G01X1642216Y432044D02*
Y421212D01*
G01X1641060Y433200D02*
X1642216Y432044D01*
G01X1639500Y433200D02*
X1641060D01*
G01X1611935Y429515D02*
X1614401Y427049D01*
G01X1626785Y412814D02*
X1633078Y406521D01*
G01X1626785Y421109D02*
Y412814D01*
G01X1631726Y426050D02*
X1626785Y421109D01*
G01X1631726Y428316D02*
Y426050D01*
G01X1630846Y429196D02*
X1631726Y428316D01*
G01X1630846Y443362D02*
Y429196D01*
G01X1631876Y444392D02*
X1630846Y443362D01*
G01X1631876Y455499D02*
Y444392D01*
G01X1630200Y457175D02*
X1631876Y455499D01*
G01X1604294Y405026D02*
X1601672D01*
G01X1609090Y409822D02*
X1604294Y405026D01*
G01X1609090Y429556D02*
Y409822D01*
G01X1609513Y429979D02*
X1609090Y429556D01*
G01X1609513Y440957D02*
Y429979D01*
G01X1609840Y441284D02*
X1609513Y440957D01*
G01X1609840Y445969D02*
Y441284D01*
G01X1612271Y448400D02*
X1609840Y445969D01*
G01X1623600Y448400D02*
X1612271D01*
G01X1625000Y449800D02*
X1623600Y448400D01*
G01X1625000Y457224D02*
Y449800D01*
G01X1633165Y465389D02*
X1625000Y457224D01*
G01X1615905Y436439D02*
X1612256Y440088D01*
G01X1623884Y459300D02*
X1632230Y467646D01*
G01X1619422Y459300D02*
X1623884D01*
G01X1607584Y447462D02*
X1619422Y459300D01*
G01X1607584Y446905D02*
Y447462D01*
G01X1607583Y446904D02*
X1607584Y446905D01*
G01X1607583Y445658D02*
Y446904D01*
G01X1607584Y445657D02*
X1607583Y445658D01*
G01X1607584Y442220D02*
Y445657D01*
G01X1607257Y441893D02*
X1607584Y442220D01*
G01X1607257Y430915D02*
Y441893D01*
G01X1606834Y430492D02*
X1607257Y430915D01*
G01X1606834Y410758D02*
Y430492D01*
G01X1603358Y407282D02*
X1606834Y410758D01*
G01X1600736Y407282D02*
X1603358D01*
G01X1610887Y407036D02*
X1612825Y408974D01*
G01X1627400Y451875D02*
X1630200Y454675D01*
G01X1627400Y429565D02*
Y451875D01*
G01X1624529Y426694D02*
X1627400Y429565D01*
G01X1594976Y436942D02*
X1591446Y440472D01*
G01X1594976Y425812D02*
Y436942D01*
G01X1650280Y448761D02*
X1646451Y452590D01*
G01X1592600Y407200D02*
Y403500D01*
G01X1593900Y408500D02*
X1592600Y407200D01*
G01X1593900Y411100D02*
Y408500D01*
G01X1592900Y412100D02*
X1593900Y411100D01*
G01X1592900Y417400D02*
Y412100D01*
G01X1600152Y424652D02*
X1592900Y417400D01*
G01X1600152Y432652D02*
Y424652D01*
G01X1603000Y435500D02*
X1600152Y432652D01*
G01X1638436Y410993D02*
X1636646Y409203D01*
G01X1638436Y418197D02*
Y410993D01*
G01X1635294Y421339D02*
X1638436Y418197D01*
G01X1635294Y429796D02*
Y421339D01*
G01X1634416Y430674D02*
X1635294Y429796D01*
G01X1634416Y441260D02*
Y430674D01*
G01X1634415Y441261D02*
X1634416Y441260D01*
G01X1634415Y441883D02*
Y441261D01*
G01X1635490Y442958D02*
X1634415Y441883D01*
G01X1635490Y457319D02*
Y442958D01*
G01X1641542Y463371D02*
X1635490Y457319D01*
G01X1663365Y463371D02*
X1641542D01*
G01X1596430Y464538D02*
X1605337Y473445D01*
G01X1623620Y460100D02*
X1631918Y468398D01*
G01X1619158Y460100D02*
X1623620D01*
G01X1606832Y447774D02*
X1619158Y460100D01*
G01X1606832Y447217D02*
Y447774D01*
G01X1606831Y447216D02*
X1606832Y447217D01*
G01X1606831Y445346D02*
Y447216D01*
G01X1606832Y445345D02*
X1606831Y445346D01*
G01X1606832Y442532D02*
Y445345D01*
G01X1606504Y442204D02*
X1606832Y442532D01*
G01X1606504Y431226D02*
Y442204D01*
G01X1606082Y430804D02*
X1606504Y431226D01*
G01X1606082Y411070D02*
Y430804D01*
G01X1603046Y408034D02*
X1606082Y411070D01*
G01X1600424Y408034D02*
X1603046D01*
G01X1612250Y435500D02*
X1615153Y432597D01*
G01X1603982Y405778D02*
X1601360D01*
G01X1608338Y410134D02*
X1603982Y405778D01*
G01X1608338Y429868D02*
Y410134D01*
G01X1608761Y430291D02*
X1608338Y429868D01*
G01X1608761Y441269D02*
Y430291D01*
G01X1609088Y441596D02*
X1608761Y441269D01*
G01X1609088Y446281D02*
Y441596D01*
G01X1612007Y449200D02*
X1609088Y446281D01*
G01X1623100Y449200D02*
X1612007D01*
G01X1624200Y450300D02*
X1623100Y449200D01*
G01X1624200Y457488D02*
Y450300D01*
G01X1632853Y466141D02*
X1624200Y457488D01*
G01X1647200Y422647D02*
X1647766Y422081D01*
G01X1647200Y430450D02*
Y422647D01*
G01X1639940Y409870D02*
X1638150Y408080D01*
G01X1639940Y410369D02*
Y409870D01*
G01X1639941Y410370D02*
X1639940Y410369D01*
G01X1639941Y411616D02*
Y410370D01*
G01X1639940Y411617D02*
X1639941Y411616D01*
G01X1639940Y418821D02*
Y411617D01*
G01X1636798Y421963D02*
X1639940Y418821D01*
G01X1636798Y430420D02*
Y421963D01*
G01X1635920Y431298D02*
X1636798Y430420D01*
G01X1635920Y441260D02*
Y431298D01*
G01X1636995Y442335D02*
X1635920Y441260D01*
G01X1636994Y442336D02*
X1636995Y442335D01*
G01X1636994Y454312D02*
Y442336D01*
G01X1639582Y456900D02*
X1636994Y454312D01*
G01X1640000Y456900D02*
X1639582D01*
G01X1630750Y404800D02*
X1632326Y403224D01*
G01X1640970Y409539D02*
X1638902Y407471D01*
G01X1640970Y418855D02*
Y409539D01*
G01X1637550Y422275D02*
X1640970Y418855D01*
G01X1637550Y430732D02*
Y422275D01*
G01X1636672Y431610D02*
X1637550Y430732D01*
G01X1636672Y440948D02*
Y431610D01*
G01X1639750Y444026D02*
X1636672Y440948D01*
G01X1639750Y445477D02*
Y444026D01*
G01X1591824Y435477D02*
Y423724D01*
G01X1591300Y436001D02*
X1591824Y435477D01*
G01X1591300Y437300D02*
Y436001D01*
G01X1588870Y439730D02*
X1591300Y437300D01*
G01X1588870Y440546D02*
Y439730D01*
G01X1642619Y442331D02*
X1639774Y439486D01*
G01X1642619Y454865D02*
Y442331D01*
G01X1648533Y460779D02*
X1642619Y454865D01*
G01X1662415Y460779D02*
X1648533D01*
G01X1602470Y452705D02*
X1611642Y461877D01*
G01X1602470Y448170D02*
Y452705D01*
G01X1600400Y446100D02*
X1602470Y448170D01*
G01X1597760Y443460D02*
X1600400Y446100D01*
G01X1597760Y424560D02*
Y443460D01*
G01X1591147Y417947D02*
X1597760Y424560D01*
G01X1591147Y411453D02*
Y417947D01*
G01X1598100Y462012D02*
X1607593Y471505D01*
G01X1598100Y453348D02*
Y462012D01*
G01X1591628Y446876D02*
X1598100Y453348D01*
G01X1590697Y446876D02*
X1591628D01*
G01X1589774Y445953D02*
X1590697Y446876D01*
G01X1589774Y443076D02*
Y445953D01*
G01X1590750Y442100D02*
X1589774Y443076D01*
G01X1592400Y442100D02*
X1590750D01*
G01X1595828Y438672D02*
X1592400Y442100D01*
G01X1595828Y424144D02*
Y438672D01*
G01X1588984Y417300D02*
X1595828Y424144D01*
G01X1593012Y451573D02*
X1591939Y450500D01*
G01X1593012Y459242D02*
Y451573D01*
G01X1606089Y472319D02*
X1593012Y459242D01*
G01X1621200Y445026D02*
X1621226D01*
G01X1621200Y445000D02*
Y445026D01*
G01X1617561Y441361D02*
X1621200Y445000D01*
G01X1617561Y414438D02*
Y441361D01*
G01X1620500Y411499D02*
X1617561Y414438D01*
G01X1620500Y407100D02*
Y411499D01*
G01X1620452Y407052D02*
X1620500Y407100D01*
G01X1620452Y406888D02*
Y407052D01*
G01X1617500Y403936D02*
X1620452Y406888D01*
G01X1635370Y464637D02*
X1638917Y468184D01*
G01X1633477Y464637D02*
X1635370D01*
G01X1625848Y457008D02*
X1633477Y464637D01*
G01X1625848Y449448D02*
Y457008D01*
G01X1624000Y447600D02*
X1625848Y449448D01*
G01X1616201Y447600D02*
X1624000D01*
G01X1613025Y444424D02*
X1616201Y447600D01*
G01X1611755Y444424D02*
X1613025D01*
G01X1610592Y443261D02*
X1611755Y444424D01*
G01X1610592Y440972D02*
Y443261D01*
G01X1610265Y440645D02*
X1610592Y440972D01*
G01X1610265Y429667D02*
Y440645D01*
G01X1609842Y429244D02*
X1610265Y429667D01*
G01X1609842Y409510D02*
Y429244D01*
G01X1604606Y404274D02*
X1609842Y409510D01*
G01X1601984Y404274D02*
X1604606D01*
G01X1636242Y455842D02*
X1640100Y459700D01*
G01X1636242Y442646D02*
Y455842D01*
G01X1635168Y441572D02*
X1636242Y442646D01*
G01X1635168Y430986D02*
Y441572D01*
G01X1636046Y430108D02*
X1635168Y430986D01*
G01X1636046Y421651D02*
Y430108D01*
G01X1639188Y418509D02*
X1636046Y421651D01*
G01X1639188Y411305D02*
Y418509D01*
G01X1639189Y411304D02*
X1639188Y411305D01*
G01X1639189Y410682D02*
Y411304D01*
G01X1639188Y410681D02*
X1639189Y410682D01*
G01X1639188Y410462D02*
Y410681D01*
G01X1637398Y408672D02*
X1639188Y410462D01*
G01X1603670Y406530D02*
X1601048D01*
G01X1607586Y410446D02*
X1603670Y406530D01*
G01X1607586Y430180D02*
Y410446D01*
G01X1608009Y430603D02*
X1607586Y430180D01*
G01X1608009Y441581D02*
Y430603D01*
G01X1608336Y441908D02*
X1608009Y441581D01*
G01X1608336Y445969D02*
Y441908D01*
G01X1608335Y445970D02*
X1608336Y445969D01*
G01X1608335Y446592D02*
Y445970D01*
G01X1608336Y446593D02*
X1608335Y446592D01*
G01X1608336Y447150D02*
Y446593D01*
G01X1619734Y458548D02*
X1608336Y447150D01*
G01X1624196Y458548D02*
X1619734D01*
G01X1632542Y466894D02*
X1624196Y458548D01*
G01X1644345Y407103D02*
X1642158Y404916D01*
G01X1644345Y407725D02*
Y407103D01*
G01X1644344Y407726D02*
X1644345Y407725D01*
G01X1644344Y420398D02*
Y407726D01*
G01X1643371Y421371D02*
X1644344Y420398D01*
G01X1643371Y454371D02*
Y421371D01*
G01X1648753Y459753D02*
X1643371Y454371D01*
G01X1649257Y459753D02*
X1648753D01*
G01X1649258Y459754D02*
X1649257Y459753D01*
G01X1650504Y459754D02*
X1649258D01*
G01X1648776Y445339D02*
X1646525Y447590D01*
G01X1608345Y464553D02*
Y476015D01*
G01X1600429Y456637D02*
X1608345Y464553D01*
G01X1600429Y454379D02*
Y456637D01*
G01X1591350Y445300D02*
X1600429Y454379D01*
G01X1630150Y427663D02*
X1626033Y423546D01*
G01X1650193Y459001D02*
X1659470D01*
G01X1650192Y459002D02*
X1650193Y459001D01*
G01X1649570Y459002D02*
X1650192D01*
G01X1649569Y459001D02*
X1649570Y459002D01*
G01X1649147Y459001D02*
X1649569D01*
G01X1644123Y453977D02*
X1649147Y459001D01*
G01X1644123Y421683D02*
Y453977D01*
G01X1645096Y420710D02*
X1644123Y421683D01*
G01X1645096Y408038D02*
Y420710D01*
G01X1645097Y408037D02*
X1645096Y408038D01*
G01X1645097Y407415D02*
Y408037D01*
G01X1645098Y407414D02*
X1645097Y407415D01*
G01X1645098Y406792D02*
Y407414D01*
G01X1642910Y404604D02*
X1645098Y406792D01*
G01X1649684Y490777D02*
X1668084D01*
G01X1642643Y483736D02*
X1649684Y490777D01*
G01X1622782Y483736D02*
X1642643D01*
G01X1620299Y486219D02*
X1622782Y483736D01*
G01X1613162Y486219D02*
X1620299D01*
G01X1604585Y477642D02*
X1613162Y486219D01*
G01X1604585Y474827D02*
Y477642D01*
G01X1598537Y468779D02*
X1604585Y474827D01*
G01X1609836Y522843D02*
X1604449Y517456D01*
G01X1609836Y527652D02*
Y522843D01*
G01X1609178Y475784D02*
Y466944D01*
G01X1612092Y478698D02*
X1609178Y475784D01*
G01X1619083Y478698D02*
X1612092D01*
G01X1619609Y479224D02*
X1619083Y478698D01*
G01X1640640Y479224D02*
X1619609D01*
G01X1646416Y473448D02*
X1640640Y479224D01*
G01X1657626Y473448D02*
X1646416D01*
G01X1625855Y518221D02*
X1615508Y507874D01*
G01X1630782Y518221D02*
X1625855D01*
G01X1638050Y510953D02*
X1630782Y518221D01*
G01X1641949Y510953D02*
X1638050D01*
G01X1642565Y510337D02*
X1641949Y510953D01*
G01X1642601Y510337D02*
X1642565D01*
G01X1644084Y508854D02*
X1642601Y510337D01*
G01X1654576Y508854D02*
X1644084D01*
G01X1603833Y475139D02*
X1598225Y469531D01*
G01X1603833Y477954D02*
Y475139D01*
G01X1612953Y487074D02*
X1603833Y477954D01*
G01X1620508Y487074D02*
X1612953D01*
G01X1623094Y484488D02*
X1620508Y487074D01*
G01X1642331Y484488D02*
X1623094D01*
G01X1649372Y491529D02*
X1642331Y484488D01*
G01X1665329Y491529D02*
X1649372D01*
G01X1616972Y466129D02*
X1617500Y465601D01*
G01X1612405Y466129D02*
X1616972D01*
G01X1609930Y468604D02*
X1612405Y466129D01*
G01X1609930Y475472D02*
Y468604D01*
G01X1612404Y477946D02*
X1609930Y475472D01*
G01X1619395Y477946D02*
X1612404D01*
G01X1619921Y478472D02*
X1619395Y477946D01*
G01X1640328Y478472D02*
X1619921D01*
G01X1646104Y472696D02*
X1640328Y478472D01*
G01X1657938Y472696D02*
X1646104D01*
G01X1664872Y467432D02*
X1639229D01*
G01X1664261Y465531D02*
X1640646D01*
G01X1613292Y525202D02*
X1618445Y530355D01*
G01X1613292Y521029D02*
Y525202D01*
G01X1606263Y514000D02*
X1613292Y521029D01*
G01X1637009Y521865D02*
X1631975Y526899D01*
G01X1651267Y521865D02*
X1637009D01*
G01X1636427Y520293D02*
X1650960D01*
G01X1628691Y528029D02*
X1636427Y520293D01*
G01X1614544Y524683D02*
X1618964Y529103D01*
G01X1614544Y520510D02*
Y524683D01*
G01X1606782Y512748D02*
X1614544Y520510D01*
G01X1646000Y477800D02*
X1651279D01*
G01X1642320Y481480D02*
X1646000Y477800D01*
G01X1621846Y481480D02*
X1642320D01*
G01X1619598Y483728D02*
X1621846Y481480D01*
G01X1613930Y483728D02*
X1619598D01*
G01X1606841Y476639D02*
X1613930Y483728D01*
G01X1606841Y471817D02*
Y476639D01*
G01X1643606Y507702D02*
X1655054D01*
G01X1643344Y507964D02*
X1643606Y507702D01*
G01X1643308Y507964D02*
X1643344D01*
G01X1641471Y509801D02*
X1643308Y507964D01*
G01X1635922Y509801D02*
X1641471D01*
G01X1628654Y517069D02*
X1635922Y509801D01*
G01X1626557Y517069D02*
X1628654D01*
G01X1616210Y506722D02*
X1626557Y517069D01*
G01X1635058Y465389D02*
X1633165D01*
G01X1638605Y468936D02*
X1635058Y465389D01*
G01X1659498Y468936D02*
X1638605D01*
G01X1628072Y524928D02*
X1627622D01*
G01X1635111Y517889D02*
X1628072Y524928D01*
G01X1649963Y517889D02*
X1635111D01*
G01X1651740Y516112D02*
X1649963Y517889D01*
G01X1618286Y515592D02*
X1627622Y524928D01*
G01X1613795Y515592D02*
X1618286D01*
G01X1608457Y510254D02*
X1613795Y515592D01*
G01X1637370Y523134D02*
X1651628D01*
G01X1634633Y525871D02*
X1637370Y523134D01*
G01X1634633Y527271D02*
Y525871D01*
G01X1612140Y525680D02*
X1617967Y531507D01*
G01X1612140Y521887D02*
Y525680D01*
G01X1605405Y515152D02*
X1612140Y521887D01*
G01X1637669Y471192D02*
X1658562D01*
G01X1634123Y467646D02*
X1637669Y471192D01*
G01X1632230Y467646D02*
X1634123D01*
G01X1650441Y519041D02*
X1652218Y517264D01*
G01X1635738Y519041D02*
X1650441D01*
G01X1628275Y526504D02*
X1635738Y519041D01*
G01X1615796Y523344D02*
X1619643Y527191D01*
G01X1615796Y520132D02*
Y523344D01*
G01X1607260Y511596D02*
X1615796Y520132D01*
G01X1647447Y482984D02*
X1650792Y486329D01*
G01X1622470Y482984D02*
X1647447D01*
G01X1619987Y485467D02*
X1622470Y482984D01*
G01X1613474Y485467D02*
X1619987D01*
G01X1605337Y477330D02*
X1613474Y485467D01*
G01X1605337Y473445D02*
Y477330D01*
G01X1637357Y471944D02*
X1658250D01*
G01X1633811Y468398D02*
X1637357Y471944D01*
G01X1631918Y468398D02*
X1633811D01*
G01X1610988Y522365D02*
X1604927Y516304D01*
G01X1610988Y527114D02*
Y522365D01*
G01X1634746Y466141D02*
X1632853D01*
G01X1638293Y469688D02*
X1634746Y466141D01*
G01X1659186Y469688D02*
X1638293D01*
G01X1645292Y476700D02*
X1651243D01*
G01X1641264Y480728D02*
X1645292Y476700D01*
G01X1621534Y480728D02*
X1641264D01*
G01X1619286Y482976D02*
X1621534Y480728D01*
G01X1614242Y482976D02*
X1619286D01*
G01X1607593Y476327D02*
X1614242Y482976D01*
G01X1607593Y471505D02*
Y476327D01*
G01X1606089Y476951D02*
Y472319D01*
G01X1613618Y484480D02*
X1606089Y476951D01*
G01X1619910Y484480D02*
X1613618D01*
G01X1622158Y482232D02*
X1619910Y484480D01*
G01X1648068Y482232D02*
X1622158D01*
G01X1650100Y480200D02*
X1648068Y482232D01*
G01X1653500Y480200D02*
X1650100D01*
G01X1638917Y468184D02*
X1659810D01*
G01X1634435Y466894D02*
X1632542D01*
G01X1637981Y470440D02*
X1634435Y466894D01*
G01X1658874Y470440D02*
X1637981D01*
G01X1646728Y474200D02*
X1657314D01*
G01X1640952Y479976D02*
X1646728Y474200D01*
G01X1619137Y479976D02*
X1640952D01*
G01X1618611Y479450D02*
X1619137Y479976D01*
G01X1618098Y479450D02*
X1618611D01*
G01X1618098Y479451D02*
Y479450D01*
G01X1611781Y479451D02*
X1618098D01*
G01X1608345Y476015D02*
X1611781Y479451D01*
G01X1648977Y492481D02*
X1662081D01*
G01X1641936Y485440D02*
X1648977Y492481D01*
G01X1623489Y485440D02*
X1641936D01*
G01X1620903Y488026D02*
X1623489Y485440D01*
G01X1613348Y488026D02*
X1620903D01*
G01X1613347Y488027D02*
X1613348Y488026D01*
G01X1612559Y488027D02*
X1613347D01*
G01X1602881Y478349D02*
X1612559Y488027D01*
G01X1602881Y478320D02*
Y478349D01*
G01X1602498Y477937D02*
X1602881Y478320D01*
G01X1602498Y475151D02*
Y477937D01*
G01X1597858Y470511D02*
X1602498Y475151D01*
G01X1628873Y521894D02*
X1630159Y520608D01*
G01X1626754Y521894D02*
X1628873D01*
G01X1619300Y514440D02*
X1626754Y521894D01*
G01X1614273Y514440D02*
X1619300D01*
G01X1608935Y509102D02*
X1614273Y514440D01*
G01X1642087Y513121D02*
X1655444D01*
G01X1638584Y516624D02*
X1642087Y513121D01*
G01X1634143Y516624D02*
X1638584D01*
G01X1630159Y520608D02*
X1634143Y516624D01*
G01X1616484Y534300D02*
X1609836Y527652D01*
G01X1631516Y534300D02*
X1616484D01*
G01X1633624Y532192D02*
X1631516Y534300D01*
G01X1642610Y532192D02*
X1633624D01*
G01X1643852Y530950D02*
X1642610Y532192D01*
G01X1667109Y530950D02*
X1643852D01*
G01X1592399Y587500D02*
X1596500Y591601D01*
G01X1629320Y530355D02*
X1631975Y527700D01*
G01X1618445Y530355D02*
X1629320D01*
G01X1631975Y526899D02*
Y527700D01*
G01X1626518Y528029D02*
X1628691D01*
G01X1625444Y529103D02*
X1626518Y528029D01*
G01X1618964Y529103D02*
X1625444D01*
G01X1630397Y531507D02*
X1634633Y527271D01*
G01X1617967Y531507D02*
X1630397D01*
G01X1626969Y526504D02*
X1628275D01*
G01X1626918Y526453D02*
X1626969Y526504D01*
G01X1625680Y526453D02*
X1626918D01*
G01X1624942Y527191D02*
X1625680Y526453D01*
G01X1619643Y527191D02*
X1624942D01*
G01X1616562Y532688D02*
X1610988Y527114D01*
G01X1631498Y532688D02*
X1616562D01*
G01X1633146Y531040D02*
X1631498Y532688D01*
G01X1642132Y531040D02*
X1633146D01*
G01X1643374Y529798D02*
X1642132Y531040D01*
G01X1667587Y529798D02*
X1643374D01*
G01X1617400Y581000D02*
X1625500Y589100D01*
G01X1611400Y581000D02*
X1617400D01*
G01X1607300Y585100D02*
X1611400Y581000D01*
G01X1597520Y585100D02*
X1607300D01*
G01X1594733Y582313D02*
X1597520Y585100D01*
G01X1622330Y588030D02*
Y592325D01*
G01X1616800Y582500D02*
X1622330Y588030D01*
G01X1612800Y582500D02*
X1616800D01*
G01X1608578Y586722D02*
X1612800Y582500D01*
G01X1596922Y586722D02*
X1608578D01*
G01X1593700Y583500D02*
X1596922Y586722D01*
G01X1653124Y604930D02*
X1644856D01*
G01X1599050Y621500D02*
X1692100D01*
G01X1596500Y618950D02*
X1599050Y621500D01*
G01X1596500Y591601D02*
Y618950D01*
G01X1643478Y602777D02*
X1640921Y605334D01*
G01X1653285Y602777D02*
X1643478D01*
G01X1625778Y619748D02*
X1692222D01*
G01X1620150Y614120D02*
X1625778Y619748D01*
G01X1620150Y597050D02*
Y614120D01*
G01X1625500Y591700D02*
X1620150Y597050D01*
G01X1625500Y589100D02*
Y591700D01*
G01X1691056Y-56D02*
X1796735D01*
G01X1688000Y3000D02*
X1691056Y-56D01*
G01X1676949Y-1124D02*
X1801524D01*
G01X1675393Y-2680D02*
X1676949Y-1124D01*
G01X1662968Y-2680D02*
X1675393D01*
G01X1656892Y-8756D02*
X1662968Y-2680D01*
G01X1650732Y-19668D02*
X1650730Y-19670D01*
G01X1651368Y-19668D02*
X1650732D01*
G01X1664548Y-6488D02*
X1651368Y-19668D01*
G01X1675512Y-6488D02*
X1664548D01*
G01X1687900Y-18876D02*
X1675512Y-6488D01*
G01X1820969Y-18876D02*
X1687900D01*
G01X1664153Y-5536D02*
X1650973Y-18716D01*
G01X1675907Y-5536D02*
X1664153D01*
G01X1681323Y-10952D02*
X1675907Y-5536D01*
G01X1824448Y-10952D02*
X1681323D01*
G01X1680300Y5358D02*
X1736808D01*
G01X1678458Y3516D02*
X1680300Y5358D01*
G01X1678458Y1732D02*
Y3516D01*
G01X1674998Y-1728D02*
X1678458Y1732D01*
G01X1662573Y-1728D02*
X1674998D01*
G01X1656497Y-7804D02*
X1662573Y-1728D01*
G01X1679335Y6310D02*
X1736413D01*
G01X1677376Y4351D02*
X1679335Y6310D01*
G01X1677376Y1997D02*
Y4351D01*
G01X1674603Y-776D02*
X1677376Y1997D01*
G01X1662178Y-776D02*
X1674603D01*
G01X1656102Y-6852D02*
X1662178Y-776D01*
G01X1682065Y-9000D02*
X1823701D01*
G01X1676697Y-3632D02*
X1682065Y-9000D01*
G01X1663363Y-3632D02*
X1676697D01*
G01X1657287Y-9708D02*
X1663363Y-3632D01*
G01X1663758Y-4584D02*
X1650578Y-17764D01*
G01X1676302Y-4584D02*
X1663758D01*
G01X1681718Y-10000D02*
X1676302Y-4584D01*
G01X1824053Y-10000D02*
X1681718D01*
G01X1661700Y376D02*
X1655624Y-5700D01*
G01X1669821Y376D02*
X1661700D01*
G01X1676907Y7462D02*
X1669821Y376D01*
G01X1735935Y7462D02*
X1676907D01*
G01X1681220Y-21180D02*
X1676819Y-16779D01*
G01X1829979Y-21180D02*
X1681220D01*
G01X1683350Y-20028D02*
X1680033Y-16711D01*
G01X1829501Y-20028D02*
X1683350D01*
G01X1710733Y93485D02*
X1712291Y91927D01*
G01X1704306Y93485D02*
X1710733D01*
G01X1702705Y91884D02*
X1704306Y93485D01*
G01X1685891Y91884D02*
X1702705D01*
G01X1681631Y96144D02*
X1685891Y91884D01*
G01X1685024Y91132D02*
X1680965Y95191D01*
G01X1703017Y91132D02*
X1685024D01*
G01X1703686Y91801D02*
X1703017Y91132D01*
G01X1710090Y91801D02*
X1703686D01*
G01X1712080Y89811D02*
X1710090Y91801D01*
G01X1717995Y89811D02*
X1712080D01*
G01X1706524Y80948D02*
X1743812D01*
G01X1703661Y83811D02*
X1706524Y80948D01*
G01X1684451Y83811D02*
X1703661D01*
G01X1678816Y89446D02*
X1684451Y83811D01*
G01X1678504Y89446D02*
X1678816D01*
G01X1677649Y90301D02*
X1678504Y89446D01*
G01X1706607Y79244D02*
X1744182D01*
G01X1706606Y79243D02*
X1706607Y79244D01*
G01X1705818Y79243D02*
X1706606D01*
G01X1702954Y82107D02*
X1705818Y79243D01*
G01X1683744Y82107D02*
X1702954D01*
G01X1683079Y82772D02*
X1683744Y82107D01*
G01X1682468Y82772D02*
X1683079D01*
G01X1679927Y85313D02*
X1682468Y82772D01*
G01X1669687Y85313D02*
X1679927D01*
G01X1667000Y88000D02*
X1669687Y85313D01*
G01X1658924Y89776D02*
X1656059Y92641D01*
G01X1659736Y89776D02*
X1658924D01*
G01X1666303Y83209D02*
X1659736Y89776D01*
G01X1678778Y83209D02*
X1666303D01*
G01X1682220Y79767D02*
X1678778Y83209D01*
G01X1697905Y79767D02*
X1682220D01*
G01X1701043Y76629D02*
X1697905Y79767D01*
G01X1702937Y76629D02*
X1701043D01*
G01X1705578Y73988D02*
X1702937Y76629D01*
G01X1722234Y73988D02*
X1705578D01*
G01X1707351Y83545D02*
X1751196D01*
G01X1703675Y87221D02*
X1707351Y83545D01*
G01X1699755Y87221D02*
X1703675D01*
G01X1698348Y88628D02*
X1699755Y87221D01*
G01X1682953Y88628D02*
X1698348D01*
G01X1676001Y95580D02*
X1682953Y88628D01*
G01X1682503Y87676D02*
X1675629Y94550D01*
G01X1689397Y87676D02*
X1682503D01*
G01X1689409Y87664D02*
X1689397Y87676D01*
G01X1692971Y87664D02*
X1689409D01*
G01X1692972Y87663D02*
X1692971Y87664D01*
G01X1694161Y87663D02*
X1692972D01*
G01X1694174Y87676D02*
X1694161Y87663D01*
G01X1697894Y87676D02*
X1694174D01*
G01X1699598Y85972D02*
X1697894Y87676D01*
G01X1703130Y85972D02*
X1699598D01*
G01X1707002Y82100D02*
X1703130Y85972D01*
G01X1743334Y82100D02*
X1707002D01*
G01X1706056Y75140D02*
X1755764D01*
G01X1702887Y78309D02*
X1706056Y75140D01*
G01X1701289Y78309D02*
X1702887D01*
G01X1698679Y80919D02*
X1701289Y78309D01*
G01X1682698Y80919D02*
X1698679D01*
G01X1679256Y84361D02*
X1682698Y80919D01*
G01X1666781Y84361D02*
X1679256D01*
G01X1660213Y90929D02*
X1666781Y84361D01*
G01X1659401Y90929D02*
X1660213D01*
G01X1655830Y94500D02*
X1659401Y90929D01*
G01X1686547Y93036D02*
X1682348Y97235D01*
G01X1702227Y93036D02*
X1686547D01*
G01X1703957Y94766D02*
X1702227Y93036D01*
G01X1714199Y91899D02*
X1711332Y94766D01*
G01X1679118Y93677D02*
X1676464Y96331D01*
G01X1680708Y93677D02*
X1679118D01*
G01X1684505Y89880D02*
X1680708Y93677D01*
G01X1701289Y89880D02*
X1684505D01*
G01X1702696Y88473D02*
X1701289Y89880D01*
G01X1706432Y88473D02*
X1702696D01*
G01X1707870Y87035D02*
X1706432Y88473D01*
G01X1709920Y87035D02*
X1707870D01*
G01X1712158Y84797D02*
X1709920Y87035D01*
G01X1706212Y80196D02*
X1744835D01*
G01X1703349Y83059D02*
X1706212Y80196D01*
G01X1684139Y83059D02*
X1703349D01*
G01X1678504Y88694D02*
X1684139Y83059D01*
G01X1676551Y88694D02*
X1678504D01*
G01X1675062Y90183D02*
X1676551Y88694D01*
G01X1675062Y91219D02*
Y90183D01*
G01X1658558Y93241D02*
X1655050Y96749D01*
G01X1660023Y93241D02*
X1658558D01*
G01X1660998Y94216D02*
X1660023Y93241D01*
G01X1664196Y94216D02*
X1660998D01*
G01X1668507Y89905D02*
X1664196Y94216D01*
G01X1674123Y89905D02*
X1668507D01*
G01X1677098Y86930D02*
X1674123Y89905D01*
G01X1677573Y86930D02*
X1677098D01*
G01X1664320Y154838D02*
G03X1665686Y156204I0J1366D01*
G01X1664122Y154838D02*
X1664320D01*
G01X1662354Y154106D02*
G02X1664122Y154838I1768J-1769D01*
G01X1660218Y151970D02*
X1662354Y154106D01*
G01X1659486Y150202D02*
G02X1660218Y151970I2501J0D01*
G01X1659486Y150197D02*
Y150202D01*
G01X1658878Y148730D02*
G03X1659486Y150197I-1466J1467D01*
G01X1658330Y148182D02*
X1658878Y148730D01*
G01X1657835Y146987D02*
G02X1658330Y148182I1690J0D01*
G01X1662877Y133131D02*
X1660985Y131239D01*
G01X1662879Y133131D02*
X1662877D01*
G01X1664586Y133838D02*
G03X1662879Y133131I0J-2414D01*
G01X1668047Y133838D02*
X1664586D01*
G01X1671709Y135355D02*
G02X1668047Y133838I-3662J3662D01*
G01X1672836Y136482D02*
X1671709Y135355D01*
G01X1673634Y136813D02*
G03X1672836Y136482I1J-1129D01*
G01X1676800Y136813D02*
X1673634D01*
G01X1680051Y135388D02*
G03X1676800Y136813I-3251J-2996D01*
G01X1680567Y134872D02*
X1680051Y135388D01*
G01X1681958Y134076D02*
G02X1680567Y134872I769J2958D01*
G01X1683573Y133407D02*
G03X1681958Y134076I-1615J-1615D01*
G01X1695984Y120996D02*
X1683573Y133407D01*
G01X1698606Y119910D02*
G02X1695984Y120996I0J3708D01*
G01X1700089Y119910D02*
X1698606D01*
G01X1700771Y120592D02*
G02X1700089Y119910I-682J0D01*
G01X1701573Y121394D02*
G03X1700771Y120592I0J-802D01*
G01X1701821Y121394D02*
X1701573D01*
G01X1702623Y120592D02*
G03X1701821Y121394I-802J0D01*
G01X1702623Y120581D02*
Y120592D01*
G01X1704475Y120581D02*
G02X1702623I-926J0D01*
G01X1704475Y120592D02*
Y120581D01*
G01X1705264Y121381D02*
G03X1704475Y120592I0J-789D01*
G01X1705538Y121381D02*
X1705264D01*
G01X1706327Y120592D02*
G03X1705538Y121381I-789J0D01*
G01X1707252Y119667D02*
G02X1706327Y120592I0J925D01*
G01X1707254Y119667D02*
X1707252D01*
G01X1708179Y120592D02*
G02X1707254Y119667I-925J0D01*
G01X1708179Y120593D02*
Y120592D01*
G01X1708882Y121296D02*
G03X1708179Y120593I0J-703D01*
G01X1709327Y121296D02*
X1708882D01*
G01X1710031Y120592D02*
G03X1709327Y121296I-704J0D01*
G01X1710713Y119910D02*
G02X1710031Y120592I0J682D01*
G01X1711201Y119910D02*
X1710713D01*
G01X1711883Y120592D02*
G02X1711201Y119910I-682J0D01*
G01X1712554Y121263D02*
G03X1711883Y120592I0J-671D01*
G01X1678816Y96144D02*
X1681631D01*
G01X1676982Y97978D02*
X1678816Y96144D01*
G01X1672483Y97978D02*
X1676982D01*
G01X1668763Y101698D02*
X1672483Y97978D01*
G01X1668763Y103124D02*
Y101698D01*
G01X1662696Y109191D02*
X1668763Y103124D01*
G01X1660985Y109191D02*
X1662696D01*
G01X1711911Y97447D02*
X1715337Y94021D01*
G01X1696251Y97447D02*
X1711911D01*
G01X1695407Y98291D02*
X1696251Y97447D01*
G01X1691382Y98291D02*
X1695407D01*
G01X1690265Y97174D02*
X1691382Y98291D01*
G01X1686141Y97174D02*
X1690265D01*
G01X1683749Y99566D02*
X1686141Y97174D01*
G01X1683749Y100074D02*
Y99566D01*
G01X1679047Y104776D02*
X1683749Y100074D01*
G01X1672374Y104776D02*
X1679047D01*
G01X1667238Y109912D02*
X1672374Y104776D01*
G01X1667238Y112387D02*
Y109912D01*
G01X1665532Y136142D02*
X1664136Y137538D01*
G01X1665782Y136038D02*
G02X1665532Y136142I1J354D01*
G01X1667335Y136038D02*
X1665782D01*
G01X1668849Y136665D02*
G02X1667335Y136038I-1514J1514D01*
G01X1670105Y137921D02*
X1668849Y136665D01*
G01X1676725Y140663D02*
G03X1670105Y137921I0J-9362D01*
G01X1678178Y140663D02*
X1676725D01*
G01X1679250Y140544D02*
G03X1678178Y140663I-1071J-4756D01*
G01X1680656Y139986D02*
G03X1679250Y140544I-2479J-4197D01*
G01X1681274Y139730D02*
G02X1680656Y139986I0J874D01*
G01X1681274Y139725D02*
Y139730D01*
G01X1685242Y139725D02*
X1681274D01*
G01X1688503Y138374D02*
G03X1685242Y139725I-3261J-3260D01*
G01X1691333Y135544D02*
X1688503Y138374D01*
G01X1691791Y134439D02*
G03X1691333Y135544I-1562J0D01*
G01X1691791Y132814D02*
Y134439D01*
G01X1691903Y132544D02*
G02X1691791Y132814I269J270D01*
G01X1692919Y131529D02*
X1691903Y132544D01*
G01X1695773Y131528D02*
G02X1692919Y131529I-1427J1426D01*
G01X1696746Y132501D02*
X1695773Y131528D01*
G01X1698056Y131190D02*
G03X1696746Y132501I-655J655D01*
G01X1696631Y129766D02*
X1698056Y131190D01*
G01X1697941Y128456D02*
G02X1696631Y129766I-655J655D01*
G01X1699421Y129935D02*
X1697941Y128456D01*
G01X1700731Y128625D02*
G03X1699421Y129935I-655J655D01*
G01X1698959Y126854D02*
X1700731Y128625D01*
G01X1698959Y126128D02*
G02Y126854I364J363D01*
G01X1699322Y125764D02*
X1698959Y126128D01*
G01X1700562Y125250D02*
G02X1699322Y125764I0J1753D01*
G01X1723099Y125250D02*
X1700562D01*
G01X1660056Y106970D02*
X1657835Y109191D01*
G01X1662344Y106970D02*
X1660056D01*
G01X1672118Y97196D02*
X1662344Y106970D01*
G01X1676662Y97196D02*
X1672118D01*
G01X1678667Y95191D02*
X1676662Y97196D01*
G01X1680965Y95191D02*
X1678667D01*
G01X1701582Y151277D02*
G02X1698927Y153139I0J2824D01*
G01X1702609Y151277D02*
X1701582D01*
G01X1707560Y149226D02*
G03X1702609Y151277I-4951J-4951D01*
G01X1715019Y141767D02*
X1707560Y149226D01*
G01X1653211Y152831D02*
X1652090Y151710D01*
G01X1653211Y157048D02*
Y152831D01*
G01X1696858Y123320D02*
X1717246D01*
G01X1696410Y123436D02*
G03X1696858Y123320I449J810D01*
G01X1696196Y123554D02*
X1696410Y123436D01*
G01X1695990Y123709D02*
G03X1696196Y123554I654J655D01*
G01X1695754Y123945D02*
X1695990Y123709D01*
G01X1695755Y124599D02*
G03X1695754Y123945I327J-328D01*
G01X1696082Y124926D02*
X1695755Y124599D01*
G01X1694772Y126236D02*
G02X1696082Y124926I655J-655D01*
G01X1693462Y127547D02*
G03X1694772Y126236I655J-656D01*
G01X1693477Y127563D02*
X1693462Y127547D01*
G01X1692168Y128872D02*
G02X1693477Y127563I654J-655D01*
G01X1692152Y128856D02*
X1692168Y128872D01*
G01X1690965Y128753D02*
G03X1692152Y128856I532J759D01*
G01X1688185Y131527D02*
X1690965Y128753D01*
G01X1688183Y132837D02*
G03X1688185Y131527I656J-654D01*
G01X1688997Y133652D02*
X1688183Y132837D01*
G01X1687685Y134962D02*
G02X1688997Y133652I656J-655D01*
G01X1686865Y134140D02*
X1687685Y134962D01*
G01X1685553Y135449D02*
G03X1686865Y134140I656J-655D01*
G01X1686217Y136114D02*
X1685553Y135449D01*
G01X1684905Y137423D02*
G02X1686217Y136114I656J-655D01*
G01X1684247Y136764D02*
X1684905Y137423D01*
G01X1682937Y136762D02*
G03X1684247Y136764I654J656D01*
G01X1682491Y137208D02*
X1682937Y136762D01*
G01X1681108Y137781D02*
G02X1682491Y137208I0J-1956D01*
G01X1680526Y137781D02*
X1681108D01*
G01X1679717Y138116D02*
G03X1680526Y137781I809J809D01*
G01X1679250Y138350D02*
G02X1679717Y138116I-119J-821D01*
G01X1679130Y138359D02*
G02X1679250Y138350I-2J-830D01*
G01X1673117Y138359D02*
X1679130D01*
G01X1672412Y138067D02*
G02X1673117Y138359I705J-705D01*
G01X1670561Y136216D02*
X1672412Y138067D01*
G01X1667235Y134838D02*
G03X1670561Y136216I0J4703D01*
G01X1662134Y134838D02*
X1667235D01*
G01X1660178Y134028D02*
G02X1662134Y134838I1956J-1957D01*
G01X1658150Y132000D02*
X1660178Y134028D01*
G01X1657835Y131239D02*
G02X1658150Y132000I1077J0D01*
G01X1655127Y141129D02*
X1654685Y140687D01*
G01X1656186Y143685D02*
G02X1655127Y141129I-3614J0D01*
G01X1656186Y143688D02*
Y143685D01*
G01X1657936Y145438D02*
G03X1656186Y143688I0J-1750D01*
G01X1658875Y145827D02*
G02X1657936Y145438I-939J939D01*
G01X1658936Y145888D02*
X1658875Y145827D01*
G01X1659386Y146974D02*
G02X1658936Y145888I-1535J0D01*
G01X1659826Y148036D02*
G03X1659386Y146974I1062J-1062D01*
G01X1659827Y148037D02*
X1659826Y148036D01*
G01X1661036Y148538D02*
G03X1659827Y148037I0J-1709D01*
G01X1661040Y148538D02*
X1661036D01*
G01X1662314Y149066D02*
G02X1661040Y148538I-1274J1273D01*
G01X1663254Y150006D02*
X1662314Y149066D01*
G01X1664689Y150716D02*
G03X1663254Y150006I333J-2479D01*
G01X1666012Y151264D02*
G02X1664689Y150716I-1323J1323D01*
G01X1666049Y151302D02*
X1666012Y151264D01*
G01X1666982Y151852D02*
G03X1666049Y151302I603J-2090D01*
G01X1667867Y152218D02*
G02X1666982Y151852I-885J887D01*
G01X1671283Y155634D02*
X1667867Y152218D01*
G01X1675223Y157266D02*
G03X1671283Y155634I0J-5572D01*
G01X1709028Y153697D02*
G03X1700411Y157266I-8617J-8618D01*
G01X1710672Y152053D02*
X1709028Y153697D01*
G01X1714274Y150561D02*
G02X1710672Y152053I0J5094D01*
G01X1662300Y96800D02*
X1664500Y99000D01*
G01X1656759Y96800D02*
X1662300D01*
G01X1655634Y97925D02*
X1656759Y96800D01*
G01X1711240Y154492D02*
G03X1716500Y152313I5260J5259D01*
G01X1709428Y156304D02*
X1711240Y154492D01*
G01X1668062Y155066D02*
X1669716Y156720D01*
G01X1667502Y154834D02*
G03X1668062Y155066I0J792D01*
G01X1666344Y154354D02*
G02X1667502Y154834I1158J-1157D01*
G01X1666343Y154353D02*
X1666344Y154354D01*
G01X1666130Y153840D02*
G02X1666343Y154353I727J-1D01*
G01X1666130Y153465D02*
Y153840D01*
G01X1665718Y152470D02*
G03X1666130Y153465I-995J995D01*
G01X1663938Y151733D02*
G03X1665718Y152470I0J2518D01*
G01X1663522Y151733D02*
X1663938D01*
G01X1662894Y151993D02*
G03X1663522Y151733I628J628D01*
G01X1661641Y151993D02*
G02X1662894I626J-626D01*
G01X1661296Y151648D02*
X1661641Y151993D01*
G01X1661099Y151375D02*
G02X1661296Y151648I949J-477D01*
G01X1660840Y150287D02*
G02X1661099Y151375I2413J0D01*
G01X1660840Y150282D02*
Y150287D01*
G01X1660985Y150137D02*
X1660840Y150282D01*
G01X1654694Y124940D02*
X1654686D01*
G01X1655598Y124034D02*
X1654694Y124940D01*
G01X1657035Y123438D02*
G02X1655598Y124034I0J2030D01*
G01X1661127Y123438D02*
X1657035D01*
G01X1662252Y123904D02*
G02X1661127Y123438I-1125J1125D01*
G01X1662486Y124138D02*
X1662252Y123904D01*
G01X1664176Y124838D02*
G03X1662486Y124138I0J-2390D01*
G01X1670077Y124838D02*
X1664176D01*
G01X1671421Y124281D02*
G03X1670077Y124838I-1344J-1343D01*
G01X1674057Y121645D02*
X1671421Y124281D01*
G01X1675301Y119549D02*
G03X1674057Y121645I-4728J-1389D01*
G01X1675595Y118839D02*
G02X1675301Y119549I710J710D01*
G01X1675720Y118714D02*
X1675595Y118839D01*
G01X1676173Y117620D02*
G03X1675720Y118714I-1547J0D01*
G01X1676621Y116540D02*
G02X1676173Y117620I1080J1081D01*
G01X1676934Y116226D02*
X1676621Y116540D01*
G01X1677104Y116056D02*
X1676934Y116226D01*
G01X1677685Y115815D02*
G02X1677104Y116056I0J822D01*
G01X1683493Y115815D02*
X1677685D01*
G01X1687250Y114259D02*
G03X1683493Y115815I-3757J-3757D01*
G01X1692877Y108632D02*
X1687250Y114259D01*
G01X1694477Y107969D02*
G02X1692877Y108632I0J2263D01*
G01X1695538Y107969D02*
X1694477D01*
G01X1696464Y108895D02*
G02X1695538Y107969I-926J0D01*
G01X1696464Y109753D02*
Y108895D01*
G01X1698316Y109753D02*
G03X1696464I-926J0D01*
G01X1698316Y108907D02*
Y109753D01*
G01X1700168Y108907D02*
G02X1698316I-926J0D01*
G01X1700168Y109755D02*
Y108907D01*
G01X1702020Y109755D02*
G03X1700168I-926J0D01*
G01X1702020Y108885D02*
Y109755D01*
G01X1703872Y108885D02*
G02X1702020I-926J0D01*
G01X1703872Y109659D02*
Y108885D01*
G01X1705724Y109659D02*
G03X1703872I-926J0D01*
G01X1705724Y108864D02*
Y109659D01*
G01X1707576Y108864D02*
G02X1705724I-926J0D01*
G01X1707576Y109762D02*
Y108864D01*
G01X1709428Y109762D02*
G03X1707576I-926J0D01*
G01X1709428Y108895D02*
Y109762D01*
G01X1710354Y107969D02*
G02X1709428Y108895I0J926D01*
G01X1712246Y107969D02*
X1710354D01*
G01X1662286Y141138D02*
G02X1660985Y140688I-1113J1113D01*
G01X1662961Y141814D02*
X1662286Y141138D01*
G01X1663986Y142238D02*
G03X1662961Y141814I0J-1451D01*
G01X1668331Y142238D02*
X1663986D01*
G01X1671795Y143673D02*
G02X1668331Y142238I-3464J3463D01*
G01X1672406Y144284D02*
X1671795Y143673D01*
G01X1674912Y145322D02*
G03X1672406Y144284I0J-3544D01*
G01X1690708Y145322D02*
X1674912D01*
G01X1695114Y143497D02*
G03X1690708Y145322I-4406J-4406D01*
G01X1696719Y142832D02*
G02X1695114Y143497I0J2270D01*
G01X1697549Y142832D02*
X1696719D01*
G01X1701972Y141000D02*
G03X1697549Y142832I-4423J-4423D01*
G01X1702521Y140451D02*
X1701972Y141000D01*
G01X1702521Y139353D02*
G03Y140451I-550J549D01*
G01X1702520Y139352D02*
X1702521Y139353D01*
G01X1702520Y138254D02*
G02Y139352I550J549D01*
G01X1702732Y138042D02*
X1702520Y138254D01*
G01X1703830Y138042D02*
G02X1702732I-549J550D01*
G01X1703831Y138043D02*
X1703830Y138042D01*
G01X1705005D02*
G03X1703831Y138043I-588J-587D01*
G01X1705141Y137906D02*
X1705005Y138042D01*
G01X1705140Y136732D02*
G03X1705141Y137906I-587J588D01*
G01X1705140Y135634D02*
G02Y136732I550J549D01*
G01X1705352Y135422D02*
X1705140Y135634D01*
G01X1706450Y135422D02*
G02X1705352I-549J550D01*
G01X1706451Y135423D02*
X1706450Y135422D01*
G01X1707549Y135423D02*
G03X1706451I-549J-550D01*
G01X1708447Y134525D02*
X1707549Y135423D01*
G01X1715598Y131564D02*
G02X1708447Y134525I-1J10113D01*
G01X1671603Y95580D02*
X1676001D01*
G01X1662189Y104999D02*
X1671603Y95580D01*
G01X1657354Y100146D02*
X1658100Y99400D01*
G01X1652200Y100146D02*
X1657354D01*
G01X1659962Y101262D02*
X1658100Y99400D01*
G01X1664696Y101262D02*
X1659962D01*
G01X1666504Y99454D02*
X1664696Y101262D01*
G01X1671407Y94550D02*
X1666504Y99454D01*
G01X1675629Y94550D02*
X1671407D01*
G01X1658100Y99400D02*
X1658154D01*
G01X1653186Y140740D02*
G02X1654685Y143837I3949J0D01*
G01X1654754Y139172D02*
G02X1653186Y140740I0J1568D01*
G01X1657949Y139172D02*
X1654754D01*
G01X1659486Y140709D02*
G02X1657949Y139172I-1537J0D01*
G01X1661115Y142338D02*
G03X1659486Y140709I0J-1629D01*
G01X1661315Y142338D02*
X1661115D01*
G01X1662290Y142742D02*
G02X1661315Y142338I-975J975D01*
G01X1662291Y142742D02*
X1662290D01*
G01X1663488Y143238D02*
G03X1662291Y142742I0J-1692D01*
G01X1666205Y143238D02*
X1663488D01*
G01X1670828Y145105D02*
G02X1666205Y143238I-4623J4790D01*
G01X1676043Y147200D02*
G03X1670828Y145105I0J-7538D01*
G01X1692045Y147200D02*
X1676043D01*
G01X1695572Y145739D02*
G03X1692045Y147200I-3527J-3527D01*
G01X1698510Y144709D02*
G02X1695572Y145739I0J4705D01*
G01X1699672Y144709D02*
X1698510D01*
G01X1702498Y143175D02*
G03X1699672Y144709I-4001J-4001D01*
G01X1710227Y135446D02*
X1702498Y143175D01*
G01X1712056Y134688D02*
G02X1710227Y135446I0J2586D01*
G01X1723584Y134688D02*
X1712056D01*
G01X1656159Y117142D02*
X1654673Y118628D01*
G01X1656159Y112954D02*
Y117142D01*
G01X1656160Y112953D02*
X1656159Y112954D01*
G01X1656160Y111707D02*
Y112953D01*
G01X1657123Y110744D02*
X1656160Y111707D01*
G01X1662206Y110744D02*
X1657123D01*
G01X1669514Y103436D02*
X1662206Y110744D01*
G01X1669514Y102010D02*
Y103436D01*
G01X1672743Y98781D02*
X1669514Y102010D01*
G01X1677809Y98781D02*
X1672743D01*
G01X1679294Y97296D02*
X1677809Y98781D01*
G01X1682109Y97296D02*
X1679294D01*
G01X1682170Y97235D02*
X1682109Y97296D01*
G01X1682348Y97235D02*
X1682170D01*
G01X1711332Y94766D02*
X1703957D01*
G01X1653011Y112953D02*
X1651948Y114016D01*
G01X1653011Y108585D02*
Y112953D01*
G01X1655377Y106219D02*
X1653011Y108585D01*
G01X1662032Y106219D02*
X1655377D01*
G01X1671920Y96331D02*
X1662032Y106219D01*
G01X1676464Y96331D02*
X1671920D01*
G01X1711153Y137200D02*
G03X1712963Y136450I1810J1809D01*
G01X1710808Y137545D02*
X1711153Y137200D01*
G01X1710808Y138237D02*
G03Y137545I345J-346D01*
G01X1711334Y138763D02*
X1710808Y138237D01*
G01X1710023Y140072D02*
G02X1711334Y138763I655J-655D01*
G01X1709807Y139856D02*
X1710023Y140072D01*
G01X1708497Y141166D02*
G03X1709807Y139856I655J-655D01*
G01X1708714Y141383D02*
X1708497Y141166D01*
G01X1707403Y142692D02*
G02X1708714Y141383I655J-655D01*
G01X1707187Y142476D02*
X1707403Y142692D01*
G01X1705877Y143786D02*
G03X1707187Y142476I655J-655D01*
G01X1706094Y144003D02*
X1705877Y143786D01*
G01X1704783Y145312D02*
G02X1706094Y144003I655J-654D01*
G01X1704567Y145096D02*
X1704783Y145312D01*
G01X1703257Y145096D02*
G03X1704567I655J655D01*
G01X1702112Y146241D02*
X1703257Y145096D01*
G01X1699259Y147423D02*
G02X1702112Y146241I0J-4034D01*
G01X1698396Y147423D02*
X1699259D01*
G01X1696400Y148250D02*
G03X1698396Y147423I1996J1996D01*
G01X1695944Y148706D02*
X1696400Y148250D01*
G01X1695007Y149095D02*
G02X1695944Y148706I0J-1323D01*
G01X1674084Y149095D02*
X1695007D01*
G01X1671115Y147865D02*
G02X1674084Y149095I2969J-2969D01*
G01X1667922Y144672D02*
X1671115Y147865D01*
G01X1666874Y144238D02*
G03X1667922Y144672I0J1482D01*
G01X1662452Y144238D02*
X1666874D01*
G01X1660985Y143837D02*
G02X1662452Y144238I1467J-2483D01*
G01X1701139Y112772D02*
X1724430D01*
G01X1686417Y118870D02*
G03X1701139Y112772I14722J14722D01*
G01X1682739Y122548D02*
X1686417Y118870D01*
G01X1679250Y124555D02*
G02X1682739Y122548I-1976J-7472D01*
G01X1677274Y124812D02*
G02X1679250Y124555I-1J-7729D01*
G01X1676370Y124812D02*
X1677274D01*
G01X1675279Y125264D02*
G03X1676370Y124812I1091J1091D01*
G01X1672445Y126438D02*
G02X1675279Y125264I0J-4008D01*
G01X1662227Y126438D02*
X1672445D01*
G01X1657269Y128492D02*
G03X1662227Y126438I4958J4957D01*
G01X1655305Y130456D02*
X1657269Y128492D01*
G01X1654685Y131239D02*
G03X1655305Y130456I3682J2279D01*
G01X1661458Y146987D02*
X1660985D01*
G01X1662272Y147324D02*
G02X1661458Y146987I-814J814D01*
G01X1662854Y147906D02*
X1662272Y147324D01*
G01X1664622Y148638D02*
G03X1662854Y147906I0J-2501D01*
G01X1667298Y148638D02*
X1664622D01*
G01X1668472Y149124D02*
G02X1667298Y148638I-1174J1175D01*
G01X1673854Y154506D02*
X1668472Y149124D01*
G01X1676046Y155414D02*
G03X1673854Y154506I0J-3101D01*
G01X1688253Y155414D02*
X1676046D01*
G01X1689143Y154524D02*
G03X1688253Y155414I-890J0D01*
G01X1689143Y154093D02*
Y154524D01*
G01X1690995Y154093D02*
G02X1689143I-926J0D01*
G01X1690995Y154440D02*
Y154093D01*
G01X1692847Y154440D02*
G03X1690995I-926J0D01*
G01X1692847Y154154D02*
Y154440D01*
G01X1694699Y154154D02*
G02X1692847I-926J0D01*
G01X1694699Y154524D02*
Y154154D01*
G01X1695160Y154985D02*
G03X1694699Y154524I0J-461D01*
G01X1700157Y154985D02*
X1695160D01*
G01X1707634Y151888D02*
G03X1700157Y154985I-7477J-7477D01*
G01X1713296Y146226D02*
X1707634Y151888D01*
G01X1661597Y114879D02*
X1660985Y115491D01*
G01X1662660Y114879D02*
X1661597D01*
G01X1663523Y114016D02*
X1662660Y114879D01*
G01X1667970Y114016D02*
X1663523D01*
G01X1668813Y113173D02*
X1667970Y114016D01*
G01X1668813Y109413D02*
Y113173D01*
G01X1672699Y105527D02*
X1668813Y109413D01*
G01X1679795Y105527D02*
X1672699D01*
G01X1684669Y100653D02*
X1679795Y105527D01*
G01X1698301Y100653D02*
X1684669D01*
G01X1700465Y98489D02*
X1698301Y100653D01*
G01X1712333Y98489D02*
X1700465D01*
G01X1659458Y138210D02*
G02X1657836Y137538I-1622J1622D01*
G01X1660036Y138788D02*
X1659458Y138210D01*
G01X1660881Y139138D02*
G03X1660036Y138788I0J-1195D01*
G01X1667480Y139138D02*
X1660881D01*
G01X1671102Y140638D02*
G02X1667480Y139138I-3622J3623D01*
G01X1672849Y142385D02*
X1671102Y140638D01*
G01X1674937Y143250D02*
G03X1672849Y142385I0J-2953D01*
G01X1687584Y143250D02*
X1674937D01*
G01X1692224Y141328D02*
G03X1687584Y143250I-4640J-4640D01*
G01X1692394Y141158D02*
X1692224Y141328D01*
G01X1693499Y140700D02*
G02X1692394Y141158I0J1562D01*
G01X1695587Y140700D02*
X1693499D01*
G01X1698439Y139518D02*
G03X1695587Y140700I-2854J-2854D01*
G01X1699374Y138583D02*
X1698439Y139518D01*
G01X1699375Y137273D02*
G03X1699374Y138583I-655J655D01*
G01X1699133Y137031D02*
X1699375Y137273D01*
G01X1700443Y135721D02*
G02X1699133Y137031I-655J655D01*
G01X1700684Y135962D02*
X1700443Y135721D01*
G01X1701995Y134653D02*
G03X1700684Y135962I-656J655D01*
G01X1701832Y134490D02*
X1701995Y134653D01*
G01X1703142Y133180D02*
G02X1701832Y134490I-655J655D01*
G01X1703304Y133342D02*
X1703142Y133180D01*
G01X1704615Y132033D02*
G03X1703304Y133342I-655J655D01*
G01X1704460Y131878D02*
X1704615Y132033D01*
G01X1705770Y130568D02*
G02X1704460Y131878I-655J655D01*
G01X1705987Y130785D02*
X1705770Y130568D01*
G01X1707171Y130786D02*
G03X1705987Y130785I-592J-592D01*
G01X1707764Y130194D02*
X1707171Y130786D01*
G01X1711808Y128519D02*
G02X1707764Y130194I0J5719D01*
G01X1736127Y128519D02*
X1711808D01*
G01X1711164Y101310D02*
G03X1713016I926J0D01*
G01X1711164Y101579D02*
Y101310D01*
G01X1709312Y101579D02*
G02X1711164I926J0D01*
G01X1709312Y101277D02*
Y101579D01*
G01X1707460Y101277D02*
G03X1709312I926J0D01*
G01X1707460Y101579D02*
Y101277D01*
G01X1705608Y101579D02*
G02X1707460I926J0D01*
G01X1705608Y101282D02*
Y101579D01*
G01X1703756Y101282D02*
G03X1705608I926J0D01*
G01X1703756Y101579D02*
Y101282D01*
G01X1702830Y102505D02*
G02X1703756Y101579I0J-926D01*
G01X1687006Y102505D02*
X1702830D01*
G01X1685241Y103235D02*
G03X1687006Y102505I1765J1770D01*
G01X1679487Y108971D02*
X1685241Y103235D01*
G01X1678997Y109461D02*
X1679487Y108971D01*
G01X1677022Y110279D02*
G02X1678997Y109461I0J-2793D01*
G01X1676272Y110013D02*
G02X1677022Y110279I655J-655D01*
G01X1674528Y108268D02*
X1676272Y110013D01*
G01X1673218Y109578D02*
G03X1674528Y108268I655J-655D01*
G01X1674962Y111323D02*
X1673218Y109578D01*
G01X1674962Y112633D02*
G02Y111323I-654J-655D01*
G01X1672855Y114740D02*
X1674962Y112633D01*
G01X1672567Y115277D02*
G03X1672855Y114740I1035J209D01*
G01X1672152Y116279D02*
G02X1672567Y115277I-1002J-1002D01*
G01X1669257Y119168D02*
X1672152Y116279D01*
G01X1666670Y120238D02*
G02X1669257Y119168I0J-3662D01*
G01X1654945Y120238D02*
X1666670D01*
G01X1654578Y120390D02*
G03X1654945Y120238I367J367D01*
G01X1654578Y121683D02*
G03Y120390I646J-646D01*
G01X1654685Y121790D02*
X1654578Y121683D01*
G01X1706924Y147125D02*
X1715808Y138241D01*
G01X1701432Y149400D02*
G02X1706924Y147125I0J-7767D01*
G01X1699335Y149400D02*
X1701432D01*
G01X1697653Y150097D02*
G03X1699335Y149400I1682J1681D01*
G01X1697217Y150533D02*
X1697653Y150097D01*
G01X1696212Y150950D02*
G02X1697217Y150533I-1J-1422D01*
G01X1686978Y150950D02*
X1696212D01*
G01X1686052Y151876D02*
G03X1686978Y150950I926J0D01*
G01X1686052Y152617D02*
Y151876D01*
G01X1684200Y152617D02*
G02X1686052I926J0D01*
G01X1684200Y151876D02*
Y152617D01*
G01X1682348Y151876D02*
G03X1684200I926J0D01*
G01X1682348Y152617D02*
Y151876D01*
G01X1680496Y152617D02*
G02X1682348I926J0D01*
G01X1680496Y151876D02*
Y152617D01*
G01X1678644Y151876D02*
G03X1680496I926J0D01*
G01X1678644Y152609D02*
Y151876D01*
G01X1676792Y152609D02*
G02X1678644I926J0D01*
G01X1676792Y151876D02*
Y152609D01*
G01X1675866Y150950D02*
G03X1676792Y151876I0J926D01*
G01X1672892Y150950D02*
X1675866D01*
G01X1671710Y150460D02*
G02X1672892Y150950I1182J-1181D01*
G01X1667242Y145992D02*
X1671710Y150460D01*
G01X1665905Y145438D02*
G03X1667242Y145992I0J1890D01*
G01X1661093Y145438D02*
X1665905D01*
G01X1659886Y144938D02*
G02X1661093Y145438I1207J-1207D01*
G01X1659386Y144438D02*
X1659886Y144938D01*
G01X1657835Y143837D02*
G03X1659386Y144438I95J2057D01*
G01X1667993Y132838D02*
G03X1664135Y131239I0J-5454D01*
G01X1670310Y132838D02*
X1667993D01*
G01X1671689Y133409D02*
G02X1670310Y132838I-1379J1380D01*
G01X1673453Y135173D02*
X1671689Y133409D01*
G01X1675045Y135896D02*
G03X1673453Y135173I166J-2479D01*
G01X1675553Y135869D02*
G03X1675045Y135896I-505J-4700D01*
G01X1677879Y134906D02*
G03X1675553Y135869I-2324J-2324D01*
G01X1679250Y133533D02*
X1677879Y134906D01*
G01X1679542Y133241D02*
X1679250Y133533D01*
G01X1681341Y132249D02*
G02X1679542Y133241I814J3604D01*
G01X1682525Y131758D02*
G03X1681341Y132249I-1185J-1184D01*
G01X1683042Y131241D02*
X1682525Y131758D01*
G01X1683042Y130205D02*
G03Y131241I-517J518D01*
G01X1682905Y130068D02*
X1683042Y130205D01*
G01X1684215Y128758D02*
G02X1682905Y130068I-655J655D01*
G01X1685525Y127448D02*
G03X1684215Y128758I-655J655D01*
G01X1686835Y126138D02*
G02X1685525Y127448I-655J655D01*
G01X1688145Y124828D02*
G03X1686835Y126138I-655J655D01*
G01X1689455Y123518D02*
G02X1688145Y124828I-655J655D01*
G01X1690765Y122208D02*
G03X1689455Y123518I-655J655D01*
G01X1692075Y120898D02*
G02X1690765Y122208I-655J655D01*
G01X1693385Y120898D02*
G03X1692075I-655J-654D01*
G01X1695285Y118999D02*
X1693385Y120898D01*
G01X1695455Y118833D02*
G02X1695285Y118999I5789J6099D01*
G01X1697413Y118022D02*
G02X1695455Y118833I0J2769D01*
G01X1702071Y118022D02*
X1697413D01*
G01X1702695Y117398D02*
G03X1702071Y118022I-624J0D01*
G01X1703310Y116783D02*
G02X1702695Y117398I0J615D01*
G01X1703932Y116783D02*
X1703310D01*
G01X1704547Y117398D02*
G02X1703932Y116783I-615J0D01*
G01X1705173Y118024D02*
G03X1704547Y117398I0J-626D01*
G01X1705773Y118024D02*
X1705173D01*
G01X1706399Y117398D02*
G03X1705773Y118024I-626J0D01*
G01X1707025Y116772D02*
G02X1706399Y117398I0J626D01*
G01X1707625Y116772D02*
X1707025D01*
G01X1708251Y117398D02*
G02X1707625Y116772I-626J0D01*
G01X1708875Y118022D02*
G03X1708251Y117398I0J-624D01*
G01X1715904Y118022D02*
X1708875D01*
G01X1655121Y133954D02*
X1654686Y134389D01*
G01X1656199Y131353D02*
G03X1655121Y133954I-3677J0D01*
G01X1656199Y131352D02*
Y131353D01*
G01X1657932Y129619D02*
G02X1656199Y131352I0J1733D01*
G01X1668761Y129620D02*
X1657932Y129619D01*
G01X1670796Y129620D02*
X1668761D01*
G01X1675166Y127810D02*
G03X1670796Y129620I-4370J-4370D01*
G01X1678285Y126518D02*
G02X1675166Y127810I0J4411D01*
G01X1680255Y126518D02*
X1678285D01*
G01X1683534Y125160D02*
G03X1680255Y126518I-3279J-3279D01*
G01X1690318Y118376D02*
X1683534Y125160D01*
G01X1690509Y118229D02*
G02X1690318Y118376I9750J12865D01*
G01X1701821Y114658D02*
G02X1690509Y118229I0J19702D01*
G01X1701828Y114656D02*
X1701821Y114658D01*
G01X1709484Y114646D02*
X1701828Y114656D01*
G01X1710265Y115425D02*
G02X1709484Y114646I-780J1D01*
G01X1710265Y115426D02*
Y115425D01*
G01X1710980Y116138D02*
G03X1710265Y115426I-2J-713D01*
G01X1711406Y116137D02*
X1710980Y116138D01*
G01X1712117Y115423D02*
G03X1711406Y116137I-713J1D01*
G01X1712117Y115422D02*
Y115423D01*
G01X1712896Y114641D02*
G02X1712117Y115422I1J780D01*
G01X1659410Y113916D02*
X1657835Y115491D01*
G01X1661496Y113916D02*
X1659410D01*
G01X1662500Y112912D02*
X1661496Y113916D01*
G01X1662500Y111890D02*
Y112912D01*
G01X1663837Y110553D02*
X1662500Y111890D01*
G01X1665534Y110553D02*
X1663837D01*
G01X1672475Y103612D02*
X1665534Y110553D01*
G01X1672475Y102902D02*
Y103612D01*
G01X1674525Y100852D02*
X1672475Y102902D01*
G01X1680467Y100852D02*
X1674525D01*
G01X1680470Y100849D02*
X1680467Y100852D01*
G01X1680875Y100849D02*
X1680470D01*
G01X1681915Y99809D02*
X1680875Y100849D01*
G01X1681915Y99404D02*
Y99809D01*
G01X1685521Y95798D02*
X1681915Y99404D01*
G01X1690682Y95798D02*
X1685521D01*
G01X1691863Y96979D02*
X1690682Y95798D01*
G01X1694940Y96979D02*
X1691863D01*
G01X1695624Y96295D02*
X1694940Y96979D01*
G01X1701838Y96295D02*
X1695624D01*
G01X1702168Y95965D02*
X1701838Y96295D01*
G01X1711763Y95965D02*
X1702168D01*
G01X1714859Y92869D02*
X1711763Y95965D01*
G01X1662266Y122318D02*
G02X1660985Y121790I-1275J1275D01*
G01X1662429Y122481D02*
X1662266Y122318D01*
G01X1664739Y123438D02*
G03X1662429Y122481I0J-3266D01*
G01X1666752Y123438D02*
X1664739D01*
G01X1669128Y122457D02*
G03X1666752Y123438I-2376J-2387D01*
G01X1673735Y117869D02*
X1669128Y122457D01*
G01X1674281Y116552D02*
G03X1673735Y117869I-1858J1D01*
G01X1674750Y115680D02*
G02X1674281Y116552I1211J1213D01*
G01X1676980Y113452D02*
X1674750Y115680D01*
G01X1678447Y112844D02*
G02X1676980Y113452I2J2078D01*
G01X1679250Y112499D02*
G02X1678447Y112844I34J1185D01*
G01X1680124Y112847D02*
G02X1679250Y112499I-840J837D01*
G01X1680639Y113363D02*
X1680124Y112847D01*
G01X1681949Y112055D02*
G03X1680639Y113363I-655J654D01*
G01X1683261Y110746D02*
G02X1681949Y112055I-656J655D01*
G01X1684475Y111962D02*
X1683261Y110746D01*
G01X1685784Y110656D02*
G03X1684475Y111962I-654J653D01*
G01X1684742Y109608D02*
X1685784Y110656D01*
G01X1686056Y108301D02*
G02X1684742Y109608I-657J653D01*
G01X1687608Y109858D02*
X1686056Y108301D01*
G01X1688919Y108552D02*
G03X1687608Y109858I-655J653D01*
G01X1686648Y106271D02*
X1688919Y108552D01*
G01X1686650Y105045D02*
G02X1686648Y106271I612J614D01*
G01X1686742Y104965D02*
G02X1686650Y105045I560J737D01*
G01X1687244Y104582D02*
X1686742Y104965D01*
G01X1687806Y104392D02*
G02X1687244Y104582I0J926D01*
G01X1689791Y104392D02*
X1687806D01*
G01X1690633Y105234D02*
G02X1689791Y104392I-842J0D01*
G01X1691589Y106190D02*
G03X1690633Y105234I0J-956D01*
G01X1691629Y106190D02*
X1691589D01*
G01X1692485Y105334D02*
G03X1691629Y106190I-856J0D01*
G01X1692485Y105234D02*
Y105334D01*
G01X1693327Y104392D02*
G02X1692485Y105234I0J842D01*
G01X1693495Y104392D02*
X1693327D01*
G01X1694337Y105234D02*
G02X1693495Y104392I-842J0D01*
G01X1695175Y106072D02*
G03X1694337Y105234I0J-838D01*
G01X1695351Y106072D02*
X1695175D01*
G01X1696189Y105234D02*
G03X1695351Y106072I-838J0D01*
G01X1697031Y104392D02*
G02X1696189Y105234I0J842D01*
G01X1697199Y104392D02*
X1697031D01*
G01X1698041Y105234D02*
G02X1697199Y104392I-842J0D01*
G01X1698883Y106076D02*
G03X1698041Y105234I0J-842D01*
G01X1699051Y106076D02*
X1698883D01*
G01X1699893Y105234D02*
G03X1699051Y106076I-842J0D01*
G01X1700735Y104392D02*
G02X1699893Y105234I0J842D01*
G01X1700903Y104392D02*
X1700735D01*
G01X1701745Y105234D02*
G02X1700903Y104392I-842J0D01*
G01X1702587Y106076D02*
G03X1701745Y105234I0J-842D01*
G01X1702755Y106076D02*
X1702587D01*
G01X1703597Y105234D02*
G03X1702755Y106076I-842J0D01*
G01X1704439Y104392D02*
G02X1703597Y105234I0J842D01*
G01X1704607Y104392D02*
X1704439D01*
G01X1705449Y105234D02*
G02X1704607Y104392I-842J0D01*
G01X1706291Y106076D02*
G03X1705449Y105234I0J-842D01*
G01X1706459Y106076D02*
X1706291D01*
G01X1707301Y105234D02*
G03X1706459Y106076I-842J0D01*
G01X1708143Y104392D02*
G02X1707301Y105234I0J842D01*
G01X1708311Y104392D02*
X1708143D01*
G01X1709153Y105234D02*
G02X1708311Y104392I-842J0D01*
G01X1709996Y106077D02*
G03X1709153Y105234I0J-843D01*
G01X1710164Y106077D02*
X1709996D01*
G01X1711005Y105236D02*
G03X1710164Y106077I-841J0D01*
G01X1711005Y104878D02*
Y105236D01*
G01X1711490Y104392D02*
G02X1711005Y104878I0J485D01*
G01X1711976Y104392D02*
X1711490D01*
G01X1714876Y105593D02*
G02X1711976Y104392I-2900J2900D01*
G01X1662467Y156069D02*
Y156659D01*
G01X1662122Y155236D02*
G03X1662467Y156069I-833J833D01*
G01X1661827Y154941D02*
X1662122Y155236D01*
G01X1657836Y153288D02*
G03X1661827Y154941I0J5644D01*
G01X1701266Y168444D02*
G02X1720179Y160610I0J-26747D01*
G01X1695845Y168444D02*
X1701266D01*
G01X1692831Y167196D02*
G02X1695845Y168444I3014J-3015D01*
G01X1688917Y163282D02*
X1692831Y167196D01*
G01X1683883Y161197D02*
G03X1688917Y163282I0J7120D01*
G01X1677177Y161197D02*
X1683883D01*
G01X1666555Y157811D02*
G02X1677177Y161197I10622J-14968D01*
G01X1666220Y157488D02*
G02X1666555Y157811I8957J-8954D01*
G01X1666218Y157486D02*
X1666220Y157488D01*
G01X1665686Y156204D02*
G02X1666218Y157486I1817J-3D01*
G01X1660583Y200646D02*
X1660440Y200789D01*
G01X1660583Y200245D02*
Y200646D01*
G01X1661680Y199148D02*
X1660583Y200245D01*
G01X1669522Y199148D02*
X1661680D01*
G01X1673348Y202974D02*
X1669522Y199148D01*
G01X1677304Y202974D02*
X1673348D01*
G01X1680908Y206578D02*
X1677304Y202974D01*
G01X1718993Y206578D02*
X1680908D01*
G01X1659310Y165219D02*
X1658500Y164409D01*
G01X1659310Y166496D02*
Y165219D01*
G01X1659285Y166521D02*
X1659310Y166496D01*
G01X1659285Y167064D02*
Y166521D01*
G01X1660037Y167816D02*
X1659285Y167064D01*
G01X1665508Y167816D02*
X1660037D01*
G01X1666341Y168649D02*
X1665508Y167816D01*
G01X1667404Y168649D02*
X1666341D01*
G01X1670439Y171684D02*
X1667404Y168649D01*
G01X1670439Y176299D02*
Y171684D01*
G01X1676895Y182755D02*
X1670439Y176299D01*
G01X1676895Y185475D02*
Y182755D01*
G01X1679300Y187880D02*
X1676895Y185475D01*
G01X1682155Y187880D02*
X1679300D01*
G01X1689468Y180567D02*
X1682155Y187880D01*
G01X1701866Y180567D02*
X1689468D01*
G01X1704388Y183089D02*
X1701866Y180567D01*
G01X1714192Y183089D02*
X1704388D01*
G01X1652321Y158000D02*
X1650852D01*
G01X1654006Y159685D02*
X1652321Y158000D01*
G01X1654638Y159685D02*
X1654006D01*
G01X1686474Y211842D02*
X1713429D01*
G01X1682779Y215537D02*
X1686474Y211842D01*
G01X1661155Y215537D02*
X1682779D01*
G01X1655628Y221064D02*
X1661155Y215537D01*
G01X1655296Y205485D02*
X1653975Y206806D01*
G01X1664548Y205485D02*
X1655296D01*
G01X1671591Y212528D02*
X1664548Y205485D01*
G01X1680083Y212528D02*
X1671591D01*
G01X1683025Y209586D02*
X1680083Y212528D01*
G01X1714469Y209586D02*
X1683025D01*
G01X1693469Y217858D02*
X1688880Y222447D01*
G01X1717397Y224322D02*
X1710933Y217858D01*
G01X1657519Y215629D02*
X1659643Y213505D01*
G01X1652467Y215629D02*
X1657519D01*
G01X1650688Y217408D02*
X1652467Y215629D01*
G01X1654225Y158062D02*
X1653211Y157048D01*
G01X1658972Y158062D02*
X1654225D01*
G01X1659503Y158593D02*
X1658972Y158062D01*
G01X1659503Y160351D02*
Y158593D01*
G01X1660221Y161069D02*
X1659503Y160351D01*
G01X1661963Y161069D02*
X1660221D01*
G01X1668973Y168079D02*
X1661963Y161069D01*
G01X1679079Y168079D02*
X1668973D01*
G01X1687739Y176739D02*
X1679079Y168079D01*
G01X1706661Y176739D02*
X1687739D01*
G01X1708350Y175050D02*
X1706661Y176739D01*
G01X1663566Y212657D02*
Y213009D01*
G01X1662458Y211549D02*
X1663566Y212657D01*
G01X1658239Y211549D02*
X1662458D01*
G01X1655568Y214220D02*
X1658239Y211549D01*
G01X1651884Y214220D02*
X1655568D01*
G01X1711279Y205326D02*
X1718474D01*
G01X1711278Y205325D02*
X1711279Y205326D01*
G01X1701506Y205325D02*
X1711278D01*
G01X1701505Y205326D02*
X1701506Y205325D01*
G01X1694924Y205326D02*
X1701505D01*
G01X1694923Y205325D02*
X1694924Y205326D01*
G01X1688271Y205325D02*
X1694923D01*
G01X1688270Y205326D02*
X1688271Y205325D01*
G01X1681427Y205326D02*
X1688270D01*
G01X1675595Y199494D02*
X1681427Y205326D01*
G01X1672015Y199494D02*
X1675595D01*
G01X1670321Y197800D02*
X1672015Y199494D01*
G01X1654956Y197800D02*
X1670321D01*
G01X1651536Y162735D02*
X1651172D01*
G01X1691909Y214098D02*
X1712493D01*
G01X1687417Y218590D02*
X1691909Y214098D01*
G01X1660900Y169400D02*
X1659495Y170805D01*
G01X1667092Y169400D02*
X1660900D01*
G01X1669688Y171996D02*
X1667092Y169400D01*
G01X1669688Y177788D02*
Y171996D01*
G01X1673337Y181437D02*
X1669688Y177788D01*
G01X1673337Y184375D02*
Y181437D01*
G01X1675077Y186115D02*
X1673337Y184375D01*
G01X1675078Y186115D02*
X1675077D01*
G01X1677595Y188632D02*
X1675078Y186115D01*
G01X1682467Y188632D02*
X1677595D01*
G01X1683109Y187990D02*
X1682467Y188632D01*
G01X1687190Y187990D02*
X1683109D01*
G01X1689690Y190490D02*
X1687190Y187990D01*
G01X1689690Y195690D02*
Y190490D01*
G01X1690352Y196352D02*
X1689690Y195690D01*
G01X1701727Y196352D02*
X1690352D01*
G01X1704483Y193596D02*
X1701727Y196352D01*
G01X1704483Y187217D02*
Y193596D01*
G01X1706600Y185100D02*
X1704483Y187217D01*
G01X1710000Y185100D02*
X1706600D01*
G01X1711676Y186776D02*
X1710000Y185100D01*
G01X1729676Y186776D02*
X1711676D01*
G01X1700411Y157266D02*
X1675223D01*
G01X1661722Y157172D02*
X1660985Y156435D01*
G01X1661722Y158178D02*
Y157172D01*
G01X1669948Y166404D02*
X1661722Y158178D01*
G01X1680188Y166404D02*
X1669948D01*
G01X1686121Y172337D02*
X1680188Y166404D01*
G01X1688168Y172337D02*
X1686121D01*
G01X1690185Y174354D02*
X1688168Y172337D01*
G01X1691439Y174354D02*
X1690185D01*
G01X1654687Y165884D02*
X1651432Y169139D01*
G01X1657835Y165884D02*
X1654687D01*
G01X1656859Y175533D02*
X1656858Y175532D01*
G01X1662138Y175533D02*
X1656859D01*
G01X1665063Y172608D02*
X1662138Y175533D01*
G01X1702258Y159274D02*
G02X1709428Y156304I0J-10140D01*
G01X1698718Y159274D02*
X1702258D01*
G01X1697792Y160200D02*
G03X1698718Y159274I926J0D01*
G01X1697792Y161844D02*
Y160200D01*
G01X1695940Y161844D02*
G02X1697792I926J0D01*
G01X1695940Y160200D02*
Y161844D01*
G01X1695014Y159274D02*
G03X1695940Y160200I0J926D01*
G01X1675882Y159274D02*
X1695014D01*
G01X1669716Y156720D02*
G02X1675882Y159274I6166J-6165D01*
G01X1687150Y217793D02*
X1662721D01*
G01X1691597Y213346D02*
X1687150Y217793D01*
G01X1712805Y213346D02*
X1691597D01*
G01X1660843Y214785D02*
X1655952Y219676D01*
G01X1665806Y214785D02*
X1660843D01*
G01X1667356Y213235D02*
X1665806Y214785D01*
G01X1667356Y213096D02*
Y213235D01*
G01X1676184Y208082D02*
X1720175D01*
G01X1672083Y203981D02*
X1676184Y208082D01*
G01X1653348Y203981D02*
X1672083D01*
G01X1652268Y205061D02*
X1653348Y203981D01*
G01X1654551Y204733D02*
X1653471Y205813D01*
G01X1664860Y204733D02*
X1654551D01*
G01X1671903Y211776D02*
X1664860Y204733D01*
G01X1679771Y211776D02*
X1671903D01*
G01X1682713Y208834D02*
X1679771Y211776D01*
G01X1720487Y208834D02*
X1682713D01*
G01X1693005Y172588D02*
X1713538D01*
G01X1690987Y171752D02*
G02X1693005Y172588I2018J-2018D01*
G01X1688207Y168972D02*
X1690987Y171752D01*
G01X1686838Y217041D02*
X1661779D01*
G01X1691285Y212594D02*
X1686838Y217041D01*
G01X1713117Y212594D02*
X1691285D01*
G01X1678500Y195341D02*
X1672233Y189074D01*
G01X1678500Y197819D02*
Y195341D01*
G01X1678499Y197820D02*
X1678500Y197819D01*
G01X1678499Y198856D02*
Y197820D01*
G01X1682465Y202822D02*
X1678499Y198856D01*
G01X1687232Y202822D02*
X1682465D01*
G01X1687233Y202821D02*
X1687232Y202822D01*
G01X1695961Y202821D02*
X1687233D01*
G01X1695962Y202822D02*
X1695961Y202821D01*
G01X1700467Y202822D02*
X1695962D01*
G01X1700468Y202821D02*
X1700467Y202822D01*
G01X1712316Y202821D02*
X1700468D01*
G01X1698501Y164676D02*
X1695734D01*
G01X1706453Y161382D02*
G03X1698501Y164676I-7952J-7952D01*
G01X1708202Y160463D02*
G02X1706453Y161382I824J3692D01*
G01X1709858Y159777D02*
G03X1708202Y160463I-1656J-1656D01*
G01X1712109Y157526D02*
X1709858Y159777D01*
G01X1721106Y153800D02*
G02X1712109Y157526I-1J12723D01*
G01X1693157Y217106D02*
X1688622Y221641D01*
G01X1711245Y217106D02*
X1693157D01*
G01X1717687Y223548D02*
X1711245Y217106D01*
G01X1651044Y183809D02*
Y182743D01*
G01X1655057Y187822D02*
X1651044Y183809D01*
G01X1672752Y187822D02*
X1655057D01*
G01X1679752Y194822D02*
X1672752Y187822D01*
G01X1679752Y198338D02*
Y194822D01*
G01X1682984Y201570D02*
X1679752Y198338D01*
G01X1686713Y201570D02*
X1682984D01*
G01X1686714Y201569D02*
X1686713Y201570D01*
G01X1696480Y201569D02*
X1686714D01*
G01X1696481Y201570D02*
X1696480Y201569D01*
G01X1699948Y201570D02*
X1696481D01*
G01X1699949Y201569D02*
X1699948Y201570D01*
G01X1716918Y201569D02*
X1699949D01*
G01X1656547Y176284D02*
X1656546Y176283D01*
G01X1656984Y176284D02*
X1656547D01*
G01X1658234Y177534D02*
X1656984Y176284D01*
G01X1658234Y182960D02*
Y177534D01*
G01X1659774Y184500D02*
X1658234Y182960D01*
G01X1672341Y184500D02*
X1659774D01*
G01X1672370Y184471D02*
X1672341Y184500D01*
G01X1677283Y189384D02*
X1672370Y184471D01*
G01X1682330Y189384D02*
X1677283D01*
G01X1682331Y189385D02*
X1682330Y189384D01*
G01X1682778Y189385D02*
X1682331D01*
G01X1683263Y188900D02*
X1682778Y189385D01*
G01X1686576Y188900D02*
X1683263D01*
G01X1688650Y190974D02*
X1686576Y188900D01*
G01X1688650Y195714D02*
Y190974D01*
G01X1690040Y197104D02*
X1688650Y195714D01*
G01X1702039Y197104D02*
X1690040D01*
G01X1705338Y193805D02*
X1702039Y197104D01*
G01X1705338Y187562D02*
Y193805D01*
G01X1706400Y186500D02*
X1705338Y187562D01*
G01X1709100Y186500D02*
X1706400D01*
G01X1709900Y187300D02*
X1709100Y186500D01*
G01X1711798Y204074D02*
X1717955D01*
G01X1711797Y204073D02*
X1711798Y204074D01*
G01X1700987Y204073D02*
X1711797D01*
G01X1700986Y204074D02*
X1700987Y204073D01*
G01X1695443Y204074D02*
X1700986D01*
G01X1695442Y204073D02*
X1695443Y204074D01*
G01X1687752Y204073D02*
X1695442D01*
G01X1687751Y204074D02*
X1687752Y204073D01*
G01X1681946Y204074D02*
X1687751D01*
G01X1676114Y198242D02*
X1681946Y204074D01*
G01X1672542Y198242D02*
X1676114D01*
G01X1672100Y197800D02*
X1672542Y198242D01*
G01X1672100Y193089D02*
Y197800D01*
G01X1670089Y191078D02*
X1672100Y193089D01*
G01X1704700Y182337D02*
X1716453D01*
G01X1702043Y179680D02*
X1704700Y182337D01*
G01X1688170Y179680D02*
X1702043D01*
G01X1687200Y180650D02*
X1688170Y179680D01*
G01X1676220Y180650D02*
X1687200D01*
G01X1671190Y175620D02*
X1676220Y180650D01*
G01X1671190Y171996D02*
Y175620D01*
G01X1671191Y171995D02*
X1671190Y171996D01*
G01X1671191Y171373D02*
Y171995D01*
G01X1667716Y167898D02*
X1671191Y171373D01*
G01X1666883Y167898D02*
X1667716D01*
G01X1663395Y164410D02*
X1666883Y167898D01*
G01X1660573Y164410D02*
X1663395D01*
G01X1659510Y163347D02*
X1660573Y164410D01*
G01X1659510Y162323D02*
Y163347D01*
G01X1658347Y161160D02*
X1659510Y162323D01*
G01X1650660Y161160D02*
X1658347D01*
G01X1709314Y189249D02*
X1712531D01*
G01X1707242Y191321D02*
X1709314Y189249D01*
G01X1707242Y198708D02*
Y191321D01*
G01X1706285Y199665D02*
X1707242Y198708D01*
G01X1699159Y199665D02*
X1706285D01*
G01X1699158Y199666D02*
X1699159Y199665D01*
G01X1697271Y199666D02*
X1699158D01*
G01X1697270Y199665D02*
X1697271Y199666D01*
G01X1688170Y199665D02*
X1697270D01*
G01X1685400Y196895D02*
X1688170Y199665D01*
G01X1685400Y192033D02*
Y196895D01*
G01X1686183Y191250D02*
X1685400Y192033D01*
G01X1692845Y216354D02*
X1688353Y220846D01*
G01X1711557Y216354D02*
X1692845D01*
G01X1717968Y222765D02*
X1711557Y216354D01*
G01X1685012Y216289D02*
X1687550Y213751D01*
G01X1661467Y216289D02*
X1685012D01*
G01X1650685Y227071D02*
X1661467Y216289D01*
G01X1651808Y179436D02*
X1651000Y178628D01*
G01X1655682Y179436D02*
X1651808D01*
G01X1657483Y181237D02*
X1655682Y179436D01*
G01X1657483Y183567D02*
Y181237D01*
G01X1659167Y185251D02*
X1657483Y183567D01*
G01X1671350Y185251D02*
X1659167D01*
G01X1681352Y195253D02*
X1671350Y185251D01*
G01X1681352Y196092D02*
Y195253D01*
G01X1699471Y200417D02*
X1716083D01*
G01X1699470Y200418D02*
X1699471Y200417D01*
G01X1696959Y200418D02*
X1699470D01*
G01X1696958Y200417D02*
X1696959Y200418D01*
G01X1687858Y200417D02*
X1696958D01*
G01X1684607Y197166D02*
X1687858Y200417D01*
G01X1684607Y192031D02*
Y197166D01*
G01X1683484Y190908D02*
X1684607Y192031D01*
G01X1676924Y195536D02*
Y196731D01*
G01X1671714Y190326D02*
X1676924Y195536D01*
G01X1700909Y170322D02*
G02X1724962Y160359I0J-34016D01*
G01X1695436Y170322D02*
X1700909D01*
G01X1691395Y168648D02*
G02X1695436Y170322I4041J-4040D01*
G01X1687153Y164406D02*
X1691395Y168648D01*
G01X1683920Y163067D02*
G03X1687153Y164406I0J4573D01*
G01X1676629Y163067D02*
X1683920D01*
G01X1669115Y161591D02*
G02X1676629Y163067I7513J-18381D01*
G01X1663026Y157676D02*
G02X1669115Y161591I13604J-14465D01*
G01X1662791Y157441D02*
X1663026Y157676D01*
G01X1662467Y156659D02*
G02X1662791Y157441I1106J0D01*
G01X1652775Y203229D02*
X1651872Y204132D01*
G01X1672539Y203229D02*
X1652775D01*
G01X1673216Y203906D02*
X1672539Y203229D01*
G01X1677172Y203906D02*
X1673216D01*
G01X1680596Y207330D02*
X1677172Y203906D01*
G01X1719305Y207330D02*
X1680596D01*
G01X1656760Y209389D02*
X1654849Y211300D01*
G01X1667388Y209389D02*
X1656760D01*
G01X1671279Y213280D02*
X1667388Y209389D01*
G01X1680395Y213280D02*
X1671279D01*
G01X1683337Y210338D02*
X1680395Y213280D01*
G01X1714157Y210338D02*
X1683337D01*
G01X1657144Y210141D02*
X1655033Y212252D01*
G01X1666793Y210141D02*
X1657144D01*
G01X1670884Y214232D02*
X1666793Y210141D01*
G01X1683020Y214232D02*
X1670884D01*
G01X1686162Y211090D02*
X1683020Y214232D01*
G01X1713845Y211090D02*
X1686162D01*
G01X1689912Y161488D02*
G03X1689785Y161180I308J-307D01*
G01X1690353Y161928D02*
X1689912Y161488D01*
G01X1691502Y161928D02*
G03X1690353I-575J-574D01*
G01X1691578Y161852D02*
X1691502Y161928D01*
G01X1692888Y163162D02*
G02X1691578Y161852I-655J-655D01*
G01X1692812Y163238D02*
X1692888Y163162D01*
G01X1692812Y164548D02*
G03Y163238I655J-655D01*
G01X1694136Y165872D02*
X1692812Y164548D01*
G01X1695823Y166571D02*
G03X1694136Y165872I0J-2386D01*
G01X1700631Y166571D02*
X1695823D01*
G01X1706381Y164187D02*
G03X1700631Y166571I-5750J-5741D01*
G01X1707184Y163382D02*
X1706381Y164187D01*
G01X1707705Y163166D02*
G02X1707184Y163382I0J737D01*
G01X1709277Y163166D02*
X1707705D01*
G01X1709880Y162563D02*
G03X1709277Y163166I-603J0D01*
G01X1710529Y161914D02*
G02X1709880Y162563I0J649D01*
G01X1711083Y161914D02*
X1710529D01*
G01X1711732Y162563D02*
G02X1711083Y161914I-649J0D01*
G01X1712335Y163166D02*
G03X1711732Y162563I0J-603D01*
G01X1712181Y214850D02*
X1718329Y220998D01*
G01X1692221Y214850D02*
X1712181D01*
G01X1687729Y219342D02*
X1692221Y214850D01*
G01X1711869Y215602D02*
X1718144Y221877D01*
G01X1692533Y215602D02*
X1711869D01*
G01X1688041Y220094D02*
X1692533Y215602D01*
G01X1655922Y257038D02*
Y292159D01*
G01X1657996Y254964D02*
X1655922Y257038D01*
G01X1661964Y254964D02*
X1657996D01*
G01X1675899Y241029D02*
X1661964Y254964D01*
G01X1682412Y241029D02*
X1675899D01*
G01X1683729Y242346D02*
X1682412Y241029D01*
G01X1687117Y229456D02*
X1665964D01*
G01X1688875Y231214D02*
X1687117Y229456D01*
G01X1688875Y240249D02*
Y231214D01*
G01X1695552Y246926D02*
X1688875Y240249D01*
G01X1703212Y246926D02*
X1695552D01*
G01X1717500Y232638D02*
X1703212Y246926D01*
G01X1709061Y222370D02*
X1716039Y229348D01*
G01X1695478Y222370D02*
X1709061D01*
G01X1690242Y227606D02*
X1695478Y222370D01*
G01X1665676Y227606D02*
X1690242D01*
G01X1654306Y258607D02*
Y282759D01*
G01X1654307Y258606D02*
X1654306Y258607D01*
G01X1654307Y255263D02*
Y258606D01*
G01X1657986Y251584D02*
X1654307Y255263D01*
G01X1662971Y251584D02*
X1657986D01*
G01X1667905Y246650D02*
X1662971Y251584D01*
G01X1667905Y243547D02*
Y246650D01*
G01X1666345Y241987D02*
X1667905Y243547D01*
G01X1685474Y253808D02*
X1827935D01*
G01X1685473Y253807D02*
X1685474Y253808D01*
G01X1678239Y253807D02*
X1685473D01*
G01X1666043Y266003D02*
X1678239Y253807D01*
G01X1666043Y267284D02*
Y266003D01*
G01X1666042Y267285D02*
X1666043Y267284D01*
G01X1666042Y267823D02*
Y267285D01*
G01X1666043Y267824D02*
X1666042Y267823D01*
G01X1666043Y299547D02*
Y267824D01*
G01X1672507Y268685D02*
Y296865D01*
G01X1680921Y260271D02*
X1672507Y268685D01*
G01X1682791Y260271D02*
X1680921D01*
G01X1682792Y260272D02*
X1682791Y260271D01*
G01X1826243Y260272D02*
X1682792D01*
G01X1688880Y222447D02*
X1664451D01*
G01X1710933Y217858D02*
X1693469D01*
G01X1689634Y223958D02*
X1665068D01*
G01X1694230Y219362D02*
X1689634Y223958D01*
G01X1710309Y219362D02*
X1694230D01*
G01X1716920Y225973D02*
X1710309Y219362D01*
G01X1666795Y266315D02*
Y299235D01*
G01X1678551Y254559D02*
X1666795Y266315D01*
G01X1685161Y254559D02*
X1678551D01*
G01X1685162Y254560D02*
X1685161Y254559D01*
G01X1832659Y254560D02*
X1685162D01*
G01X1682965Y247175D02*
X1684509Y245631D01*
G01X1673511Y247175D02*
X1682965D01*
G01X1661726Y258960D02*
X1673511Y247175D01*
G01X1661726Y311845D02*
Y258960D01*
G01X1680531Y238029D02*
X1681116Y238614D01*
G01X1664660Y238029D02*
X1680531D01*
G01X1673259Y268997D02*
Y296553D01*
G01X1681233Y261023D02*
X1673259Y268997D01*
G01X1682479Y261023D02*
X1681233D01*
G01X1682480Y261024D02*
X1682479Y261023D01*
G01X1825931Y261024D02*
X1682480D01*
G01X1683977Y257416D02*
X1834531D01*
G01X1683976Y257415D02*
X1683977Y257416D01*
G01X1679736Y257415D02*
X1683976D01*
G01X1669651Y267500D02*
X1679736Y257415D01*
G01X1669651Y298050D02*
Y267500D01*
G01X1659822Y258170D02*
Y317041D01*
G01X1675387Y242605D02*
X1659822Y258170D01*
G01X1680769Y242605D02*
X1675387D01*
G01X1662956Y245811D02*
Y243582D01*
G01X1661839Y246928D02*
X1662956Y245811D01*
G01X1658943Y246928D02*
X1661839D01*
G01X1652051Y253820D02*
X1658943Y246928D01*
G01X1652051Y257670D02*
Y253820D01*
G01X1652050Y257671D02*
X1652051Y257670D01*
G01X1652050Y281823D02*
Y257671D01*
G01X1662988Y218590D02*
X1687417D01*
G01X1671355Y268207D02*
Y297343D01*
G01X1680443Y259119D02*
X1671355Y268207D01*
G01X1683269Y259119D02*
X1680443D01*
G01X1683270Y259120D02*
X1683269Y259119D01*
G01X1865147Y259120D02*
X1683270D01*
G01X1682173Y251935D02*
X1683615Y250493D01*
G01X1677983Y251935D02*
X1682173D01*
G01X1663982Y265936D02*
X1677983Y251935D01*
G01X1663982Y299725D02*
Y265936D01*
G01X1659108Y245352D02*
X1661186D01*
G01X1651299Y253161D02*
X1659108Y245352D01*
G01X1651299Y257358D02*
Y253161D01*
G01X1651298Y257359D02*
X1651299Y257358D01*
G01X1651298Y281511D02*
Y257359D01*
G01X1678295Y252687D02*
X1717653D01*
G01X1664734Y266248D02*
X1678295Y252687D01*
G01X1664734Y299413D02*
Y266248D01*
G01X1684372Y256464D02*
X1834136D01*
G01X1684371Y256463D02*
X1684372Y256464D01*
G01X1679341Y256463D02*
X1684371D01*
G01X1668699Y267105D02*
X1679341Y256463D01*
G01X1668699Y298445D02*
Y267105D01*
G01X1655058Y258919D02*
Y283071D01*
G01X1655059Y258918D02*
X1655058Y258919D01*
G01X1655059Y256837D02*
Y258918D01*
G01X1657684Y254212D02*
X1655059Y256837D01*
G01X1661652Y254212D02*
X1657684D01*
G01X1675629Y240235D02*
X1661652Y254212D01*
G01X1684537Y240235D02*
X1675629D01*
G01X1694236Y249934D02*
X1684537Y240235D01*
G01X1704623Y249934D02*
X1694236D01*
G01X1708379Y246178D02*
X1704623Y249934D01*
G01X1715837Y246178D02*
X1708379D01*
G01X1703524Y247678D02*
X1716774Y234428D01*
G01X1695240Y247678D02*
X1703524D01*
G01X1688122Y240560D02*
X1695240Y247678D01*
G01X1688122Y239938D02*
Y240560D01*
G01X1688123Y239937D02*
X1688122Y239938D01*
G01X1688123Y231526D02*
Y239937D01*
G01X1686805Y230208D02*
X1688123Y231526D01*
G01X1666276Y230208D02*
X1686805D01*
G01X1664698Y245139D02*
X1666329D01*
G01X1662654Y247183D02*
X1664698Y245139D01*
G01X1662648Y247183D02*
X1662654D01*
G01X1662151Y247680D02*
X1662648Y247183D01*
G01X1659255Y247680D02*
X1662151D01*
G01X1652803Y254132D02*
X1659255Y247680D01*
G01X1652803Y257982D02*
Y254132D01*
G01X1652802Y257983D02*
X1652803Y257982D01*
G01X1652802Y282135D02*
Y257983D01*
G01X1682168Y261776D02*
X1825619D01*
G01X1682167Y261775D02*
X1682168Y261776D01*
G01X1681545Y261775D02*
X1682167D01*
G01X1674011Y269309D02*
X1681545Y261775D01*
G01X1674011Y296241D02*
Y269309D01*
G01X1664947Y233665D02*
X1681632D01*
G01X1703836Y248430D02*
X1716114Y236152D01*
G01X1694860Y248430D02*
X1703836D01*
G01X1682113Y235683D02*
X1694860Y248430D01*
G01X1663993Y235683D02*
X1682113D01*
G01X1688622Y221641D02*
X1664193D01*
G01X1689852Y225868D02*
X1665286D01*
G01X1694854Y220866D02*
X1689852Y225868D01*
G01X1709685Y220866D02*
X1694854D01*
G01X1716454Y227635D02*
X1709685Y220866D01*
G01X1681856Y262528D02*
X1825307D01*
G01X1674763Y269621D02*
X1681856Y262528D01*
G01X1674763Y295929D02*
Y269621D01*
G01X1708485Y248553D02*
X1717070D01*
G01X1705600Y251438D02*
X1708485Y248553D01*
G01X1693488Y251438D02*
X1705600D01*
G01X1690190Y248140D02*
X1693488Y251438D01*
G01X1687798Y248140D02*
X1690190D01*
G01X1687259Y248679D02*
X1687798Y248140D01*
G01X1674603Y248679D02*
X1687259D01*
G01X1663230Y260052D02*
X1674603Y248679D01*
G01X1663230Y300209D02*
Y260052D01*
G01X1688353Y220846D02*
X1663924D01*
G01X1673556Y245500D02*
X1681760D01*
G01X1660574Y258482D02*
X1673556Y245500D01*
G01X1660574Y312643D02*
Y258482D01*
G01X1690091Y226693D02*
X1665525D01*
G01X1695166Y221618D02*
X1690091Y226693D01*
G01X1709373Y221618D02*
X1695166D01*
G01X1716149Y228394D02*
X1709373Y221618D01*
G01X1682958Y265184D02*
X1824205D01*
G01X1677452Y270690D02*
X1682958Y265184D01*
G01X1677452Y286064D02*
Y270690D01*
G01X1683948Y232062D02*
X1665486D01*
G01X1684300Y232414D02*
X1683948Y232062D01*
G01X1684300Y233579D02*
Y232414D01*
G01X1670403Y267812D02*
Y297738D01*
G01X1680048Y258167D02*
X1670403Y267812D01*
G01X1683664Y258167D02*
X1680048D01*
G01X1683665Y258168D02*
X1683664Y258167D01*
G01X1864752Y258168D02*
X1683665D01*
G01X1711472Y241858D02*
X1824875D01*
G01X1704148Y249182D02*
X1711472Y241858D01*
G01X1694548Y249182D02*
X1704148D01*
G01X1681866Y236500D02*
X1694548Y249182D01*
G01X1664418Y236500D02*
X1681866D01*
G01X1653554Y258295D02*
Y282447D01*
G01X1653555Y258294D02*
X1653554Y258295D01*
G01X1653555Y254951D02*
Y258294D01*
G01X1658498Y250008D02*
X1653555Y254951D01*
G01X1662000Y250008D02*
X1658498D01*
G01X1667547Y266627D02*
Y298923D01*
G01X1678863Y255311D02*
X1667547Y266627D01*
G01X1684849Y255311D02*
X1678863D01*
G01X1684850Y255312D02*
X1684849Y255311D01*
G01X1832971Y255312D02*
X1684850D01*
G01X1682251Y263480D02*
X1824912D01*
G01X1675715Y270016D02*
X1682251Y263480D01*
G01X1675715Y291095D02*
Y270016D01*
G01X1676700Y270378D02*
Y286659D01*
G01X1682646Y264432D02*
X1676700Y270378D01*
G01X1824517Y264432D02*
X1682646D01*
G01X1689329Y223199D02*
X1664763D01*
G01X1693918Y218610D02*
X1689329Y223199D01*
G01X1710621Y218610D02*
X1693918D01*
G01X1717232Y225221D02*
X1710621Y218610D01*
G01X1689751Y224905D02*
X1665185D01*
G01X1694542Y220114D02*
X1689751Y224905D01*
G01X1709997Y220114D02*
X1694542D01*
G01X1716766Y226883D02*
X1709997Y220114D01*
G01X1708859Y223874D02*
X1715420Y230435D01*
G01X1696102Y223874D02*
X1708859D01*
G01X1691618Y228358D02*
X1696102Y223874D01*
G01X1665998Y228358D02*
X1691618D01*
G01X1663300Y219342D02*
X1687729D01*
G01X1663612Y220094D02*
X1688041D01*
G01X1662478Y259600D02*
Y310296D01*
G01X1674151Y247927D02*
X1662478Y259600D01*
G01X1685404Y247927D02*
X1674151D01*
G01X1686695Y246636D02*
X1685404Y247927D01*
G01X1689759Y246636D02*
X1686695D01*
G01X1693809Y250686D02*
X1689759Y246636D01*
G01X1705288Y250686D02*
X1693809D01*
G01X1708173Y247801D02*
X1705288Y250686D01*
G01X1716453Y247801D02*
X1708173D01*
G01X1659952Y318235D02*
Y368685D01*
G01X1655918Y314201D02*
X1659952Y318235D01*
G01X1655918Y292163D02*
Y314201D01*
G01X1655922Y292159D02*
X1655918Y292163D01*
G01X1651020Y340974D02*
X1657295Y347249D01*
G01X1651020Y329190D02*
Y340974D01*
G01X1651021Y329189D02*
X1651020Y329190D01*
G01X1651021Y322123D02*
Y329189D01*
G01X1651020Y322122D02*
X1651021Y322123D01*
G01X1651020Y304050D02*
Y322122D01*
G01X1653393Y301677D02*
X1651020Y304050D01*
G01X1653393Y301140D02*
Y301677D01*
G01X1653395Y301138D02*
X1653393Y301140D01*
G01X1653395Y294696D02*
Y301138D01*
G01X1653394Y294695D02*
X1653395Y294696D01*
G01X1653394Y294073D02*
Y294695D01*
G01X1653393Y294072D02*
X1653394Y294073D01*
G01X1653393Y283672D02*
Y294072D01*
G01X1654306Y282759D02*
X1653393Y283672D01*
G01X1668764Y302268D02*
X1666043Y299547D01*
G01X1668764Y309801D02*
Y302268D01*
G01X1671207Y312244D02*
X1668764Y309801D01*
G01X1671207Y409726D02*
Y312244D01*
G01X1677671Y317337D02*
Y434830D01*
G01X1677672Y317336D02*
X1677671Y317337D01*
G01X1677672Y316714D02*
Y317336D01*
G01X1677673Y316713D02*
X1677672Y316714D01*
G01X1677673Y311975D02*
Y316713D01*
G01X1677671Y311973D02*
X1677673Y311975D01*
G01X1677671Y309562D02*
Y311973D01*
G01X1675228Y307119D02*
X1677671Y309562D01*
G01X1675228Y303984D02*
Y307119D01*
G01X1675229Y303983D02*
X1675228Y303984D01*
G01X1675229Y299587D02*
Y303983D01*
G01X1672507Y296865D02*
X1675229Y299587D01*
G01X1671959Y314967D02*
Y417941D01*
G01X1671960Y314966D02*
X1671959Y314967D01*
G01X1671960Y314344D02*
Y314966D01*
G01X1671959Y314343D02*
X1671960Y314344D01*
G01X1671959Y311932D02*
Y314343D01*
G01X1669516Y309489D02*
X1671959Y311932D01*
G01X1669516Y301956D02*
Y309489D01*
G01X1666795Y299235D02*
X1669516Y301956D01*
G01X1665252Y315371D02*
X1661726Y311845D01*
G01X1665252Y368124D02*
Y315371D01*
G01X1678423Y317649D02*
Y434518D01*
G01X1678424Y317648D02*
X1678423Y317649D01*
G01X1678424Y317026D02*
Y317648D01*
G01X1678425Y317025D02*
X1678424Y317026D01*
G01X1678425Y311663D02*
Y317025D01*
G01X1678423Y311661D02*
X1678425Y311663D01*
G01X1678423Y309250D02*
Y311661D01*
G01X1675980Y306807D02*
X1678423Y309250D01*
G01X1675980Y304296D02*
Y306807D01*
G01X1675981Y304295D02*
X1675980Y304296D01*
G01X1675981Y299275D02*
Y304295D01*
G01X1673259Y296553D02*
X1675981Y299275D01*
G01X1672372Y300771D02*
X1669651Y298050D01*
G01X1672372Y308304D02*
Y300771D01*
G01X1674815Y310747D02*
X1672372Y308304D01*
G01X1674815Y313158D02*
Y310747D01*
G01X1674816Y313159D02*
X1674815Y313158D01*
G01X1674816Y316151D02*
Y313159D01*
G01X1674815Y316152D02*
X1674816Y316151D01*
G01X1674815Y435079D02*
Y316152D01*
G01X1660704Y317923D02*
Y368997D01*
G01X1659822Y317041D02*
X1660704Y317923D01*
G01X1651137Y282736D02*
X1652050Y281823D01*
G01X1651137Y295008D02*
Y282736D01*
G01X1651138Y295009D02*
X1651137Y295008D01*
G01X1651138Y295631D02*
Y295009D01*
G01X1651139Y295632D02*
X1651138Y295631D01*
G01X1651139Y300202D02*
Y295632D01*
G01X1651137Y300204D02*
X1651139Y300202D01*
G01X1651137Y300741D02*
Y300204D01*
G01X1676519Y316859D02*
Y436103D01*
G01X1676520Y316858D02*
X1676519Y316859D01*
G01X1676520Y312452D02*
Y316858D01*
G01X1676519Y312451D02*
X1676520Y312452D01*
G01X1676519Y310040D02*
Y312451D01*
G01X1674076Y307597D02*
X1676519Y310040D01*
G01X1674076Y303506D02*
Y307597D01*
G01X1674077Y303505D02*
X1674076Y303506D01*
G01X1674077Y300065D02*
Y303505D01*
G01X1671355Y297343D02*
X1674077Y300065D01*
G01X1666890Y302633D02*
X1663982Y299725D01*
G01X1666890Y310974D02*
Y302633D01*
G01X1669323Y313407D02*
X1666890Y310974D01*
G01X1669323Y368854D02*
Y313407D01*
G01X1667642Y302321D02*
X1664734Y299413D01*
G01X1667642Y310662D02*
Y302321D01*
G01X1670075Y313095D02*
X1667642Y310662D01*
G01X1670075Y369166D02*
Y313095D01*
G01X1671420Y301166D02*
X1668699Y298445D01*
G01X1671420Y308699D02*
Y301166D01*
G01X1673863Y311142D02*
X1671420Y308699D01*
G01X1673863Y313553D02*
Y311142D01*
G01X1673864Y313554D02*
X1673863Y313553D01*
G01X1673864Y315756D02*
Y313554D01*
G01X1673863Y315757D02*
X1673864Y315756D01*
G01X1673863Y434684D02*
Y315757D01*
G01X1659200Y318547D02*
Y368373D01*
G01X1654969Y314316D02*
X1659200Y318547D01*
G01X1654969Y283160D02*
Y314316D01*
G01X1655058Y283071D02*
X1654969Y283160D01*
G01X1651889Y283048D02*
X1652802Y282135D01*
G01X1651889Y294696D02*
Y283048D01*
G01X1651890Y294697D02*
X1651889Y294696D01*
G01X1651890Y295319D02*
Y294697D01*
G01X1651891Y295320D02*
X1651890Y295319D01*
G01X1651891Y300514D02*
Y295320D01*
G01X1651889Y300516D02*
X1651891Y300514D01*
G01X1651889Y301053D02*
Y300516D01*
G01X1676733Y298963D02*
X1674011Y296241D01*
G01X1676733Y305924D02*
Y298963D01*
G01X1679175Y308366D02*
X1676733Y305924D01*
G01X1679175Y311349D02*
Y308366D01*
G01X1679177Y311351D02*
X1679175Y311349D01*
G01X1679177Y317337D02*
Y311351D01*
G01X1679176Y317338D02*
X1679177Y317337D01*
G01X1679176Y317960D02*
Y317338D01*
G01X1679175Y317961D02*
X1679176Y317960D01*
G01X1679175Y431605D02*
Y317961D01*
G01X1677485Y298651D02*
X1674763Y295929D01*
G01X1677485Y305612D02*
Y298651D01*
G01X1679927Y308054D02*
X1677485Y305612D01*
G01X1679927Y311037D02*
Y308054D01*
G01X1679929Y311039D02*
X1679927Y311037D01*
G01X1679929Y317649D02*
Y311039D01*
G01X1679928Y317650D02*
X1679929Y317649D01*
G01X1679928Y318272D02*
Y317650D01*
G01X1679927Y318273D02*
X1679928Y318272D01*
G01X1679927Y431085D02*
Y318273D01*
G01X1666029Y303008D02*
X1663230Y300209D01*
G01X1666029Y311591D02*
Y303008D01*
G01X1667917Y313479D02*
X1666029Y311591D01*
G01X1667917Y368733D02*
Y313479D01*
G01X1664100Y316169D02*
X1660574Y312643D01*
G01X1664100Y367552D02*
Y316169D01*
G01X1677981Y286593D02*
X1677452Y286064D01*
G01X1679100Y286593D02*
X1677981D01*
G01X1675567Y316464D02*
Y435391D01*
G01X1675568Y316463D02*
X1675567Y316464D01*
G01X1675568Y312847D02*
Y316463D01*
G01X1675567Y312846D02*
X1675568Y312847D01*
G01X1675567Y310435D02*
Y312846D01*
G01X1673124Y307992D02*
X1675567Y310435D01*
G01X1673124Y300459D02*
Y307992D01*
G01X1670403Y297738D02*
X1673124Y300459D01*
G01X1652641Y300828D02*
Y301365D01*
G01X1652643Y300826D02*
X1652641Y300828D01*
G01X1652643Y295008D02*
Y300826D01*
G01X1652642Y295007D02*
X1652643Y295008D01*
G01X1652642Y294385D02*
Y295007D01*
G01X1652641Y294384D02*
X1652642Y294385D01*
G01X1652641Y283360D02*
Y294384D01*
G01X1653554Y282447D02*
X1652641Y283360D01*
G01X1672711Y315279D02*
Y418253D01*
G01X1672712Y315278D02*
X1672711Y315279D01*
G01X1672712Y314032D02*
Y315278D01*
G01X1672711Y314031D02*
X1672712Y314032D01*
G01X1672711Y311620D02*
Y314031D01*
G01X1670268Y309177D02*
X1672711Y311620D01*
G01X1670268Y301644D02*
Y309177D01*
G01X1667547Y298923D02*
X1670268Y301644D01*
G01X1678437Y293817D02*
X1675715Y291095D01*
G01X1678437Y293837D02*
Y293817D01*
G01X1679100Y294500D02*
X1678437Y293837D01*
G01X1679100Y289059D02*
Y289500D01*
G01X1676700Y286659D02*
X1679100Y289059D01*
G01X1667165Y314983D02*
Y368421D01*
G01X1662478Y310296D02*
X1667165Y314983D01*
G01X1651829Y376808D02*
Y445955D01*
G01X1659952Y368685D02*
X1651829Y376808D01*
G01X1657295Y350068D02*
Y367584D01*
G01X1657296Y350067D02*
X1657295Y350068D01*
G01X1657296Y348821D02*
Y350067D01*
G01X1657295Y348820D02*
X1657296Y348821D01*
G01X1657295Y347249D02*
Y348820D01*
G01X1662663Y394363D02*
X1661243Y392943D01*
G01X1662663Y405751D02*
Y394363D01*
G01X1656214Y377162D02*
X1665252Y368124D01*
G01X1656214Y391008D02*
Y377162D01*
G01X1659106Y393900D02*
X1656214Y391008D01*
G01X1659106Y408244D02*
Y393900D01*
G01X1652582Y377119D02*
Y417147D01*
G01X1660704Y368997D02*
X1652582Y377119D01*
G01X1654400Y366848D02*
Y350400D01*
G01X1661803Y376374D02*
X1669323Y368854D01*
G01X1661803Y379793D02*
Y376374D01*
G01X1666271Y384261D02*
X1661803Y379793D01*
G01X1666271Y408004D02*
Y384261D01*
G01X1670455Y381105D02*
Y408030D01*
G01X1666818Y377468D02*
X1670455Y381105D01*
G01X1665678Y377468D02*
X1666818D01*
G01X1664905Y376695D02*
X1665678Y377468D01*
G01X1662555Y376686D02*
X1670075Y369166D01*
G01X1662555Y379481D02*
Y376686D01*
G01X1667023Y383949D02*
X1662555Y379481D01*
G01X1667023Y408316D02*
Y383949D01*
G01X1669703Y381700D02*
Y407718D01*
G01X1666423Y378420D02*
X1669703Y381700D01*
G01X1665603Y378420D02*
X1666423D01*
G01X1664829Y379194D02*
X1665603Y378420D01*
G01X1655791Y366960D02*
Y349444D01*
G01X1660960Y375690D02*
X1667917Y368733D01*
G01X1660960Y380827D02*
Y375690D01*
G01X1665342Y385209D02*
X1660960Y380827D01*
G01X1665342Y407085D02*
Y385209D01*
G01X1655062Y376590D02*
X1664100Y367552D01*
G01X1655062Y391562D02*
Y376590D01*
G01X1657954Y394454D02*
X1655062Y391562D01*
G01X1657954Y407766D02*
Y394454D01*
G01X1663415Y392536D02*
X1661243Y390364D01*
G01X1663415Y406064D02*
Y392536D01*
G01X1656543Y349756D02*
Y367272D01*
G01X1656544Y349755D02*
X1656543Y349756D01*
G01X1656544Y349133D02*
Y349755D01*
G01X1656543Y349132D02*
X1656544Y349133D01*
G01X1656543Y347561D02*
Y349132D01*
G01X1664590Y385521D02*
Y406626D01*
G01X1660208Y381139D02*
X1664590Y385521D01*
G01X1660208Y375378D02*
Y381139D01*
G01X1667165Y368421D02*
X1660208Y375378D01*
G01X1660637Y456251D02*
X1661470D01*
G01X1651899Y447513D02*
X1660637Y456251D01*
G01X1651899Y446025D02*
Y447513D01*
G01X1651829Y445955D02*
X1651899Y446025D01*
G01X1665924Y461876D02*
X1663677Y464123D01*
G01X1671730Y461876D02*
X1665924D01*
G01X1673809Y463955D02*
X1671730Y461876D01*
G01X1673813Y463955D02*
X1673809D01*
G01X1674154Y464296D02*
X1673813Y463955D01*
G01X1690851Y464296D02*
X1674154D01*
G01X1694567Y468012D02*
X1690851Y464296D01*
G01X1718673Y455276D02*
X1705937Y468012D01*
G01X1657952Y410462D02*
X1662663Y405751D01*
G01X1657952Y441861D02*
Y410462D01*
G01X1667372Y451281D02*
X1657952Y441861D01*
G01X1671685Y451281D02*
X1667372D01*
G01X1672109Y450857D02*
X1671685Y451281D01*
G01X1675241Y450857D02*
X1672109D01*
G01X1676304Y449794D02*
X1675241Y450857D01*
G01X1667946Y412987D02*
X1671207Y409726D01*
G01X1680737Y437896D02*
X1902960D01*
G01X1677671Y434830D02*
X1680737Y437896D01*
G01X1665900Y425900D02*
X1667809Y427809D01*
G01X1665900Y424000D02*
Y425900D01*
G01X1671959Y417941D02*
X1665900Y424000D01*
G01X1657200Y410150D02*
X1659106Y408244D01*
G01X1657200Y442173D02*
Y410150D01*
G01X1667060Y452033D02*
X1657200Y442173D01*
G01X1671997Y452033D02*
X1667060D01*
G01X1672421Y451609D02*
X1671997Y452033D01*
G01X1676718Y451609D02*
X1672421D01*
G01X1677880Y450447D02*
X1676718Y451609D01*
G01X1677880Y448203D02*
Y450447D01*
G01X1684136Y441947D02*
X1677880Y448203D01*
G01X1719317Y441947D02*
X1684136D01*
G01X1665748Y459217D02*
X1662846Y462119D01*
G01X1671906Y459217D02*
X1665748D01*
G01X1674053Y461364D02*
X1671906Y459217D01*
G01X1674057Y461364D02*
X1674053D01*
G01X1674643Y461950D02*
X1674057Y461364D01*
G01X1679145Y461950D02*
X1674643D01*
G01X1681049Y437144D02*
X1903555D01*
G01X1678423Y434518D02*
X1681049Y437144D01*
G01X1666508Y463284D02*
X1664261Y465531D01*
G01X1671146Y463284D02*
X1666508D01*
G01X1673226Y465364D02*
X1671146Y463284D01*
G01X1671764Y438130D02*
X1674815Y435079D01*
G01X1671764Y441016D02*
Y438130D01*
G01X1671538Y441242D02*
X1671764Y441016D01*
G01X1671538Y441388D02*
Y441242D01*
G01X1670615Y442311D02*
X1671538Y441388D01*
G01X1670469Y442311D02*
X1670615D01*
G01X1669816Y442964D02*
X1670469Y442311D01*
G01X1669816Y443953D02*
Y442964D01*
G01X1660689Y453751D02*
X1661522D01*
G01X1652581Y445643D02*
X1660689Y453751D01*
G01X1652581Y417148D02*
Y445643D01*
G01X1652582Y417147D02*
X1652581Y417148D01*
G01X1659159Y458248D02*
X1659158Y458249D01*
G01X1661754Y458248D02*
X1659159D01*
G01X1665241Y454761D02*
X1661754Y458248D01*
G01X1674954Y454761D02*
X1665241D01*
G01X1678632Y451083D02*
X1674954Y454761D01*
G01X1678632Y448515D02*
Y451083D01*
G01X1684376Y442771D02*
X1678632Y448515D01*
G01X1708720Y442771D02*
X1684376D01*
G01X1712075Y446126D02*
X1708720Y442771D01*
G01X1731274Y446126D02*
X1712075D01*
G01X1675186Y443900D02*
X1673064Y446022D01*
G01X1675186Y442026D02*
Y443900D01*
G01X1673544Y440384D02*
X1675186Y442026D01*
G01X1673544Y439078D02*
Y440384D01*
G01X1676519Y436103D02*
X1673544Y439078D01*
G01X1661360Y412915D02*
X1666271Y408004D01*
G01X1661360Y438618D02*
Y412915D01*
G01X1663477Y440735D02*
X1661360Y438618D01*
G01X1664762Y440735D02*
X1663477D01*
G01X1719297Y456780D02*
X1706561Y469516D01*
G01X1667588Y430849D02*
X1667649D01*
G01X1666414Y432023D02*
X1667588Y430849D01*
G01X1665470Y432023D02*
X1666414D01*
G01X1664096Y430649D02*
X1665470Y432023D01*
G01X1664096Y414389D02*
Y430649D01*
G01X1670455Y408030D02*
X1664096Y414389D01*
G01X1662112Y413227D02*
X1667023Y408316D01*
G01X1662112Y433044D02*
Y413227D01*
G01X1667316Y438248D02*
X1662112Y433044D01*
G01X1667316Y440735D02*
Y438248D01*
G01X1667462Y440735D02*
X1667316D01*
G01X1670812Y437735D02*
X1673863Y434684D01*
G01X1670812Y439739D02*
Y437735D01*
G01X1669816Y440735D02*
X1670812Y439739D01*
G01X1669962Y440735D02*
X1669816D01*
G01X1666414Y432975D02*
X1667588Y434149D01*
G01X1665358Y432975D02*
X1666414D01*
G01X1663344Y430961D02*
X1665358Y432975D01*
G01X1663344Y414077D02*
Y430961D01*
G01X1669703Y407718D02*
X1663344Y414077D01*
G01X1666177Y460559D02*
X1663365Y463371D01*
G01X1671477Y460559D02*
X1666177D01*
G01X1673534Y462616D02*
X1671477Y460559D01*
G01X1673538Y462616D02*
X1673534D01*
G01X1674466Y463544D02*
X1673538Y462616D01*
G01X1691163Y463544D02*
X1674466D01*
G01X1694879Y467260D02*
X1691163Y463544D01*
G01X1718361Y454524D02*
X1705625Y467260D01*
G01X1683957Y436387D02*
X1679175Y431605D01*
G01X1904428Y436387D02*
X1683957D01*
G01X1665432Y457762D02*
X1662415Y460779D01*
G01X1672690Y457762D02*
X1665432D01*
G01X1675388Y460460D02*
X1672690Y457762D01*
G01X1676939Y460460D02*
X1675388D01*
G01X1677596Y459803D02*
X1676939Y460460D01*
G01X1681160Y459803D02*
X1677596D01*
G01X1682526Y461169D02*
X1681160Y459803D01*
G01X1689852Y461169D02*
X1682526D01*
G01X1695191Y466508D02*
X1689852Y461169D01*
G01X1722833Y447841D02*
X1704166Y466508D01*
G01X1684077Y435235D02*
X1679927Y431085D01*
G01X1904906Y435235D02*
X1684077D01*
G01X1660608Y411819D02*
X1665342Y407085D01*
G01X1660608Y439581D02*
Y411819D01*
G01X1664762Y443735D02*
X1660608Y439581D01*
G01X1656048Y409672D02*
X1657954Y407766D01*
G01X1656048Y442705D02*
Y409672D01*
G01X1666528Y453185D02*
X1656048Y442705D01*
G01X1673074Y453185D02*
X1666528D01*
G01X1706249Y468764D02*
X1718985Y456028D01*
G01X1671488Y446942D02*
X1673068Y448522D01*
G01X1671488Y442502D02*
Y446942D01*
G01X1672290Y441700D02*
X1671488Y442502D01*
G01X1672290Y441554D02*
Y441700D01*
G01X1672517Y441327D02*
X1672290Y441554D01*
G01X1672517Y440705D02*
Y441327D01*
G01X1672516Y440704D02*
X1672517Y440705D01*
G01X1672516Y438442D02*
Y440704D01*
G01X1675567Y435391D02*
X1672516Y438442D01*
G01X1658704Y410775D02*
X1663415Y406064D01*
G01X1658704Y441549D02*
Y410775D01*
G01X1667684Y450529D02*
X1658704Y441549D01*
G01X1671373Y450529D02*
X1667684D01*
G01X1671797Y450105D02*
X1671373Y450529D01*
G01X1673716Y450105D02*
X1671797D01*
G01X1676287Y447534D02*
X1673716Y450105D01*
G01X1676287Y447244D02*
Y447534D01*
G01X1650505Y459753D02*
X1650504Y459754D01*
G01X1662377Y459753D02*
X1650505D01*
G01X1665647Y456483D02*
X1662377Y459753D01*
G01X1673621Y456483D02*
X1665647D01*
G01X1675113Y457975D02*
X1673621Y456483D01*
G01X1675132Y457975D02*
X1675113D01*
G01X1676041Y458884D02*
X1675132Y457975D01*
G01X1667729Y423235D02*
Y424621D01*
G01X1672711Y418253D02*
X1667729Y423235D01*
G01X1675221Y455677D02*
X1675744Y456200D01*
G01X1665389Y455677D02*
X1675221D01*
G01X1662065Y459001D02*
X1665389Y455677D01*
G01X1660094Y459001D02*
X1662065D01*
G01X1660093Y459000D02*
X1660094Y459001D01*
G01X1659471Y459000D02*
X1660093D01*
G01X1659470Y459001D02*
X1659471Y459000D01*
G01X1665251Y446453D02*
X1669816D01*
G01X1659856Y441058D02*
X1665251Y446453D01*
G01X1659856Y411360D02*
Y441058D01*
G01X1664590Y406626D02*
X1659856Y411360D01*
G01X1699030Y480269D02*
X1729986D01*
G01X1698042Y481257D02*
X1699030Y480269D01*
G01X1686950Y481257D02*
X1698042D01*
G01X1678954Y489253D02*
X1686950Y481257D01*
G01X1669608Y489253D02*
X1678954D01*
G01X1668084Y490777D02*
X1669608Y489253D01*
G01X1705937Y468012D02*
X1694567D01*
G01X1658918Y474740D02*
X1657626Y473448D01*
G01X1671125Y474740D02*
X1658918D01*
G01X1672265Y473600D02*
X1671125Y474740D01*
G01X1659530Y513808D02*
X1654576Y508854D01*
G01X1697187Y513808D02*
X1659530D01*
G01X1698407Y515028D02*
X1697187Y513808D01*
G01X1705418Y515028D02*
X1698407D01*
G01X1706118Y515728D02*
X1705418Y515028D01*
G01X1739128Y515728D02*
X1706118D01*
G01X1669464Y495664D02*
X1665329Y491529D01*
G01X1673607Y495664D02*
X1669464D01*
G01X1686931Y482340D02*
X1673607Y495664D01*
G01X1698335Y482340D02*
X1686931D01*
G01X1700846Y484851D02*
X1698335Y482340D01*
G01X1706093Y484851D02*
X1700846D01*
G01X1709923Y481021D02*
X1706093Y484851D01*
G01X1730298Y481021D02*
X1709923D01*
G01X1688106Y483394D02*
X1687500Y484000D01*
G01X1697119Y483394D02*
X1688106D01*
G01X1700034Y486309D02*
X1697119Y483394D01*
G01X1706011Y486309D02*
X1700034D01*
G01X1710347Y481973D02*
X1706011Y486309D01*
G01X1730693Y481973D02*
X1710347D01*
G01X1657208Y506552D02*
X1653556Y502900D01*
G01X1669147Y506552D02*
X1657208D01*
G01X1669148Y506553D02*
X1669147Y506552D01*
G01X1675690Y506553D02*
X1669148D01*
G01X1686088Y496155D02*
X1675690Y506553D01*
G01X1708299Y496155D02*
X1686088D01*
G01X1723244Y511100D02*
X1708299Y496155D01*
G01X1659230Y473988D02*
X1657938Y472696D01*
G01X1669571Y473988D02*
X1659230D01*
G01X1671935Y471624D02*
X1669571Y473988D01*
G01X1682466Y471624D02*
X1671935D01*
G01X1684118Y473276D02*
X1682466Y471624D01*
G01X1708121Y473276D02*
X1684118D01*
G01X1720857Y460540D02*
X1708121Y473276D01*
G01X1665047Y467257D02*
X1664872Y467432D01*
G01X1673230Y465364D02*
X1673226D01*
G01X1673570Y465704D02*
X1673230Y465364D01*
G01X1684922Y465704D02*
X1673570D01*
G01X1685881Y466663D02*
X1684922Y465704D01*
G01X1687416Y466663D02*
X1685881D01*
G01X1687741Y466988D02*
X1687416Y466663D01*
G01X1653564Y519568D02*
X1651267Y521865D01*
G01X1690584Y519568D02*
X1653564D01*
G01X1695409Y524393D02*
X1690584Y519568D01*
G01X1717524Y524393D02*
X1695409D01*
G01X1695928Y523141D02*
X1717902D01*
G01X1691203Y518416D02*
X1695928Y523141D01*
G01X1652837Y518416D02*
X1691203D01*
G01X1650960Y520293D02*
X1652837Y518416D01*
G01X1710296Y477213D02*
X1722080Y465429D01*
G01X1686144Y477213D02*
X1710296D01*
G01X1685085Y478272D02*
X1686144Y477213D01*
G01X1667928Y478272D02*
X1685085D01*
G01X1666867Y479333D02*
X1667928Y478272D01*
G01X1652812Y479333D02*
X1666867D01*
G01X1651279Y477800D02*
X1652812Y479333D01*
G01X1692443Y488639D02*
Y487259D01*
G01X1693855Y490051D02*
X1692443Y488639D01*
G01X1709152Y490051D02*
X1693855D01*
G01X1714736Y484467D02*
X1709152Y490051D01*
G01X1706704Y514576D02*
X1739786D01*
G01X1706004Y513876D02*
X1706704Y514576D01*
G01X1698885Y513876D02*
X1706004D01*
G01X1697665Y512656D02*
X1698885Y513876D01*
G01X1660008Y512656D02*
X1697665D01*
G01X1655054Y507702D02*
X1660008Y512656D01*
G01X1660779Y470217D02*
X1659498Y468936D01*
G01X1668022Y470217D02*
X1660779D01*
G01X1670375Y467864D02*
X1668022Y470217D01*
G01X1684026Y467864D02*
X1670375D01*
G01X1685678Y469516D02*
X1684026Y467864D01*
G01X1706561Y469516D02*
X1685678D01*
G01X1696231Y516112D02*
X1651740D01*
G01X1697451Y517332D02*
X1696231Y516112D01*
G01X1704462Y517332D02*
X1697451D01*
G01X1705162Y518032D02*
X1704462Y517332D01*
G01X1706642Y518032D02*
X1705162D01*
G01X1706643Y518033D02*
X1706642Y518032D01*
G01X1716054Y518033D02*
X1706643D01*
G01X1694931Y525545D02*
X1717046D01*
G01X1690106Y520720D02*
X1694931Y525545D01*
G01X1654042Y520720D02*
X1690106D01*
G01X1651628Y523134D02*
X1654042Y520720D01*
G01X1707497Y471772D02*
X1720233Y459036D01*
G01X1684742Y471772D02*
X1707497D01*
G01X1683090Y470120D02*
X1684742Y471772D01*
G01X1671311Y470120D02*
X1683090D01*
G01X1668958Y472473D02*
X1671311Y470120D01*
G01X1659843Y472473D02*
X1668958D01*
G01X1658562Y471192D02*
X1659843Y472473D01*
G01X1710260Y491203D02*
X1715844Y485619D01*
G01X1691443Y491203D02*
X1710260D01*
G01X1687443Y487203D02*
X1691443Y491203D01*
G01X1707337Y521837D02*
X1718228D01*
G01X1703984Y518484D02*
X1707337Y521837D01*
G01X1696973Y518484D02*
X1703984D01*
G01X1695753Y517264D02*
X1696973Y518484D01*
G01X1652218Y517264D02*
X1695753D01*
G01X1655939Y476444D02*
X1655790Y476593D01*
G01X1684502Y476444D02*
X1655939D01*
G01X1685437Y475509D02*
X1684502Y476444D01*
G01X1708944Y475509D02*
X1685437D01*
G01X1721184Y463269D02*
X1708944Y475509D01*
G01X1705625Y467260D02*
X1694879D01*
G01X1687100Y479517D02*
X1729674D01*
G01X1681193Y485424D02*
X1687100Y479517D01*
G01X1670104Y485424D02*
X1681193D01*
G01X1669199Y486329D02*
X1670104Y485424D01*
G01X1650792Y486329D02*
X1669199D01*
G01X1707809Y472524D02*
X1720545Y459788D01*
G01X1684430Y472524D02*
X1707809D01*
G01X1682778Y470872D02*
X1684430Y472524D01*
G01X1671623Y470872D02*
X1682778D01*
G01X1669270Y473225D02*
X1671623Y470872D01*
G01X1659531Y473225D02*
X1669270D01*
G01X1658250Y471944D02*
X1659531Y473225D01*
G01X1660467Y470969D02*
X1659186Y469688D01*
G01X1668334Y470969D02*
X1660467D01*
G01X1670687Y468616D02*
X1668334Y470969D01*
G01X1683714Y468616D02*
X1670687D01*
G01X1685366Y470268D02*
X1683714Y468616D01*
G01X1706873Y470268D02*
X1685366D01*
G01X1719609Y457532D02*
X1706873Y470268D01*
G01X1704166Y466508D02*
X1695191D01*
G01X1709984Y476461D02*
X1721768Y464677D01*
G01X1685832Y476461D02*
X1709984D01*
G01X1684773Y477520D02*
X1685832Y476461D01*
G01X1667616Y477520D02*
X1684773D01*
G01X1666736Y478400D02*
X1667616Y477520D01*
G01X1652943Y478400D02*
X1666736D01*
G01X1651243Y476700D02*
X1652943Y478400D01*
G01X1654800Y481500D02*
X1653500Y480200D01*
G01X1666462Y481500D02*
X1654800D01*
G01X1668538Y479424D02*
X1666462Y481500D01*
G01X1685563Y479424D02*
X1668538D01*
G01X1686622Y478365D02*
X1685563Y479424D01*
G01X1710774Y478365D02*
X1686622D01*
G01X1714569Y474570D02*
X1710774Y478365D01*
G01X1711175Y482925D02*
X1731088D01*
G01X1705579Y488521D02*
X1711175Y482925D01*
G01X1695005Y488521D02*
X1705579D01*
G01X1694019Y487535D02*
X1695005Y488521D01*
G01X1694019Y486606D02*
Y487535D01*
G01X1693096Y485683D02*
X1694019Y486606D01*
G01X1691463Y485683D02*
X1693096D01*
G01X1689943Y487203D02*
X1691463Y485683D01*
G01X1685990Y468764D02*
X1706249D01*
G01X1684338Y467112D02*
X1685990Y468764D01*
G01X1670063Y467112D02*
X1684338D01*
G01X1667710Y469465D02*
X1670063Y467112D01*
G01X1661091Y469465D02*
X1667710D01*
G01X1659810Y468184D02*
X1661091Y469465D01*
G01X1660155Y471721D02*
X1658874Y470440D01*
G01X1668646Y471721D02*
X1660155D01*
G01X1670999Y469368D02*
X1668646Y471721D01*
G01X1683402Y469368D02*
X1670999D01*
G01X1685054Y471020D02*
X1683402Y469368D01*
G01X1707185Y471020D02*
X1685054D01*
G01X1719921Y458284D02*
X1707185Y471020D01*
G01X1707904Y474557D02*
X1720600Y461861D01*
G01X1685042Y474557D02*
X1707904D01*
G01X1684107Y475492D02*
X1685042Y474557D01*
G01X1658606Y475492D02*
X1684107D01*
G01X1657314Y474200D02*
X1658606Y475492D01*
G01X1698354Y486690D02*
Y486873D01*
G01X1696395Y484731D02*
X1698354Y486690D01*
G01X1688998Y484731D02*
X1696395D01*
G01X1688153Y485576D02*
X1688998Y484731D01*
G01X1685042Y485576D02*
X1688153D01*
G01X1680100Y490518D02*
X1685042Y485576D01*
G01X1680100Y495138D02*
Y490518D01*
G01X1673638Y501600D02*
X1680100Y495138D01*
G01X1671200Y501600D02*
X1673638D01*
G01X1662081Y492481D02*
X1671200Y501600D01*
G01X1705640Y516880D02*
X1738380D01*
G01X1704940Y516180D02*
X1705640Y516880D01*
G01X1697929Y516180D02*
X1704940D01*
G01X1696709Y514960D02*
X1697929Y516180D01*
G01X1657283Y514960D02*
X1696709D01*
G01X1655444Y513121D02*
X1657283Y514960D01*
G01X1671565Y535406D02*
X1667109Y530950D01*
G01X1676865Y535406D02*
X1671565D01*
G01X1678934Y533337D02*
X1676865Y535406D01*
G01X1681113Y533337D02*
X1678934D01*
G01X1682106Y534330D02*
X1681113Y533337D01*
G01X1682106Y538310D02*
Y534330D01*
G01X1687830Y544034D02*
X1682106Y538310D01*
G01X1712566Y544034D02*
X1687830D01*
G01X1656100Y584100D02*
Y601954D01*
G01X1664400Y575800D02*
X1656100Y584100D01*
G01X1693600Y575800D02*
X1664400D01*
G01X1698460Y570940D02*
X1693600Y575800D01*
G01X1698460Y564441D02*
Y570940D01*
G01X1703797Y559104D02*
X1698460Y564441D01*
G01X1707806Y559104D02*
X1703797D01*
G01X1724677Y575975D02*
X1707806Y559104D01*
G01X1700176Y578676D02*
X1699600Y578100D01*
G01X1700176Y599465D02*
Y578676D01*
G01X1654692Y583516D02*
Y601370D01*
G01X1663816Y574392D02*
X1654692Y583516D01*
G01X1693016Y574392D02*
X1663816D01*
G01X1697052Y570356D02*
X1693016Y574392D01*
G01X1697052Y563857D02*
Y570356D01*
G01X1703213Y557696D02*
X1697052Y563857D01*
G01X1708390Y557696D02*
X1703213D01*
G01X1725261Y574567D02*
X1708390Y557696D01*
G01X1672043Y534254D02*
X1667587Y529798D01*
G01X1676387Y534254D02*
X1672043D01*
G01X1678456Y532185D02*
X1676387Y534254D01*
G01X1681591Y532185D02*
X1678456D01*
G01X1683258Y533852D02*
X1681591Y532185D01*
G01X1683258Y537832D02*
Y533852D01*
G01X1688226Y542800D02*
X1683258Y537832D01*
G01X1712962Y542800D02*
X1688226D01*
G01X1698850Y575800D02*
X1722510D01*
G01X1696300Y578350D02*
X1698850Y575800D01*
G01X1696300Y587900D02*
Y578350D01*
G01X1698448Y590048D02*
X1696300Y587900D01*
G01X1656100Y601954D02*
X1653124Y604930D01*
G01X1699600Y600041D02*
X1700176Y599465D01*
G01X1699600Y614000D02*
Y600041D01*
G01X1692100Y621500D02*
X1699600Y614000D01*
G01X1654692Y601370D02*
X1653285Y602777D01*
G01X1698448Y613522D02*
Y590048D01*
G01X1692222Y619748D02*
X1698448Y613522D01*
G01X1754394Y3868D02*
X1749085Y9177D01*
G01X1775271Y3868D02*
X1754394D01*
G01X1759956Y4620D02*
X1774959D01*
G01X1755500Y9076D02*
X1759956Y4620D01*
G01X1772351Y11350D02*
X1781101Y2600D01*
G01X1741200Y11350D02*
X1772351D01*
G01X1739700Y9850D02*
X1741200Y11350D01*
G01X1739700Y8250D02*
Y9850D01*
G01X1736808Y5358D02*
X1739700Y8250D01*
G01X1773463Y12302D02*
X1782143Y3622D01*
G01X1740805Y12302D02*
X1773463D01*
G01X1738748Y10245D02*
X1740805Y12302D01*
G01X1738748Y8645D02*
Y10245D01*
G01X1736413Y6310D02*
X1738748Y8645D01*
G01X1737596Y9123D02*
X1735935Y7462D01*
G01X1737596Y10723D02*
Y9123D01*
G01X1740327Y13454D02*
X1737596Y10723D01*
G01X1773941Y13454D02*
X1740327D01*
G01X1749357Y86911D02*
X1758646Y96200D01*
G01X1721959Y86911D02*
X1749357D01*
G01X1718306Y90564D02*
X1721959Y86911D01*
G01X1713655Y90564D02*
X1718306D01*
G01X1712292Y91927D02*
X1713655Y90564D01*
G01X1712291Y91927D02*
X1712292D01*
G01X1748126Y90570D02*
X1763636Y106080D01*
G01X1722651Y90570D02*
X1748126D01*
G01X1719200Y94021D02*
X1722651Y90570D01*
G01X1715337Y94021D02*
X1719200D01*
G01X1721647Y86159D02*
X1717995Y89811D01*
G01X1750268Y86159D02*
X1721647D01*
G01X1756471Y92362D02*
X1750268Y86159D01*
G01X1767524Y92362D02*
X1756471D01*
G01X1772406Y97244D02*
X1767524Y92362D01*
G01X1765399Y81757D02*
X1782177D01*
G01X1763547Y79905D02*
X1765399Y81757D01*
G01X1753231Y79905D02*
X1763547D01*
G01X1751796Y81340D02*
X1753231Y79905D01*
G01X1744204Y81340D02*
X1751796D01*
G01X1743812Y80948D02*
X1744204Y81340D01*
G01X1766105Y80052D02*
X1787468D01*
G01X1763781Y77728D02*
X1766105Y80052D01*
G01X1755829Y77728D02*
X1763781D01*
G01X1754570Y76469D02*
X1755829Y77728D01*
G01X1746957Y76469D02*
X1754570D01*
G01X1744182Y79244D02*
X1746957Y76469D01*
G01X1725474Y70748D02*
X1722234Y73988D01*
G01X1725474Y69250D02*
Y70748D01*
G01X1766871Y86767D02*
X1774685Y94581D01*
G01X1754418Y86767D02*
X1766871D01*
G01X1751196Y83545D02*
X1754418Y86767D01*
G01X1743770Y82536D02*
X1743334Y82100D01*
G01X1752230Y82536D02*
X1743770D01*
G01X1753266Y81500D02*
X1752230Y82536D01*
G01X1753277Y81500D02*
X1753266D01*
G01X1753352Y81425D02*
X1753277Y81500D01*
G01X1760725Y81425D02*
X1753352D01*
G01X1765000Y85700D02*
X1760725Y81425D01*
G01X1768100Y85700D02*
X1765000D01*
G01X1773622Y91222D02*
X1768100Y85700D01*
G01X1791718Y91222D02*
X1773622D01*
G01X1766500Y79100D02*
X1788411D01*
G01X1764176Y76776D02*
X1766500Y79100D01*
G01X1757400Y76776D02*
X1764176D01*
G01X1755764Y75140D02*
X1757400Y76776D01*
G01X1718601Y91899D02*
X1714199D01*
G01X1722437Y88063D02*
X1718601Y91899D01*
G01X1748879Y88063D02*
X1722437D01*
G01X1758168Y97352D02*
X1748879Y88063D01*
G01X1750677Y84797D02*
X1712158D01*
G01X1753899Y88019D02*
X1750677Y84797D01*
G01X1763232Y88019D02*
X1753899D01*
G01X1766323Y91110D02*
X1763232Y88019D01*
G01X1768043Y91110D02*
X1766323D01*
G01X1772925Y95992D02*
X1768043Y91110D01*
G01X1737700Y91800D02*
X1734728Y94772D01*
G01X1748079Y91800D02*
X1737700D01*
G01X1763490Y107211D02*
X1748079Y91800D01*
G01X1719289Y92869D02*
X1714859D01*
G01X1722943Y89215D02*
X1719289Y92869D01*
G01X1748401Y89215D02*
X1722943D01*
G01X1757886Y98700D02*
X1748401Y89215D01*
G01X1765710Y81004D02*
X1786768D01*
G01X1763859Y79153D02*
X1765710Y81004D01*
G01X1752919Y79153D02*
X1763859D01*
G01X1751227Y77461D02*
X1752919Y79153D01*
G01X1747570Y77461D02*
X1751227D01*
G01X1744835Y80196D02*
X1747570Y77461D01*
G01X1731823Y150775D02*
G03X1735989Y149050I4165J4166D01*
G01X1729273Y153326D02*
X1731823Y150775D01*
G01X1725724Y156875D02*
X1729273Y153326D01*
G01X1713065Y121263D02*
X1712554D01*
G01X1713735Y120593D02*
G03X1713065Y121263I-670J0D01*
G01X1713735Y120592D02*
Y120593D01*
G01X1714417Y119910D02*
G02X1713735Y120592I0J682D01*
G01X1717245Y119910D02*
X1714417D01*
G01X1718278Y119482D02*
G03X1717245Y119910I-1033J-1033D01*
G01X1719321Y119050D02*
G02X1718278Y119482I0J1475D01*
G01X1726260Y119050D02*
X1719321D01*
G01X1727068Y119105D02*
G02X1726260Y119050I-809J5918D01*
G01X1728256Y119597D02*
G02X1727068Y119105I-1188J1188D01*
G01X1729383Y120724D02*
X1728256Y119597D01*
G01X1730788Y122128D02*
X1729383Y120724D01*
G01X1730972Y122311D02*
X1730788Y122128D01*
G01X1733322Y124661D02*
X1730972Y122311D01*
G01X1734686Y125226D02*
G03X1733322Y124661I0J-1929D01*
G01X1736254Y125226D02*
X1734686D01*
G01X1736800Y124680D02*
G03X1736254Y125226I-546J0D01*
G01X1736800Y124134D02*
Y124680D01*
G01X1736730Y123923D02*
G03X1736800Y124134I-283J211D01*
G01X1736311Y123750D02*
G03X1736730Y123923I0J594D01*
G01X1735912Y123750D02*
X1736311D01*
G01X1773578Y100339D02*
X1784885D01*
G01X1769439Y96200D02*
X1773578Y100339D01*
G01X1758646Y96200D02*
X1769439D01*
G01X1763636Y106080D02*
X1785245D01*
G01X1725491Y126241D02*
G02X1723099Y125250I-2392J2392D01*
G01X1727082Y126900D02*
G03X1725491Y126241I0J-2250D01*
G01X1739064Y126900D02*
X1727082D01*
G01X1791939Y97244D02*
X1772406D01*
G01X1764600Y118685D02*
X1765015Y119100D01*
G01X1764600Y109951D02*
Y118685D01*
G01X1750299Y95650D02*
X1764600Y109951D01*
G01X1746491Y95650D02*
X1750299D01*
G01X1716441Y141178D02*
G02X1715019Y141767I0J2011D01*
G01X1717336Y141116D02*
G02X1716441Y141178I0J6492D01*
G01X1721558Y141116D02*
X1717336D01*
G01X1721975Y141291D02*
G02X1721558Y141116I-417J409D01*
G01X1723310Y142650D02*
X1721975Y141291D01*
G01X1723314Y142650D02*
X1723310D01*
G01X1726464Y124177D02*
Y123750D01*
G01X1726863Y124576D02*
G03X1726464Y124177I0J-399D01*
G01X1727460Y124576D02*
X1726863D01*
G01X1727966Y124070D02*
G03X1727460Y124576I-506J0D01*
G01X1727966Y123222D02*
Y124070D01*
G01X1727736Y122667D02*
G03X1727966Y123222I-555J555D01*
G01X1726729Y122250D02*
G03X1727736Y122667I0J1424D01*
G01X1719829Y122250D02*
X1726729D01*
G01X1718767Y122690D02*
G03X1719829Y122250I1062J1062D01*
G01X1717246Y123320D02*
G02X1718767Y122690I0J-2151D01*
G01X1717181Y150561D02*
X1714274D01*
G01X1728721Y145781D02*
G03X1717181Y150561I-11540J-11540D01*
G01X1732133Y142369D02*
X1728721Y145781D01*
G01X1734835Y141250D02*
G02X1732133Y142369I0J3822D01*
G01X1734838Y141250D02*
X1734835D01*
G01X1739062Y139502D02*
G03X1734838Y141250I-4224J-4230D01*
G01X1739064Y139500D02*
X1739062Y139502D01*
G01X1734838Y142384D02*
G03X1734989Y142750I-366J365D01*
G01X1734326Y142172D02*
G03X1734838Y142384I0J724D01*
G01X1734323Y142172D02*
X1734326D01*
G01X1733414Y142548D02*
G03X1734323Y142172I909J910D01*
G01X1733127Y142835D02*
X1733414Y142548D01*
G01X1732820Y143300D02*
G03X1733127Y142835I1286J515D01*
G01X1732454Y144185D02*
G02X1732820Y143300I-885J-884D01*
G01X1731926Y144712D02*
X1732454Y144185D01*
G01X1727540Y149098D02*
X1731926Y144712D01*
G01X1719937Y152247D02*
G02X1727540Y149098I1J-10751D01*
G01X1718683Y152313D02*
G02X1719937Y152247I-2J-11991D01*
G01X1716500Y152313D02*
X1718683D01*
G01X1713442Y108410D02*
G02X1712246Y107969I-1195J1399D01*
G01X1713547Y108508D02*
G02X1713442Y108410I-1307J1295D01*
G01X1716304Y109650D02*
G03X1713547Y108508I0J-3899D01*
G01X1723789Y109650D02*
X1716304D01*
G01X1725795Y110481D02*
G02X1723789Y109650I-2006J2006D01*
G01X1726464Y111150D02*
X1725795Y110481D01*
G01X1723407Y131564D02*
X1715598D01*
G01X1724889Y130950D02*
G03X1723407Y131564I-1482J-1482D01*
G01X1726579Y130250D02*
G02X1724889Y130950I0J2390D01*
G01X1734585Y130250D02*
X1726579D01*
G01X1735737Y130727D02*
G02X1734585Y130250I-1152J1153D01*
G01X1735992Y130982D02*
X1735737Y130727D01*
G01X1738365Y131965D02*
G03X1735992Y130982I0J-3355D01*
G01X1742770Y131965D02*
X1738365D01*
G01X1743721Y131571D02*
G03X1742770Y131965I-951J-951D01*
G01X1743091Y130050D02*
G03X1743721Y131571I0J891D01*
G01X1742214Y130050D02*
X1743091D01*
G01X1724889Y133383D02*
G03X1723584Y134688I-1305J0D01*
G01X1724889Y133381D02*
Y133383D01*
G01X1726249Y131715D02*
G02X1724889Y133381I340J1666D01*
G01X1726620Y131719D02*
X1726249Y131715D01*
G01X1735989Y133250D02*
G02X1726620Y131719I-9369J27901D01*
G01X1758802Y97352D02*
X1758168D01*
G01X1758803Y97353D02*
X1758802Y97352D01*
G01X1768962Y97353D02*
X1758803D01*
G01X1773210Y101601D02*
X1768962Y97353D01*
G01X1784373Y101601D02*
X1773210D01*
G01X1793370Y95992D02*
X1772925D01*
G01X1739063Y136894D02*
X1739064Y136350D01*
G01X1738508Y137446D02*
G02X1739063Y136894I0J-555D01*
G01X1737648Y137446D02*
X1738508D01*
G01X1736540Y136338D02*
G02X1737648Y137446I1108J0D01*
G01X1736540Y135990D02*
Y136338D01*
G01X1734688Y135990D02*
G03X1736540I926J0D01*
G01X1733762Y136916D02*
G02X1734688Y135990I0J-926D01*
G01X1732737Y136916D02*
X1733762D01*
G01X1731231Y136292D02*
G02X1732737Y136916I1506J-1505D01*
G01X1729943Y135004D02*
X1731231Y136292D01*
G01X1729088Y134650D02*
G03X1729943Y135004I0J1210D01*
G01X1727755Y134650D02*
X1729088D01*
G01X1726788Y135051D02*
G03X1727755Y134650I968J967D01*
G01X1725667Y136172D02*
X1726788Y135051D01*
G01X1724996Y136450D02*
G02X1725667Y136172I0J-949D01*
G01X1712963Y136450D02*
X1724996D01*
G01X1743501Y143937D02*
X1742214Y142650D01*
G01X1743867Y144820D02*
G02X1743501Y143937I-1248J0D01*
G01X1743867Y146514D02*
Y144820D01*
G01X1743066Y148447D02*
G02X1743867Y146514I-1932J-1933D01*
G01X1736275Y155238D02*
X1743066Y148447D01*
G01X1734520Y155965D02*
G02X1736275Y155238I0J-2482D01*
G01X1733376Y155965D02*
X1734520D01*
G01X1732289Y156412D02*
G03X1733376Y155965I1088J1100D01*
G01X1738472Y119050D02*
G03X1742214Y120600I0J5292D01*
G01X1736395Y119050D02*
X1738472D01*
G01X1734678Y118339D02*
G02X1736395Y119050I1717J-1718D01*
G01X1733305Y116966D02*
X1734678Y118339D01*
G01X1724470Y112774D02*
G03X1733305Y116966I-1464J14491D01*
G01X1724430Y112772D02*
G03X1724470Y112774I0J394D01*
G01X1718065Y144250D02*
G02X1713296Y146226I1J6746D01*
G01X1726455Y144250D02*
X1718065D01*
G01X1727366Y143872D02*
G03X1726455Y144250I-912J-911D01*
G01X1727643Y143595D02*
X1727366Y143872D01*
G01X1727643Y142165D02*
G03Y143595I-715J715D01*
G01X1728953Y140855D02*
G02X1727643Y142165I-655J655D01*
G01X1730383Y140856D02*
G03X1728953Y140855I-715J-715D01*
G01X1731789Y139450D02*
X1730383Y140856D01*
G01X1726730Y151470D02*
G03X1721106Y153800I-5625J-5624D01*
G01X1732243Y145957D02*
X1726730Y151470D01*
G01X1736281Y144284D02*
G02X1732243Y145957I0J5710D01*
G01X1736487Y144284D02*
X1736281D01*
G01X1738097Y143617D02*
G03X1736487Y144284I-1610J-1610D01*
G01X1739064Y142650D02*
X1738097Y143617D01*
G01X1716050Y94772D02*
X1712333Y98489D01*
G01X1734728Y94772D02*
X1716050D01*
G01X1784327Y107211D02*
X1763490D01*
G01X1738527Y129513D02*
G02X1736127Y128519I-2400J2399D01*
G01X1739064Y130050D02*
X1738527Y129513D01*
G01X1722587Y108000D02*
X1723314D01*
G01X1721789Y107202D02*
G02X1722587Y108000I798J0D01*
G01X1721789Y104685D02*
Y107202D01*
G01X1719609Y102505D02*
G03X1721789Y104685I0J2180D01*
G01X1713942Y102505D02*
X1719609D01*
G01X1713016Y101579D02*
G02X1713942Y102505I926J0D01*
G01X1713016Y101310D02*
Y101579D01*
G01X1735339Y139738D02*
G02X1735914Y139500I0J-813D01*
G01X1734820Y139738D02*
X1735339D01*
G01X1733787Y139310D02*
G02X1734820Y139738I1033J-1033D01*
G01X1732713Y138236D02*
X1733787Y139310D01*
G01X1731781Y137850D02*
G03X1732713Y138236I0J1318D01*
G01X1716753Y137850D02*
X1731781D01*
G01X1715808Y138241D02*
G03X1716753Y137850I945J945D01*
G01X1718166Y117085D02*
G03X1715904Y118022I-2262J-2262D01*
G01X1718614Y116691D02*
G03X1718166Y117085I-3275J-3272D01*
G01X1719080Y116225D02*
X1718614Y116691D01*
G01X1719985Y115850D02*
G02X1719080Y116225I0J1280D01*
G01X1725738Y115850D02*
X1719985D01*
G01X1728434Y116967D02*
G02X1725738Y115850I-2696J2695D01*
G01X1732151Y120684D02*
X1728434Y116967D01*
G01X1735932Y122250D02*
G03X1732151Y120684I0J-5347D01*
G01X1738718Y123404D02*
G02X1735932Y122250I-2786J2786D01*
G01X1739064Y123750D02*
X1738718Y123404D01*
G01X1713188Y114640D02*
X1712896Y114641D01*
G01X1713969Y115419D02*
G02X1713188Y114640I-780J1D01*
G01X1714668Y116116D02*
G03X1713969Y115419I-2J-697D01*
G01X1715125Y116115D02*
X1714668Y116116D01*
G01X1715821Y115417D02*
G03X1715125Y116115I-697J1D01*
G01X1715821Y115415D02*
Y115417D01*
G01X1716599Y114634D02*
G02X1715821Y115415I2J780D01*
G01X1716980Y114633D02*
X1716599Y114634D01*
G01X1717294Y114503D02*
G03X1716980Y114633I-314J-314D01*
G01X1717815Y114287D02*
G02X1717294Y114503I0J737D01*
G01X1724919Y114287D02*
X1717815D01*
G01X1730593Y116922D02*
G02X1724919Y114287I-6439J6439D01*
G01X1732617Y118946D02*
X1730593Y116922D01*
G01X1736610Y120600D02*
G03X1732617Y118946I0J-5647D01*
G01X1739064Y120600D02*
X1736610D01*
G01X1764100Y98700D02*
X1757886D01*
G01X1768238Y102838D02*
X1764100Y98700D01*
G01X1783686Y102838D02*
X1768238D01*
G01X1716708Y106352D02*
G03X1714876Y105593I0J-2591D01*
G01X1718149Y106352D02*
X1716708D01*
G01X1718771Y106610D02*
G02X1718149Y106352I-623J623D01*
G01X1720164Y108000D02*
X1718771Y106610D01*
G01X1738940Y149074D02*
X1742214Y145800D01*
G01X1735489Y151220D02*
G02X1738940Y149074I-2879J-8478D01*
G01X1734832Y151416D02*
G02X1735489Y151220I-2229J-8672D01*
G01X1731212Y153480D02*
G03X1734832Y151416I5579J5579D01*
G01X1725406Y159286D02*
X1731212Y153480D01*
G01X1720148Y155532D02*
X1717280Y158400D01*
G01X1720973Y155190D02*
G02X1720148Y155532I0J1166D01*
G01X1723305Y155190D02*
X1720973D01*
G01X1726130Y154020D02*
G03X1723305Y155190I-2825J-2826D01*
G01X1732196Y147953D02*
X1726130Y154020D01*
G01X1732578Y147795D02*
G02X1732196Y147953I0J540D01*
G01X1734531Y147795D02*
X1732578D01*
G01X1735269Y147057D02*
G03X1734531Y147795I-738J0D01*
G01X1735269Y146866D02*
Y147057D01*
G01X1737121Y146866D02*
G02X1735269I-926J0D01*
G01X1737121Y147208D02*
Y146866D01*
G01X1737861Y147948D02*
G03X1737121Y147208I0J-740D01*
G01X1739064Y146745D02*
G03X1737861Y147948I-1203J0D01*
G01X1739064Y145800D02*
Y146745D01*
G01X1724420Y157415D02*
G02X1725724Y156875I0J-1844D01*
G01X1724170Y157415D02*
X1724420D01*
G01X1721763Y158412D02*
G03X1724170Y157415I2407J2407D01*
G01X1721564Y158598D02*
G03X1721763Y158412I2856J2856D01*
G01X1720706Y159456D02*
X1721564Y158598D01*
G01X1720475Y160014D02*
G03X1720706Y159456I789J0D01*
G01X1720268Y160521D02*
G02X1720475Y160014I-517J-507D01*
G01X1720179Y160610D02*
X1720268Y160521D01*
G01X1722374Y203197D02*
X1718993Y206578D01*
G01X1837403Y203197D02*
X1722374D01*
G01X1716999Y185896D02*
X1714192Y183089D01*
G01X1842675Y185896D02*
X1716999D01*
G01X1718463Y216876D02*
X1825376D01*
G01X1713429Y211842D02*
X1718463Y216876D01*
G01X1718903Y214020D02*
X1714469Y209586D01*
G01X1827820Y214020D02*
X1718903D01*
G01X1729892Y193908D02*
X1851041D01*
G01X1718474Y205326D02*
X1729892Y193908D01*
G01X1712493Y214098D02*
X1718549Y220154D01*
G01X1729928Y187028D02*
X1729676Y186776D01*
G01X1842607Y187028D02*
X1729928D01*
G01X1718639Y219180D02*
X1712805Y213346D01*
G01X1722653Y205604D02*
X1843646D01*
G01X1720175Y208082D02*
X1722653Y205604D01*
G01X1722957Y206364D02*
X1720487Y208834D01*
G01X1845386Y206364D02*
X1722957D01*
G01X1732288Y156412D02*
X1732289D01*
G01X1730757Y157943D02*
X1732288Y156412D01*
G01X1730050Y159650D02*
G03X1730757Y157943I2414J0D01*
G01X1730050Y160531D02*
Y159650D01*
G01X1729500Y161858D02*
G02X1730050Y160531I-1328J-1328D01*
G01X1724238Y167120D02*
X1729500Y161858D01*
G01X1722417Y167874D02*
G02X1724238Y167120I0J-2576D01*
G01X1721489Y167874D02*
X1722417D01*
G01X1718612Y169065D02*
G03X1721489Y167874I2876J2877D01*
G01X1716186Y171491D02*
X1718612Y169065D01*
G01X1713538Y172588D02*
G02X1716186Y171491I0J-3744D01*
G01X1718551Y218028D02*
X1713117Y212594D01*
G01X1712317Y202822D02*
X1712316Y202821D01*
G01X1717436Y202822D02*
X1712317D01*
G01X1728854Y191404D02*
X1717436Y202822D01*
G01X1848131Y191404D02*
X1728854D01*
G01X1728335Y190152D02*
X1716918Y201569D01*
G01X1843708Y190152D02*
X1728335D01*
G01X1729373Y192656D02*
X1849722D01*
G01X1717955Y204074D02*
X1729373Y192656D01*
G01X1770434Y184566D02*
X1774500Y180500D01*
G01X1718682Y184566D02*
X1770434D01*
G01X1716453Y182337D02*
X1718682Y184566D01*
G01X1714000Y187780D02*
X1843073D01*
G01X1712531Y189249D02*
X1714000Y187780D01*
G01X1727968Y188532D02*
X1843698D01*
G01X1716083Y200417D02*
X1727968Y188532D01*
G01X1725246Y159672D02*
G03X1725406Y159286I546J0D01*
G01X1724962Y160359D02*
G02X1725246Y159672I-687J-686D01*
G01X1722626Y204009D02*
X1719305Y207330D01*
G01X1838492Y204009D02*
X1722626D01*
G01X1718591Y214772D02*
X1714157Y210338D01*
G01X1826922Y214772D02*
X1718591D01*
G01X1718479Y215724D02*
X1713845Y211090D01*
G01X1826527Y215724D02*
X1718479D01*
G01X1713063Y163166D02*
X1712335D01*
G01X1714992Y162367D02*
G03X1713063Y163166I-1929J-1929D01*
G01X1716288Y161071D02*
X1714992Y162367D01*
G01X1716750Y159954D02*
G03X1716288Y161071I-1582J0D01*
G01X1716750Y159679D02*
Y159954D01*
G01X1717280Y158400D02*
G02X1716750Y159679I1278J1279D01*
G01X1717500Y232200D02*
Y232638D01*
G01X1718513Y231187D02*
X1717500Y232200D01*
G01X1726647Y231187D02*
X1718513D01*
G01X1732760Y237300D02*
X1726647Y231187D01*
G01X1733900Y237300D02*
X1732760D01*
G01X1770850Y235878D02*
X1786848D01*
G01X1769933Y236795D02*
X1770850Y235878D01*
G01X1765256Y236795D02*
X1769933D01*
G01X1764350Y235889D02*
X1765256Y236795D01*
G01X1748173Y235889D02*
X1764350D01*
G01X1746400Y234116D02*
X1748173Y235889D01*
G01X1746400Y231480D02*
Y234116D01*
G01X1744268Y229348D02*
X1746400Y231480D01*
G01X1716039Y229348D02*
X1744268D01*
G01X1782590Y224322D02*
X1717397D01*
G01X1763567Y225973D02*
X1716920D01*
G01X1766077Y228483D02*
X1763567Y225973D01*
G01X1766077Y232681D02*
Y228483D01*
G01X1718549Y220154D02*
X1823858D01*
G01X1717653Y252687D02*
X1724181Y246159D01*
G01X1824350Y219180D02*
X1718639D01*
G01X1722524Y239636D02*
X1824968D01*
G01X1720829Y237941D02*
X1722524Y239636D01*
G01X1720829Y235535D02*
Y237941D01*
G01X1719722Y234428D02*
X1720829Y235535D01*
G01X1716774Y234428D02*
X1719722D01*
G01X1824828Y218028D02*
X1718551D01*
G01X1722930Y241106D02*
X1824562D01*
G01X1719080Y237256D02*
X1722930Y241106D01*
G01X1719080Y236152D02*
Y237256D01*
G01X1716114Y236152D02*
X1719080D01*
G01X1782880Y223548D02*
X1717687D01*
G01X1745801Y227635D02*
X1716454D01*
G01X1749462Y231296D02*
X1745801Y227635D01*
G01X1749462Y232955D02*
Y231296D01*
G01X1719428Y244357D02*
X1824640D01*
G01X1718801Y244984D02*
X1719428Y244357D01*
G01X1718801Y246822D02*
Y244984D01*
G01X1717070Y248553D02*
X1718801Y246822D01*
G01X1794732Y222765D02*
X1717968D01*
G01X1744378Y228394D02*
X1716149D01*
G01X1747300Y231316D02*
X1744378Y228394D01*
G01X1747300Y233952D02*
Y231316D01*
G01X1748485Y235137D02*
X1747300Y233952D01*
G01X1764662Y235137D02*
X1748485D01*
G01X1765568Y236043D02*
X1764662Y235137D01*
G01X1769621Y236043D02*
X1765568D01*
G01X1770538Y235126D02*
X1769621Y236043D01*
G01X1787160Y235126D02*
X1770538D01*
G01X1763879Y225221D02*
X1717232D01*
G01X1768338Y229680D02*
X1763879Y225221D01*
G01X1768338Y233282D02*
Y229680D01*
G01X1768700Y233644D02*
X1768338Y233282D01*
G01X1746113Y226883D02*
X1716766D01*
G01X1751038Y231808D02*
X1746113Y226883D01*
G01X1751038Y232738D02*
Y231808D01*
G01X1752685Y234385D02*
X1751038Y232738D01*
G01X1764974Y234385D02*
X1752685D01*
G01X1765880Y235291D02*
X1764974Y234385D01*
G01X1769309Y235291D02*
X1765880D01*
G01X1770226Y234374D02*
X1769309Y235291D01*
G01X1783004Y234374D02*
X1770226D01*
G01X1734425Y235325D02*
X1736400Y237300D01*
G01X1731885Y235325D02*
X1734425D01*
G01X1726995Y230435D02*
X1731885Y235325D01*
G01X1715420Y230435D02*
X1726995D01*
G01X1718329Y220998D02*
X1822598D01*
G01X1718144Y221877D02*
X1796026D01*
G01X1718049Y246205D02*
X1716453Y247801D01*
G01X1718049Y246185D02*
Y246205D01*
G01X1718048Y246184D02*
X1718049Y246185D01*
G01X1718048Y245562D02*
Y246184D01*
G01X1718049Y245561D02*
X1718048Y245562D01*
G01X1718049Y244672D02*
Y245561D01*
G01X1719733Y242988D02*
X1718049Y244672D01*
G01X1824945Y242988D02*
X1719733D01*
G01X1836317Y455276D02*
X1718673D01*
G01X1834133Y460540D02*
X1720857D01*
G01X1733436Y443964D02*
X1731274Y446126D01*
G01X1872425Y443964D02*
X1733436D01*
G01X1835693Y456780D02*
X1719297D01*
G01X1720233Y459036D02*
X1834757D01*
G01X1831176Y463269D02*
X1721184D01*
G01X1836629Y454524D02*
X1718361D01*
G01X1720545Y459788D02*
X1834445D01*
G01X1736019Y449719D02*
X1737150Y450850D01*
G01X1736019Y447364D02*
Y449719D01*
G01X1737259Y446124D02*
X1736019Y447364D01*
G01X1842102Y446124D02*
X1737259D01*
G01X1835381Y457532D02*
X1719609D01*
G01X1731259Y447841D02*
X1722833D01*
G01X1734384Y444716D02*
X1731259Y447841D01*
G01X1872113Y444716D02*
X1734384D01*
G01X1718985Y456028D02*
X1836005D01*
G01X1835069Y458284D02*
X1719921D01*
G01X1720600Y461861D02*
X1833654D01*
G01X1731679Y478576D02*
X1780345D01*
G01X1729986Y480269D02*
X1731679Y478576D01*
G01X1744600Y521200D02*
X1739128Y515728D01*
G01X1758700Y521200D02*
X1744600D01*
G01X1762400Y524900D02*
X1758700Y521200D01*
G01X1768600Y524900D02*
X1762400D01*
G01X1771343Y522157D02*
X1768600Y524900D01*
G01X1775227Y522157D02*
X1771343D01*
G01X1731991Y479328D02*
X1730298Y481021D01*
G01X1779962Y479328D02*
X1731991D01*
G01X1732386Y480280D02*
X1730693Y481973D01*
G01X1779567Y480280D02*
X1732386D01*
G01X1738000Y511100D02*
X1723244D01*
G01X1745500Y518600D02*
X1738000Y511100D01*
G01X1762700Y518600D02*
X1745500D01*
G01X1764800Y516500D02*
X1762700Y518600D01*
G01X1774100Y516500D02*
X1764800D01*
G01X1724031Y530900D02*
X1717524Y524393D01*
G01X1717902Y523141D02*
X1724509Y529748D01*
G01X1722080Y465429D02*
X1827207D01*
G01X1728073Y484467D02*
X1714736D01*
G01X1728074Y484468D02*
X1728073Y484467D01*
G01X1728696Y484468D02*
X1728074D01*
G01X1728697Y484467D02*
X1728696Y484468D01*
G01X1730610Y484467D02*
X1728697D01*
G01X1733093Y481984D02*
X1730610Y484467D01*
G01X1770086Y481984D02*
X1733093D01*
G01X1781552Y493450D02*
X1770086Y481984D01*
G01X1773296Y518596D02*
X1783057Y528357D01*
G01X1766305Y518596D02*
X1773296D01*
G01X1764400Y520501D02*
X1766305Y518596D01*
G01X1764400Y521800D02*
Y520501D01*
G01X1763500Y522700D02*
X1764400Y521800D01*
G01X1762100Y522700D02*
X1763500D01*
G01X1759274Y519874D02*
X1762100Y522700D01*
G01X1745084Y519874D02*
X1759274D01*
G01X1739786Y514576D02*
X1745084Y519874D01*
G01X1725465Y527444D02*
X1716054Y518033D01*
G01X1717046Y525545D02*
X1723553Y532052D01*
G01X1773823Y501424D02*
X1795475D01*
G01X1755535Y483136D02*
X1773823Y501424D01*
G01X1733571Y483136D02*
X1755535D01*
G01X1731088Y485619D02*
X1733571Y483136D01*
G01X1729175Y485619D02*
X1731088D01*
G01X1729174Y485620D02*
X1729175Y485619D01*
G01X1727596Y485620D02*
X1729174D01*
G01X1727595Y485619D02*
X1727596Y485620D01*
G01X1715844Y485619D02*
X1727595D01*
G01X1718228Y521837D02*
X1724987Y528596D01*
G01X1773691Y517644D02*
X1798971Y542924D01*
G01X1765756Y517644D02*
X1773691D01*
G01X1762715Y520685D02*
X1765756Y517644D01*
G01X1762715Y521085D02*
Y520685D01*
G01X1731367Y477824D02*
X1780033D01*
G01X1729674Y479517D02*
X1731367Y477824D01*
G01X1721768Y464677D02*
X1827744D01*
G01X1728606Y474570D02*
X1714569D01*
G01X1734200Y468976D02*
X1728606Y474570D01*
G01X1829124Y468976D02*
X1734200D01*
G01X1732781Y481232D02*
X1779172D01*
G01X1731088Y482925D02*
X1732781Y481232D01*
G01X1771670Y523500D02*
X1774940D01*
G01X1768880Y526290D02*
X1771670Y523500D01*
G01X1761890Y526290D02*
X1768880D01*
G01X1758400Y522800D02*
X1761890Y526290D01*
G01X1744300Y522800D02*
X1758400D01*
G01X1738380Y516880D02*
X1744300Y522800D01*
G01X1719587Y551055D02*
X1712566Y544034D01*
G01X1732213Y551055D02*
X1719587D01*
G01X1739234Y544034D02*
X1732213Y551055D01*
G01X1746466Y544034D02*
X1739234D01*
G01X1751809Y549377D02*
X1746466Y544034D01*
G01X1752772Y549377D02*
X1751809D01*
G01X1753154Y549759D02*
X1752772Y549377D01*
G01X1754460Y549759D02*
X1753154D01*
G01X1754842Y549377D02*
X1754460Y549759D01*
G01X1756293Y549377D02*
X1754842D01*
G01X1757478Y548192D02*
X1756293Y549377D01*
G01X1730064Y583172D02*
X1733368Y579868D01*
G01X1724000Y583172D02*
X1730064D01*
G01X1720544Y586628D02*
X1724000Y583172D01*
G01X1720544Y594677D02*
Y586628D01*
G01X1734476Y575975D02*
X1724677D01*
G01X1740501Y582000D02*
X1734476Y575975D01*
G01X1743416Y582000D02*
X1740501D01*
G01X1752627Y591211D02*
X1743416Y582000D01*
G01X1760400Y579900D02*
X1776000Y595500D01*
G01X1760400Y572700D02*
Y579900D01*
G01X1761400Y571700D02*
X1760400Y572700D01*
G01X1763500Y571700D02*
X1761400D01*
G01X1764300Y570900D02*
X1763500Y571700D01*
G01X1760497Y530900D02*
X1724031D01*
G01X1764767Y535170D02*
X1760497Y530900D01*
G01X1764767Y538521D02*
Y535170D01*
G01X1762928Y540360D02*
X1764767Y538521D01*
G01X1762928Y569528D02*
Y540360D01*
G01X1764300Y570900D02*
X1762928Y569528D01*
G01X1770228Y569925D02*
X1776683Y576380D01*
G01X1765729Y569925D02*
X1770228D01*
G01X1764080Y568276D02*
X1765729Y569925D01*
G01X1764080Y540838D02*
Y568276D01*
G01X1765919Y538999D02*
X1764080Y540838D01*
G01X1765919Y533968D02*
Y538999D01*
G01X1761699Y529748D02*
X1765919Y533968D01*
G01X1724509Y529748D02*
X1761699D01*
G01X1726480Y572600D02*
X1725694Y571814D01*
G01X1736000Y572600D02*
X1726480D01*
G01X1738900Y575500D02*
X1736000Y572600D01*
G01X1740900Y575500D02*
X1738900D01*
G01X1750567Y585167D02*
X1740900Y575500D01*
G01X1760467Y585167D02*
X1750567D01*
G01X1766400Y591100D02*
X1760467Y585167D01*
G01X1763357Y527444D02*
X1725465D01*
G01X1768223Y532310D02*
X1763357Y527444D01*
G01X1768223Y539955D02*
Y532310D01*
G01X1766384Y541794D02*
X1768223Y539955D01*
G01X1766384Y552039D02*
Y541794D01*
G01X1769300Y554955D02*
X1766384Y552039D01*
G01X1769300Y564429D02*
Y554955D01*
G01X1767529Y566200D02*
X1769300Y564429D01*
G01X1770414Y566200D02*
X1777746Y573532D01*
G01X1767529Y566200D02*
X1770414D01*
G01X1758700Y581429D02*
X1777847Y600576D01*
G01X1758700Y571868D02*
Y581429D01*
G01X1761776Y568792D02*
X1758700Y571868D01*
G01X1761776Y539882D02*
Y568792D01*
G01X1763615Y538043D02*
X1761776Y539882D01*
G01X1763615Y535648D02*
Y538043D01*
G01X1760019Y532052D02*
X1763615Y535648D01*
G01X1723553Y532052D02*
X1760019D01*
G01X1735975Y574567D02*
X1725261D01*
G01X1738316Y576908D02*
X1735975Y574567D01*
G01X1740316Y576908D02*
X1738316D01*
G01X1753211Y589803D02*
X1740316Y576908D01*
G01X1770771Y568500D02*
X1776955Y574684D01*
G01X1765934Y568500D02*
X1770771D01*
G01X1765232Y567798D02*
X1765934Y568500D01*
G01X1765232Y541316D02*
Y567798D01*
G01X1767071Y539477D02*
X1765232Y541316D01*
G01X1767071Y532788D02*
Y539477D01*
G01X1762879Y528596D02*
X1767071Y532788D01*
G01X1724987Y528596D02*
X1762879D01*
G01X1720065Y549903D02*
X1712962Y542800D01*
G01X1731735Y549903D02*
X1720065D01*
G01X1738838Y542800D02*
X1731735Y549903D01*
G01X1748424Y542800D02*
X1738838D01*
G01X1753807Y548183D02*
X1748424Y542800D01*
G01X1742924Y583500D02*
X1761054Y601630D01*
G01X1740001Y583500D02*
X1742924D01*
G01X1733884Y577383D02*
X1740001Y583500D01*
G01X1724093Y577383D02*
X1733884D01*
G01X1722510Y575800D02*
X1724093Y577383D01*
G01X1749500Y564500D02*
X1759500Y554500D01*
G01X1743500Y564500D02*
X1749500D01*
G01X1738438Y560020D02*
X1737958Y560500D01*
G01X1747480Y560020D02*
X1738438D01*
G01X1754000Y553500D02*
X1747480Y560020D01*
G01X1718037Y597184D02*
X1720544Y594677D01*
G01X1761218Y591211D02*
X1752627D01*
G01X1762062Y592055D02*
X1761218Y591211D01*
G01X1770600Y605450D02*
X1778800Y613650D01*
G01X1770600Y600800D02*
Y605450D01*
G01X1766400Y599400D02*
Y591100D01*
G01X1761814Y589803D02*
X1753211D01*
G01X1762062Y589555D02*
X1761814Y589803D01*
G01X1773700Y598910D02*
X1778240Y603450D01*
G01X1769490Y598910D02*
X1773700D01*
G01X1766770Y601630D02*
X1769490Y598910D01*
G01X1761054Y601630D02*
X1766770D01*
G01X1827446Y26719D02*
X1833884Y33157D01*
G01X1827446Y20581D02*
Y26719D01*
G01X1826004Y19139D02*
X1827446Y20581D01*
G01X1826004Y7741D02*
Y19139D01*
G01X1824232Y5969D02*
X1826004Y7741D01*
G01X1821592Y5969D02*
X1824232D01*
G01X1819268Y3645D02*
X1821592Y5969D01*
G01X1817500Y3645D02*
X1819268D01*
G01X1814566Y711D02*
X1817500Y3645D01*
G01X1797502Y711D02*
X1814566D01*
G01X1796735Y-56D02*
X1797502Y711D01*
G01X1833309Y18591D02*
X1838249D01*
G01X1828312Y13594D02*
X1833309Y18591D01*
G01X1828312Y7312D02*
Y13594D01*
G01X1827100Y6100D02*
X1828312Y7312D01*
G01X1827100Y-254D02*
Y6100D01*
G01X1826130Y-1224D02*
X1827100Y-254D01*
G01X1807475Y-1224D02*
X1826130D01*
G01X1805623Y-3076D02*
X1807475Y-1224D01*
G01X1803476Y-3076D02*
X1805623D01*
G01X1801524Y-1124D02*
X1803476Y-3076D01*
G01X1825200Y-14645D02*
X1820969Y-18876D01*
G01X1825200Y-11900D02*
Y-14645D01*
G01X1831996Y-5104D02*
X1825200Y-11900D01*
G01X1831996Y-1651D02*
Y-5104D01*
G01X1833523Y-124D02*
X1831996Y-1651D01*
G01X1833523Y5152D02*
Y-124D01*
G01X1834871Y6500D02*
X1833523Y5152D01*
G01X1843746Y6500D02*
X1834871D01*
G01X1831000Y-4400D02*
X1824448Y-10952D01*
G01X1831000Y-1300D02*
Y-4400D01*
G01X1832571Y271D02*
X1831000Y-1300D01*
G01X1832571Y4728D02*
Y271D01*
G01X1832570Y4729D02*
X1832571Y4728D01*
G01X1832570Y5517D02*
Y4729D01*
G01X1832571Y5518D02*
X1832570Y5517D01*
G01X1832571Y5547D02*
Y5518D01*
G01X1834476Y7452D02*
X1832571Y5547D01*
G01X1841250Y7452D02*
X1834476D01*
G01X1778443Y696D02*
X1775271Y3868D01*
G01X1796423Y696D02*
X1778443D01*
G01X1797323Y1596D02*
X1796423Y696D01*
G01X1810992Y1596D02*
X1797323D01*
G01X1813793Y4397D02*
X1810992Y1596D01*
G01X1818956Y4397D02*
X1813793D01*
G01X1821280Y6721D02*
X1818956Y4397D01*
G01X1823920Y6721D02*
X1821280D01*
G01X1825252Y8053D02*
X1823920Y6721D01*
G01X1825252Y19146D02*
Y8053D01*
G01X1823300Y21098D02*
X1825252Y19146D01*
G01X1823300Y21700D02*
Y21098D01*
G01X1825545Y27098D02*
X1832541Y34094D01*
G01X1821759Y27098D02*
X1825545D01*
G01X1818200Y23539D02*
X1821759Y27098D01*
G01X1818200Y21000D02*
Y23539D01*
G01X1823075Y16125D02*
X1818200Y21000D01*
G01X1823075Y10684D02*
Y16125D01*
G01X1822024Y9633D02*
X1823075Y10684D01*
G01X1822024Y8529D02*
Y9633D01*
G01X1818644Y5149D02*
X1822024Y8529D01*
G01X1813481Y5149D02*
X1818644D01*
G01X1810680Y2348D02*
X1813481Y5149D01*
G01X1797011Y2348D02*
X1810680D01*
G01X1796111Y1448D02*
X1797011Y2348D01*
G01X1778755Y1448D02*
X1796111D01*
G01X1775582Y4621D02*
X1778755Y1448D01*
G01X1774960Y4621D02*
X1775582D01*
G01X1774959Y4620D02*
X1774960Y4621D01*
G01X1825150Y28050D02*
X1834788Y37688D01*
G01X1822154Y28050D02*
X1825150D01*
G01X1822153Y28051D02*
X1822154Y28050D01*
G01X1821365Y28051D02*
X1822153D01*
G01X1821364Y28050D02*
X1821365Y28051D01*
G01X1821000Y28050D02*
X1821364D01*
G01X1817075Y24125D02*
X1821000Y28050D01*
G01X1817075Y20631D02*
Y24125D01*
G01X1822123Y15583D02*
X1817075Y20631D01*
G01X1822123Y11079D02*
Y15583D01*
G01X1821072Y10028D02*
X1822123Y11079D01*
G01X1821072Y8924D02*
Y10028D01*
G01X1818249Y6101D02*
X1821072Y8924D01*
G01X1813086Y6101D02*
X1818249D01*
G01X1810285Y3300D02*
X1813086Y6101D01*
G01X1796616Y3300D02*
X1810285D01*
G01X1795916Y2600D02*
X1796616Y3300D01*
G01X1781101Y2600D02*
X1795916D01*
G01X1815150Y21209D02*
Y26650D01*
G01X1821171Y15188D02*
X1815150Y21209D01*
G01X1821171Y11474D02*
Y15188D01*
G01X1820120Y10423D02*
X1821171Y11474D01*
G01X1820120Y9319D02*
Y10423D01*
G01X1817854Y7053D02*
X1820120Y9319D01*
G01X1812691Y7053D02*
X1817854D01*
G01X1809890Y4252D02*
X1812691Y7053D01*
G01X1796221Y4252D02*
X1809890D01*
G01X1795591Y3622D02*
X1796221Y4252D01*
G01X1782143Y3622D02*
X1795591D01*
G01X1817750Y29250D02*
X1815150Y26650D01*
G01X1825003Y29250D02*
X1817750D01*
G01X1834393Y38640D02*
X1825003Y29250D01*
G01X1829900Y10735D02*
X1829888D01*
G01X1829900Y10301D02*
Y10735D01*
G01X1830452Y9749D02*
X1829900Y10301D01*
G01X1830452Y846D02*
Y9749D01*
G01X1829096Y-510D02*
X1830452Y846D01*
G01X1829096Y-3605D02*
Y-510D01*
G01X1823701Y-9000D02*
X1829096Y-3605D01*
G01X1830048Y-4005D02*
X1824053Y-10000D01*
G01X1830048Y-905D02*
Y-4005D01*
G01X1831500Y547D02*
X1830048Y-905D01*
G01X1831500Y6671D02*
Y547D01*
G01X1834476Y9647D02*
X1831500Y6671D01*
G01X1834476Y12469D02*
Y9647D01*
G01X1843256Y21249D02*
X1834476Y12469D01*
G01X1782621Y4774D02*
X1773941Y13454D01*
G01X1795113Y4774D02*
X1782621D01*
G01X1795743Y5404D02*
X1795113Y4774D01*
G01X1803127Y5404D02*
X1795743D01*
G01X1803129Y5406D02*
X1803127Y5404D01*
G01X1804871Y5406D02*
X1803129D01*
G01X1804873Y5404D02*
X1804871Y5406D01*
G01X1809412Y5404D02*
X1804873D01*
G01X1812213Y8205D02*
X1809412Y5404D01*
G01X1817376Y8205D02*
X1812213D01*
G01X1818968Y9797D02*
X1817376Y8205D01*
G01X1818968Y10901D02*
Y9797D01*
G01X1820019Y11952D02*
X1818968Y10901D01*
G01X1820019Y14710D02*
Y11952D01*
G01X1813148Y21581D02*
X1820019Y14710D01*
G01X1813148Y27451D02*
Y21581D01*
G01X1817871Y32174D02*
X1813148Y27451D01*
G01X1821307Y32174D02*
X1817871D01*
G01X1823966Y34833D02*
X1821307Y32174D01*
G01X1835452Y-15707D02*
X1829979Y-21180D01*
G01X1835452Y-12049D02*
Y-15707D01*
G01X1840800Y-6701D02*
X1835452Y-12049D01*
G01X1831388Y23220D02*
X1837653D01*
G01X1830304Y22136D02*
X1831388Y23220D01*
G01X1830304Y19398D02*
Y22136D01*
G01X1826956Y16050D02*
X1830304Y19398D01*
G01X1826956Y7346D02*
Y16050D01*
G01X1824627Y5017D02*
X1826956Y7346D01*
G01X1823911Y5017D02*
X1824627D01*
G01X1822800Y3906D02*
X1823911Y5017D01*
G01X1822800Y2871D02*
Y3906D01*
G01X1819687Y-242D02*
X1822800Y2871D01*
G01X1806058Y-242D02*
X1819687D01*
G01X1804800Y-1500D02*
X1806058Y-242D01*
G01X1834300Y-15229D02*
X1829501Y-20028D01*
G01X1834300Y-11499D02*
Y-15229D01*
G01X1839600Y-6199D02*
X1834300Y-11499D01*
G01X1833884Y33157D02*
X1839257D01*
G01X1827100Y83400D02*
Y81600D01*
G01X1825200Y85300D02*
X1827100Y83400D01*
G01X1823100Y85300D02*
X1825200D01*
G01X1816800Y79000D02*
X1823100Y85300D01*
G01X1804500Y79000D02*
X1816800D01*
G01X1801244Y82256D02*
X1804500Y79000D01*
G01X1798454Y82256D02*
X1801244D01*
G01X1844440Y103524D02*
X1833061Y92145D01*
G01X1832541Y34094D02*
X1838694D01*
G01X1789986Y86786D02*
X1805296Y102096D01*
G01X1787206Y86786D02*
X1789986D01*
G01X1782177Y81757D02*
X1787206Y86786D01*
G01X1820152Y94453D02*
X1826299Y100600D01*
G01X1820152Y89453D02*
Y94453D01*
G01X1815804Y85105D02*
X1820152Y89453D01*
G01X1807230Y85105D02*
X1815804D01*
G01X1801559Y90776D02*
X1807230Y85105D01*
G01X1798192Y90776D02*
X1801559D01*
G01X1787468Y80052D02*
X1798192Y90776D01*
G01X1834788Y37688D02*
X1839324D01*
G01X1838929Y38640D02*
X1834393D01*
G01X1808848Y108352D02*
X1791718Y91222D01*
G01X1821183Y94083D02*
X1826700Y99600D01*
G01X1821183Y89083D02*
Y94083D01*
G01X1816253Y84153D02*
X1821183Y89083D01*
G01X1806835Y84153D02*
X1816253D01*
G01X1801164Y89824D02*
X1806835Y84153D01*
G01X1799135Y89824D02*
X1801164D01*
G01X1788411Y79100D02*
X1799135Y89824D01*
G01X1823966Y36453D02*
Y34833D01*
G01X1826900Y39387D02*
X1823966Y36453D01*
G01X1826900Y40400D02*
Y39387D01*
G01X1786768Y81004D02*
X1806793Y101029D01*
G01X1825439Y130939D02*
X1845133D01*
G01X1819500Y125000D02*
X1825439Y130939D01*
G01X1812084Y125000D02*
X1819500D01*
G01X1793071Y105987D02*
X1812084Y125000D01*
G01X1790533Y105987D02*
X1793071D01*
G01X1784885Y100339D02*
X1790533Y105987D01*
G01X1822774Y131691D02*
X1844821D01*
G01X1820635Y129552D02*
X1822774Y131691D01*
G01X1812183Y129552D02*
X1820635D01*
G01X1809538Y126907D02*
X1812183Y129552D01*
G01X1806441Y126907D02*
X1809538D01*
G01X1804354Y124820D02*
X1806441Y126907D01*
G01X1804354Y122590D02*
Y124820D01*
G01X1792124Y110360D02*
X1804354Y122590D01*
G01X1789525Y110360D02*
X1792124D01*
G01X1785245Y106080D02*
X1789525Y110360D01*
G01X1805150Y110455D02*
X1791939Y97244D01*
G01X1805150Y115521D02*
Y110455D01*
G01X1811107Y121478D02*
X1805150Y115521D01*
G01X1815026Y121478D02*
X1811107D01*
G01X1818417Y107200D02*
X1844770D01*
G01X1813313Y102096D02*
X1818417Y107200D01*
G01X1805296Y102096D02*
X1813313D01*
G01X1830080Y99887D02*
X1835655D01*
G01X1829367Y100600D02*
X1830080Y99887D01*
G01X1826299Y100600D02*
X1829367D01*
G01X1827585Y128435D02*
X1844095D01*
G01X1817637Y118487D02*
X1827585Y128435D01*
G01X1811658Y118487D02*
X1817637D01*
G01X1808331Y115160D02*
X1811658Y118487D01*
G01X1808331Y113916D02*
Y115160D01*
G01X1809889Y112358D02*
X1808331Y113916D01*
G01X1809889Y110740D02*
Y112358D01*
G01X1793730Y94581D02*
X1809889Y110740D01*
G01X1774685Y94581D02*
X1793730D01*
G01X1843351Y108352D02*
X1808848D01*
G01X1829685Y98935D02*
X1836050D01*
G01X1829020Y99600D02*
X1829685Y98935D01*
G01X1826700Y99600D02*
X1829020D01*
G01X1790227Y107455D02*
X1784373Y101601D01*
G01X1792614Y107455D02*
X1790227D01*
G01X1807818Y122659D02*
X1792614Y107455D01*
G01X1807818Y124179D02*
Y122659D01*
G01X1806402Y109024D02*
X1793370Y95992D01*
G01X1806402Y115002D02*
Y109024D01*
G01X1811139Y119739D02*
X1806402Y115002D01*
G01X1811197Y119739D02*
X1811139D01*
G01X1811209Y119751D02*
X1811197Y119739D01*
G01X1815520Y119751D02*
X1811209D01*
G01X1815532Y119739D02*
X1815520Y119751D01*
G01X1817118Y119739D02*
X1815532D01*
G01X1827066Y129687D02*
X1817118Y119739D01*
G01X1844614Y129687D02*
X1827066D01*
G01X1788867Y111751D02*
X1784327Y107211D01*
G01X1792107Y111751D02*
X1788867D01*
G01X1803070Y122714D02*
X1792107Y111751D01*
G01X1803070Y125250D02*
Y122714D01*
G01X1806320Y128500D02*
X1803070Y125250D01*
G01X1807509Y128500D02*
X1806320D01*
G01X1789862Y109014D02*
X1783686Y102838D01*
G01X1792430Y109014D02*
X1789862D01*
G01X1805789Y122373D02*
X1792430Y109014D01*
G01X1805789Y124545D02*
Y122373D01*
G01X1806999Y125755D02*
X1805789Y124545D01*
G01X1810897Y125755D02*
X1806999D01*
G01X1813118Y127976D02*
X1810897Y125755D01*
G01X1815901Y103620D02*
X1824990D01*
G01X1813310Y101029D02*
X1815901Y103620D01*
G01X1806793Y101029D02*
X1813310D01*
G01X1825376Y216876D02*
X1829267Y220767D01*
G01X1830700Y216900D02*
X1827820Y214020D01*
G01X1834400Y216900D02*
X1830700D01*
G01X1835356Y171756D02*
X1837293Y173693D01*
G01X1835356Y169830D02*
Y171756D01*
G01X1834208Y168682D02*
X1835356Y169830D01*
G01X1822591Y168682D02*
X1834208D01*
G01X1821261Y170012D02*
X1822591Y168682D01*
G01X1840433Y196567D02*
X1830415D01*
G01X1833767Y173284D02*
X1835831Y175348D01*
G01X1800249Y173284D02*
X1833767D01*
G01X1799033Y174500D02*
X1800249Y173284D01*
G01X1793082Y174500D02*
X1799033D01*
G01X1791582Y173000D02*
X1793082Y174500D01*
G01X1776500Y173000D02*
X1791582D01*
G01X1774500Y175000D02*
X1776500Y173000D01*
G01X1774500Y180500D02*
Y175000D01*
G01X1833629Y171679D02*
X1836395Y174445D01*
G01X1833629Y170807D02*
Y171679D01*
G01X1830813Y218663D02*
X1826922Y214772D01*
G01X1834182Y176100D02*
X1850952D01*
G01X1834103Y176021D02*
X1834182Y176100D01*
G01X1830418Y219615D02*
X1826527Y215724D01*
G01X1824691Y237428D02*
X1826085Y236034D01*
G01X1788398Y237428D02*
X1824691D01*
G01X1786848Y235878D02*
X1788398Y237428D01*
G01X1829267Y220767D02*
X1838716D01*
G01X1834143Y247600D02*
X1843700D01*
G01X1827935Y253808D02*
X1834143Y247600D01*
G01X1826244Y260273D02*
X1826243Y260272D01*
G01X1830982Y260273D02*
X1826244D01*
G01X1830983Y260272D02*
X1830982Y260273D01*
G01X1865625Y260272D02*
X1830983D01*
G01X1784200Y225932D02*
X1782590Y224322D01*
G01X1784200Y230442D02*
Y225932D01*
G01X1789386Y235628D02*
X1784200Y230442D01*
G01X1793072Y235628D02*
X1789386D01*
G01X1793600Y235100D02*
X1793072Y235628D01*
G01X1838519Y248700D02*
X1832659Y254560D01*
G01X1825932Y261025D02*
X1825931Y261024D01*
G01X1831294Y261025D02*
X1825932D01*
G01X1831295Y261024D02*
X1831294Y261025D01*
G01X1866020Y261024D02*
X1831295D01*
G01X1834531Y257416D02*
X1840195Y251752D01*
G01X1826727Y223023D02*
X1840465D01*
G01X1823858Y220154D02*
X1826727Y223023D01*
G01X1834136Y256464D02*
X1839800Y250800D01*
G01X1827441Y222271D02*
X1824350Y219180D01*
G01X1839340Y222271D02*
X1827441D01*
G01X1834143Y226801D02*
X1837804D01*
G01X1829589Y231355D02*
X1834143Y226801D01*
G01X1829589Y231977D02*
Y231355D01*
G01X1829590Y231978D02*
X1829589Y231977D01*
G01X1829590Y235014D02*
Y231978D01*
G01X1824968Y239636D02*
X1829590Y235014D01*
G01X1828319Y221519D02*
X1824828Y218028D01*
G01X1839028Y221519D02*
X1828319D01*
G01X1831607Y261776D02*
X1866432D01*
G01X1831606Y261777D02*
X1831607Y261776D01*
G01X1825620Y261777D02*
X1831606D01*
G01X1825619Y261776D02*
X1825620Y261777D01*
G01X1834455Y227553D02*
X1845193D01*
G01X1830342Y231666D02*
X1834455Y227553D01*
G01X1830342Y235326D02*
Y231666D01*
G01X1824562Y241106D02*
X1830342Y235326D01*
G01X1784952Y225620D02*
X1782880Y223548D01*
G01X1784952Y230130D02*
Y225620D01*
G01X1789698Y234876D02*
X1784952Y230130D01*
G01X1791324Y234876D02*
X1789698D01*
G01X1793700Y232500D02*
X1791324Y234876D01*
G01X1831919Y262528D02*
X1866744D01*
G01X1831918Y262529D02*
X1831919Y262528D01*
G01X1825308Y262529D02*
X1831918D01*
G01X1825307Y262528D02*
X1825308Y262529D01*
G01X1834800Y230400D02*
X1848470D01*
G01X1832600Y232600D02*
X1834800Y230400D01*
G01X1832600Y236397D02*
Y232600D01*
G01X1824640Y244357D02*
X1832600Y236397D01*
G01X1803280Y231313D02*
X1794732Y222765D01*
G01X1803280Y232611D02*
Y231313D01*
G01X1788710Y236676D02*
X1787160Y235126D01*
G01X1822053Y236676D02*
X1788710D01*
G01X1822877Y235852D02*
X1822053Y236676D01*
G01X1833021Y265184D02*
X1868319D01*
G01X1833020Y265185D02*
X1833021Y265184D01*
G01X1824206Y265185D02*
X1833020D01*
G01X1824205Y265184D02*
X1824206Y265185D01*
G01X1834767Y228305D02*
X1845505D01*
G01X1831096Y231976D02*
X1834767Y228305D01*
G01X1831096Y235637D02*
Y231976D01*
G01X1824875Y241858D02*
X1831096Y235637D01*
G01X1838683Y249600D02*
X1832971Y255312D01*
G01X1832314Y263480D02*
X1867320D01*
G01X1832313Y263481D02*
X1832314Y263480D01*
G01X1824913Y263481D02*
X1832313D01*
G01X1824912Y263480D02*
X1824913Y263481D01*
G01X1837843Y218663D02*
X1830813D01*
G01X1824518Y264433D02*
X1824517Y264432D01*
G01X1832708Y264433D02*
X1824518D01*
G01X1832709Y264432D02*
X1832708Y264433D01*
G01X1867724Y264432D02*
X1832709D01*
G01X1838238Y219615D02*
X1830418D01*
G01X1784440Y232938D02*
X1783004Y234374D01*
G01X1825700Y224100D02*
X1840452D01*
G01X1822598Y220998D02*
X1825700Y224100D01*
G01X1806083Y231934D02*
Y232584D01*
G01X1796026Y221877D02*
X1806083Y231934D01*
G01X1831848Y236085D02*
X1824945Y242988D01*
G01X1831848Y232288D02*
Y236085D01*
G01X1834736Y229400D02*
X1831848Y232288D01*
G01X1845828Y229400D02*
X1834736D01*
G01X1835553Y461960D02*
X1834133Y460540D01*
G01X1834757Y459036D02*
X1836177Y460456D01*
G01X1832542Y464635D02*
X1831176Y463269D01*
G01X1846671Y464635D02*
X1832542D01*
G01X1834445Y459788D02*
X1835865Y461208D01*
G01X1836801Y458952D02*
X1835381Y457532D01*
G01X1827744Y464677D02*
X1833767Y470700D01*
G01X1836489Y459704D02*
X1835069Y458284D01*
G01X1835104Y463311D02*
X1847339D01*
G01X1833654Y461861D02*
X1835104Y463311D01*
G01X1835365Y479559D02*
X1852195D01*
G01X1828210Y472404D02*
X1835365Y479559D01*
G01X1813693Y472404D02*
X1828210D01*
G01X1808914Y477183D02*
X1813693Y472404D01*
G01X1798867Y477183D02*
X1808914D01*
G01X1795784Y474100D02*
X1798867Y477183D01*
G01X1784821Y474100D02*
X1795784D01*
G01X1780345Y478576D02*
X1784821Y474100D01*
G01X1781904Y528834D02*
X1775227Y522157D01*
G01X1784082Y483448D02*
X1779962Y479328D01*
G01X1799145Y483448D02*
X1784082D01*
G01X1803900Y488203D02*
X1799145Y483448D01*
G01X1803900Y491500D02*
Y488203D01*
G01X1783687Y484400D02*
X1779567Y480280D01*
G01X1784853Y484400D02*
X1783687D01*
G01X1784854Y484401D02*
X1784853Y484400D01*
G01X1785642Y484401D02*
X1784854D01*
G01X1785643Y484400D02*
X1785642Y484401D01*
G01X1790447Y484400D02*
X1785643D01*
G01X1793680Y487633D02*
X1790447Y484400D01*
G01X1793680Y491709D02*
Y487633D01*
G01X1795715Y493744D02*
X1793680Y491709D01*
G01X1826924Y493744D02*
X1795715D01*
G01X1839376Y481292D02*
X1826924Y493744D01*
G01X1777300Y519700D02*
X1774100Y516500D01*
G01X1786800Y519700D02*
X1777300D01*
G01X1787800Y520700D02*
X1786800Y519700D01*
G01X1787800Y525600D02*
Y520700D01*
G01X1803220Y541020D02*
X1787800Y525600D01*
G01X1834054Y472276D02*
X1837300D01*
G01X1827207Y465429D02*
X1834054Y472276D01*
G01X1792986Y493450D02*
X1781552D01*
G01X1794984Y495448D02*
X1792986Y493450D01*
G01X1810954Y495448D02*
X1794984D01*
G01X1813006Y497500D02*
X1810954Y495448D01*
G01X1827800Y497500D02*
X1813006D01*
G01X1829576Y495724D02*
X1827800Y497500D01*
G01X1838824Y495724D02*
X1829576D01*
G01X1786000Y525563D02*
Y522600D01*
G01X1802409Y541972D02*
X1786000Y525563D01*
G01X1832348Y498652D02*
X1833700Y497300D01*
G01X1812344Y498652D02*
X1832348D01*
G01X1810292Y496600D02*
X1812344Y498652D01*
G01X1800299Y496600D02*
X1810292D01*
G01X1795475Y501424D02*
X1800299Y496600D01*
G01X1829662Y471652D02*
X1835879Y477869D01*
G01X1812330Y471652D02*
X1829662D01*
G01X1807551Y476431D02*
X1812330Y471652D01*
G01X1800499Y476431D02*
X1807551D01*
G01X1796682Y472614D02*
X1800499Y476431D01*
G01X1785243Y472614D02*
X1796682D01*
G01X1780033Y477824D02*
X1785243Y472614D01*
G01X1833767Y470700D02*
X1851500D01*
G01X1834000Y473852D02*
X1829124Y468976D01*
G01X1853022Y473852D02*
X1834000D01*
G01X1827614Y494696D02*
X1839236Y483074D01*
G01X1795296Y494696D02*
X1827614D01*
G01X1792610Y492010D02*
X1795296Y494696D01*
G01X1792610Y487910D02*
Y492010D01*
G01X1790210Y485510D02*
X1792610Y487910D01*
G01X1783450Y485510D02*
X1790210D01*
G01X1779172Y481232D02*
X1783450Y485510D01*
G01X1774940Y523500D02*
X1780752Y529312D01*
G01X1781904Y533181D02*
Y528834D01*
G01X1791828Y543105D02*
X1781904Y533181D01*
G01X1791828Y556722D02*
Y543105D01*
G01X1790218Y558332D02*
X1791828Y556722D01*
G01X1790218Y571518D02*
Y558332D01*
G01X1792826Y574126D02*
X1790218Y571518D01*
G01X1792826Y574654D02*
Y574126D01*
G01X1792805Y574675D02*
X1792826Y574654D01*
G01X1813480Y541020D02*
X1803220D01*
G01X1822300Y532200D02*
X1813480Y541020D01*
G01X1834200Y532200D02*
X1822300D01*
G01X1841300Y525100D02*
X1834200Y532200D01*
G01X1815907Y587480D02*
X1816458D01*
G01X1814539Y588848D02*
X1815907Y587480D01*
G01X1782050Y583779D02*
X1788969Y590698D01*
G01X1782050Y578290D02*
Y583779D01*
G01X1780140Y576380D02*
X1782050Y578290D01*
G01X1776683Y576380D02*
X1780140D01*
G01X1830634Y558766D02*
X1849204D01*
G01X1827187Y562213D02*
X1830634Y558766D01*
G01X1806902Y562213D02*
X1827187D01*
G01X1799881Y555192D02*
X1806902Y562213D01*
G01X1799881Y548320D02*
Y555192D01*
G01X1783057Y531496D02*
X1799881Y548320D01*
G01X1783057Y528357D02*
Y531496D01*
G01X1790125Y587898D02*
X1791349Y589122D01*
G01X1790125Y578795D02*
Y587898D01*
G01X1784862Y573532D02*
X1790125Y578795D01*
G01X1777746Y573532D02*
X1784862D01*
G01X1840719Y541972D02*
X1802409D01*
G01X1788300Y578600D02*
Y585100D01*
G01X1784384Y574684D02*
X1788300Y578600D01*
G01X1776955Y574684D02*
X1784384D01*
G01X1798971Y542924D02*
X1840324D01*
G01X1821174Y554862D02*
X1842400D01*
G01X1819260Y556776D02*
X1821174Y554862D01*
G01X1810372Y556776D02*
X1819260D01*
G01X1809309Y555713D02*
X1810372Y556776D01*
G01X1834703Y582153D02*
X1837534Y579322D01*
G01X1834703Y583082D02*
Y582153D01*
G01X1829909Y587876D02*
X1834703Y583082D01*
G01X1829909Y588026D02*
Y587876D01*
G01X1827935Y590000D02*
X1829909Y588026D01*
G01X1795900Y552100D02*
X1793900Y550100D01*
G01X1795900Y558330D02*
Y552100D01*
G01X1793660Y560570D02*
X1795900Y558330D01*
G01X1813299Y526701D02*
X1813500Y526500D01*
G01X1813299Y532143D02*
Y526701D01*
G01X1813654Y532498D02*
X1813299Y532143D01*
G01X1820002Y532498D02*
X1813654D01*
G01X1821500Y531000D02*
X1820002Y532498D01*
G01X1831900Y531000D02*
X1821500D01*
G01X1837200Y525700D02*
X1831900Y531000D01*
G01X1791329Y583059D02*
X1792170Y583900D01*
G01X1791329Y577358D02*
Y583059D01*
G01X1789066Y575095D02*
X1791329Y577358D01*
G01X1789066Y557854D02*
Y575095D01*
G01X1790676Y556244D02*
X1789066Y557854D01*
G01X1790676Y544006D02*
Y556244D01*
G01X1780752Y534082D02*
X1790676Y544006D01*
G01X1780752Y529312D02*
Y534082D01*
G01X1789853Y595500D02*
X1791323Y594030D01*
G01X1776000Y595500D02*
X1789853D01*
G01X1795717Y588848D02*
X1814539D01*
G01X1793867Y590698D02*
X1795717Y588848D01*
G01X1788969Y590698D02*
X1793867D01*
G01X1824180Y610010D02*
X1840220Y593970D01*
G01X1793700Y610010D02*
X1824180D01*
G01X1790060Y613650D02*
X1793700Y610010D01*
G01X1778800Y613650D02*
X1790060D01*
G01X1787424Y600576D02*
X1787500Y600500D01*
G01X1777847Y600576D02*
X1787424D01*
G01X1800500Y590000D02*
X1827935D01*
G01X1787050Y603450D02*
X1800500Y590000D01*
G01X1778240Y603450D02*
X1787050D01*
G01X1838249Y18591D02*
X1841289Y21631D01*
G01X1845602Y8356D02*
X1843746Y6500D01*
G01X1845602Y10899D02*
Y8356D01*
G01X1843768Y12733D02*
X1845602Y10899D01*
G01X1843768Y15682D02*
Y12733D01*
G01X1846460Y18374D02*
X1843768Y15682D01*
G01X1866682Y18374D02*
X1846460D01*
G01X1879530Y31222D02*
X1866682Y18374D01*
G01X1879530Y32605D02*
Y31222D01*
G01X1885600Y38675D02*
X1879530Y32605D01*
G01X1843426Y9528D02*
X1841250Y7452D01*
G01X1865816Y31783D02*
X1868818Y34785D01*
G01X1853453Y31783D02*
X1865816D01*
G01X1851659Y33577D02*
X1853453Y31783D01*
G01X1843256Y28756D02*
Y21249D01*
G01X1846573Y32073D02*
X1843256Y28756D01*
G01X1846674Y32073D02*
X1846573D01*
G01X1849027Y34426D02*
X1846674Y32073D01*
G01X1840800Y-729D02*
Y-6701D01*
G01X1856491Y14962D02*
X1840800Y-729D01*
G01X1877247Y14962D02*
X1856491D01*
G01X1881396Y19111D02*
X1877247Y14962D01*
G01X1885288Y19111D02*
X1881396D01*
G01X1887865Y21688D02*
X1885288Y19111D01*
G01X1887865Y36520D02*
Y21688D01*
G01X1866211Y30831D02*
X1869213Y33833D01*
G01X1853058Y30831D02*
X1866211D01*
G01X1850659Y33230D02*
X1853058Y30831D01*
G01X1841352Y31489D02*
X1845874Y36011D01*
G01X1841352Y26919D02*
Y31489D01*
G01X1837653Y23220D02*
X1841352Y26919D01*
G01X1849732Y17622D02*
X1845420Y13310D01*
G01X1866994Y17622D02*
X1849732D01*
G01X1880331Y30959D02*
X1866994Y17622D01*
G01X1880331Y32342D02*
Y30959D01*
G01X1886555Y38566D02*
X1880331Y32342D01*
G01X1839600Y-299D02*
Y-6199D01*
G01X1856013Y16114D02*
X1839600Y-299D01*
G01X1876769Y16114D02*
X1856013D01*
G01X1880937Y20282D02*
X1876769Y16114D01*
G01X1881346Y20282D02*
X1880937D01*
G01X1881352Y20288D02*
X1881346Y20282D01*
G01X1882326Y20288D02*
X1881352D01*
G01X1882327Y20287D02*
X1882326Y20288D01*
G01X1884834Y20287D02*
X1882327D01*
G01X1886666Y22119D02*
X1884834Y20287D01*
G01X1886666Y34006D02*
Y22119D01*
G01X1841060Y34960D02*
Y35540D01*
G01X1839257Y33157D02*
X1841060Y34960D01*
G01X1885600Y63183D02*
Y38675D01*
G01X1890663Y68246D02*
X1885600Y63183D01*
G01X1912037Y68246D02*
X1890663D01*
G01X1876236Y34785D02*
X1878997Y37546D01*
G01X1868818Y34785D02*
X1876236D01*
G01X1851659Y35884D02*
Y33577D01*
G01X1850427Y37116D02*
X1851659Y35884D01*
G01X1840275Y37116D02*
X1850427D01*
G01X1839400Y36241D02*
X1840275Y37116D01*
G01X1839400Y34800D02*
Y36241D01*
G01X1838694Y34094D02*
X1839400Y34800D01*
G01X1900989Y73460D02*
X1896970D01*
G01X1892305Y90389D02*
X1901176Y99260D01*
G01X1874931Y90389D02*
X1892305D01*
G01X1858600Y106720D02*
X1874931Y90389D01*
G01X1889321Y70150D02*
X1911075D01*
G01X1880150Y60979D02*
X1889321Y70150D01*
G01X1880150Y57650D02*
Y60979D01*
G01X1878310Y55810D02*
X1880150Y57650D01*
G01X1878310Y47173D02*
Y55810D01*
G01X1875040Y43903D02*
X1878310Y47173D01*
G01X1875040Y42354D02*
Y43903D01*
G01X1868782Y36096D02*
X1875040Y42354D01*
G01X1856007Y36096D02*
X1868782D01*
G01X1854035Y38068D02*
X1856007Y36096D01*
G01X1839704Y38068D02*
X1854035D01*
G01X1839324Y37688D02*
X1839704Y38068D01*
G01X1895354Y75650D02*
X1899863D01*
G01X1839309Y39020D02*
X1838929Y38640D01*
G01X1854430Y39020D02*
X1839309D01*
G01X1856402Y37048D02*
X1854430Y39020D01*
G01X1868224Y37048D02*
X1856402D01*
G01X1874020Y42844D02*
X1868224Y37048D01*
G01X1874020Y44230D02*
Y42844D01*
G01X1877240Y47450D02*
X1874020Y44230D01*
G01X1877240Y56351D02*
Y47450D01*
G01X1879120Y58231D02*
X1877240Y56351D01*
G01X1879120Y61850D02*
Y58231D01*
G01X1888670Y71400D02*
X1879120Y61850D01*
G01X1910978Y71400D02*
X1888670D01*
G01X1875281Y91386D02*
X1859562Y107105D01*
G01X1891955Y91386D02*
X1875281D01*
G01X1903305Y102736D02*
X1891955Y91386D01*
G01X1892700Y89437D02*
X1901571Y98308D01*
G01X1874536Y89437D02*
X1892700D01*
G01X1857303Y106670D02*
X1874536Y89437D01*
G01X1894701Y77226D02*
X1899634D01*
G01X1894075Y76600D02*
X1894701Y77226D01*
G01X1883200Y76600D02*
X1894075D01*
G01X1892524Y41179D02*
X1887865Y36520D01*
G01X1892524Y55842D02*
Y41179D01*
G01X1901871Y65189D02*
X1892524Y55842D01*
G01X1890268Y69198D02*
X1911470D01*
G01X1884648Y63578D02*
X1890268Y69198D01*
G01X1884648Y40968D02*
Y63578D01*
G01X1877513Y33833D02*
X1884648Y40968D01*
G01X1869213Y33833D02*
X1877513D01*
G01X1850659Y35023D02*
Y33230D01*
G01X1849671Y36011D02*
X1850659Y35023D01*
G01X1845874Y36011D02*
X1849671D01*
G01X1886555Y61170D02*
Y38566D01*
G01X1892879Y67494D02*
X1886555Y61170D01*
G01X1912349Y67494D02*
X1892879D01*
G01X1886665Y34007D02*
X1886666Y34006D01*
G01X1886665Y36997D02*
Y34007D01*
G01X1891372Y41704D02*
X1886665Y36997D01*
G01X1891372Y56320D02*
Y41704D01*
G01X1901394Y66342D02*
X1891372Y56320D01*
G01X1880914Y151431D02*
X1886050D01*
G01X1879748Y152597D02*
X1880914Y151431D01*
G01X1879748Y153420D02*
Y152597D01*
G01X1878524Y154644D02*
X1879748Y153420D01*
G01X1872956Y154644D02*
X1878524D01*
G01X1871700Y155900D02*
X1872956Y154644D01*
G01X1861978Y155900D02*
X1871700D01*
G01X1860500Y157378D02*
X1861978Y155900D01*
G01X1887919Y97142D02*
X1898102Y107325D01*
G01X1875608Y97142D02*
X1887919D01*
G01X1868992Y103758D02*
X1875608Y97142D01*
G01X1868992Y113198D02*
Y103758D01*
G01X1861522Y120668D02*
X1868992Y113198D01*
G01X1855404Y120668D02*
X1861522D01*
G01X1845133Y130939D02*
X1855404Y120668D01*
G01X1886395Y97894D02*
X1897651Y109150D01*
G01X1875920Y97894D02*
X1886395D01*
G01X1869744Y104070D02*
X1875920Y97894D01*
G01X1869744Y113966D02*
Y104070D01*
G01X1862291Y121420D02*
X1869744Y113966D01*
G01X1855716Y121420D02*
X1862291D01*
G01X1845444Y131692D02*
X1855716Y121420D01*
G01X1844822Y131692D02*
X1845444D01*
G01X1844821Y131691D02*
X1844822Y131692D01*
G01X1873552Y138618D02*
X1872254D01*
G01X1876909Y141975D02*
X1873552Y138618D01*
G01X1879539Y141975D02*
X1876909D01*
G01X1883811Y137703D02*
X1879539Y141975D01*
G01X1897488Y137703D02*
X1883811D01*
G01X1866602Y144270D02*
X1872254Y138618D01*
G01X1859203Y144270D02*
X1866602D01*
G01X1852387Y151086D02*
X1859203Y144270D01*
G01X1846145Y151086D02*
X1852387D01*
G01X1845237Y151994D02*
X1846145Y151086D01*
G01X1839667Y151994D02*
X1845237D01*
G01X1890580Y154800D02*
X1925703D01*
G01X1890228Y155152D02*
X1890580Y154800D01*
G01X1890228Y156252D02*
Y155152D01*
G01X1888202Y150402D02*
Y157978D01*
G01X1887536Y149736D02*
X1888202Y150402D01*
G01X1878827Y149736D02*
X1887536D01*
G01X1878009Y150554D02*
X1878827Y149736D01*
G01X1878009Y152756D02*
Y150554D01*
G01X1878096Y152843D02*
X1878009Y152756D01*
G01X1897110Y129674D02*
X1900820Y125964D01*
G01X1869987Y129674D02*
X1897110D01*
G01X1867153Y126840D02*
X1869987Y129674D01*
G01X1867153Y123797D02*
Y126840D01*
G01X1865906Y122550D02*
X1867153Y123797D01*
G01X1864040Y122550D02*
X1865906D01*
G01X1863666Y122924D02*
X1864040Y122550D01*
G01X1860168Y122924D02*
X1863666D01*
G01X1859022Y124070D02*
X1860168Y122924D01*
G01X1859022Y130357D02*
Y124070D01*
G01X1855996Y133383D02*
X1859022Y130357D01*
G01X1855317Y133383D02*
X1855996D01*
G01X1855040Y133660D02*
X1855317Y133383D01*
G01X1855040Y133613D02*
Y133660D01*
G01X1854962Y133613D02*
X1855040D01*
G01X1883800Y155726D02*
X1881324Y153250D01*
G01X1883800Y157800D02*
Y155726D01*
G01X1846253Y103524D02*
X1844440D01*
G01X1850926Y108197D02*
X1846253Y103524D01*
G01X1853317Y108197D02*
X1850926D01*
G01X1866047Y131340D02*
X1898308D01*
G01X1865522Y130815D02*
X1866047Y131340D01*
G01X1861015Y130815D02*
X1865522D01*
G01X1851170Y113600D02*
X1857110D01*
G01X1844770Y107200D02*
X1851170Y113600D01*
G01X1837393Y149527D02*
X1837090Y149830D01*
G01X1852416Y149527D02*
X1837393D01*
G01X1858773Y143170D02*
X1852416Y149527D01*
G01X1863959Y143170D02*
X1858773D01*
G01X1867372Y139757D02*
X1863959Y143170D01*
G01X1867374Y139757D02*
X1867372D01*
G01X1873856Y133275D02*
X1867374Y139757D01*
G01X1896022Y133275D02*
X1873856D01*
G01X1900977Y138230D02*
X1896022Y133275D01*
G01X1858600Y111000D02*
Y106720D01*
G01X1857800Y111800D02*
X1858600Y111000D01*
G01X1851030Y111800D02*
X1857800D01*
G01X1847264Y108034D02*
X1851030Y111800D01*
G01X1847264Y107982D02*
Y108034D01*
G01X1844910Y105628D02*
X1847264Y107982D01*
G01X1842186Y105628D02*
X1844910D01*
G01X1842185Y105629D02*
X1842186Y105628D01*
G01X1841397Y105629D02*
X1842185D01*
G01X1835655Y99887D02*
X1841397Y105629D01*
G01X1866646Y149885D02*
X1859548Y156983D01*
G01X1874323Y149885D02*
X1866646D01*
G01X1878808Y145400D02*
X1874323Y149885D01*
G01X1896284Y145400D02*
X1878808D01*
G01X1898980Y148096D02*
X1896284Y145400D01*
G01X1890834Y95071D02*
X1905513Y109750D01*
G01X1875964Y95071D02*
X1890834D01*
G01X1862811Y108224D02*
X1875964Y95071D01*
G01X1862811Y115555D02*
Y108224D01*
G01X1860238Y118128D02*
X1862811Y115555D01*
G01X1854402Y118128D02*
X1860238D01*
G01X1844095Y128435D02*
X1854402Y118128D01*
G01X1868244Y130344D02*
X1862400Y124500D01*
G01X1869593Y130344D02*
X1868244D01*
G01X1869675Y130426D02*
X1869593Y130344D01*
G01X1897510Y130426D02*
X1869675D01*
G01X1896205Y143974D02*
X1899375Y147144D01*
G01X1893456Y143974D02*
X1896205D01*
G01X1888834Y139352D02*
X1893456Y143974D01*
G01X1884395Y139352D02*
X1888834D01*
G01X1880795Y142952D02*
X1884395Y139352D01*
G01X1876195Y142952D02*
X1880795D01*
G01X1876194Y142953D02*
X1876195Y142952D01*
G01X1875406Y142953D02*
X1876194D01*
G01X1874552Y142099D02*
X1875406Y142953D01*
G01X1871798Y142099D02*
X1874552D01*
G01X1864325Y149572D02*
X1871798Y142099D01*
G01X1859342Y149572D02*
X1864325D01*
G01X1857849Y148079D02*
X1859342Y149572D01*
G01X1850175Y115176D02*
X1843351Y108352D01*
G01X1857844Y115176D02*
X1850175D01*
G01X1859562Y113458D02*
X1857844Y115176D01*
G01X1859562Y107105D02*
Y113458D01*
G01X1857303Y107097D02*
Y106670D01*
G01X1854500Y109900D02*
X1857303Y107097D01*
G01X1850999Y109900D02*
X1854500D01*
G01X1845775Y104676D02*
X1850999Y109900D01*
G01X1841791Y104676D02*
X1845775D01*
G01X1836050Y98935D02*
X1841791Y104676D01*
G01X1854921Y119380D02*
X1844614Y129687D01*
G01X1860871Y119380D02*
X1854921D01*
G01X1864904Y115347D02*
X1860871Y119380D01*
G01X1864904Y114735D02*
Y115347D01*
G01X1895774Y110400D02*
X1890974Y105600D01*
G01X1902763Y110400D02*
X1895774D01*
G01X1853092Y130098D02*
X1854115Y131121D01*
G01X1853092Y126847D02*
Y130098D01*
G01X1857767Y122172D02*
X1853092Y126847D01*
G01X1863007Y122172D02*
X1857767D01*
G01X1863449Y121730D02*
X1863007Y122172D01*
G01X1866365Y121730D02*
X1863449D01*
G01X1868162Y123527D02*
X1866365Y121730D01*
G01X1868162Y126634D02*
Y123527D01*
G01X1870404Y128876D02*
X1868162Y126634D01*
G01X1896779Y128876D02*
X1870404D01*
G01X1900068Y125587D02*
X1896779Y128876D01*
G01X1843835Y196765D02*
X1837403Y203197D01*
G01X1847728Y196765D02*
X1843835D01*
G01X1851417Y200454D02*
X1847728Y196765D01*
G01X1851471Y200454D02*
X1851417D01*
G01X1852693Y201676D02*
X1851471Y200454D01*
G01X1859153Y201676D02*
X1852693D01*
G01X1862072Y198757D02*
X1859153Y201676D01*
G01X1862072Y196107D02*
Y198757D01*
G01X1866771Y191408D02*
X1862072Y196107D01*
G01X1875305Y191408D02*
X1866771D01*
G01X1882824Y183889D02*
X1875305Y191408D01*
G01X1882824Y183047D02*
Y183889D01*
G01X1883747Y182124D02*
X1882824Y183047D01*
G01X1893260Y182124D02*
X1883747D01*
G01X1893368Y182232D02*
X1893260Y182124D01*
G01X1940696Y182232D02*
X1893368D01*
G01X1860500Y166344D02*
Y157378D01*
G01X1856619Y170225D02*
X1860500Y166344D01*
G01X1851972Y170225D02*
X1856619D01*
G01X1849256Y172941D02*
X1851972Y170225D01*
G01X1839387Y172941D02*
X1849256D01*
G01X1836932Y170486D02*
X1839387Y172941D01*
G01X1854247Y174324D02*
X1842675Y185896D01*
G01X1859180Y174324D02*
X1854247D01*
G01X1860356Y175500D02*
X1859180Y174324D01*
G01X1862436Y175500D02*
X1860356D01*
G01X1871736Y184800D02*
X1862436Y175500D01*
G01X1875700Y184800D02*
X1871736D01*
G01X1872357Y203780D02*
X1877880D01*
G01X1870095Y206042D02*
X1872357Y203780D01*
G01X1861035Y206042D02*
X1870095D01*
G01X1858218Y208859D02*
X1861035Y206042D01*
G01X1847349Y208859D02*
X1858218D01*
G01X1843595Y212613D02*
X1847349Y208859D01*
G01X1843595Y215888D02*
Y212613D01*
G01X1838716Y220767D02*
X1843595Y215888D01*
G01X1885800Y186300D02*
X1898218D01*
G01X1884000Y188100D02*
X1885800Y186300D01*
G01X1890628Y156652D02*
X1890228Y156252D01*
G01X1924044Y156652D02*
X1890628D01*
G01X1893624Y158504D02*
X1924005D01*
G01X1893272Y158856D02*
X1893624Y158504D01*
G01X1893272Y160004D02*
Y158856D01*
G01X1893624Y160356D02*
X1893272Y160004D01*
G01X1923360Y160356D02*
X1893624D01*
G01X1892432Y162208D02*
X1923341D01*
G01X1888202Y157978D02*
X1892432Y162208D01*
G01X1891952Y165500D02*
X1930100D01*
G01X1890334Y163882D02*
X1891952Y165500D01*
G01X1882447Y163882D02*
X1890334D01*
G01X1871729Y174600D02*
X1882447Y163882D01*
G01X1868500Y174600D02*
X1871729D01*
G01X1865476Y171576D02*
X1868500Y174600D01*
G01X1861254Y171576D02*
X1865476D01*
G01X1860752Y171074D02*
X1861254Y171576D01*
G01X1852444Y171074D02*
X1860752D01*
G01X1849825Y173693D02*
X1852444Y171074D01*
G01X1837293Y173693D02*
X1849825D01*
G01X1886048Y185348D02*
X1898330D01*
G01X1884400Y183700D02*
X1886048Y185348D01*
G01X1881416Y181484D02*
X1883800Y179100D01*
G01X1881416Y183305D02*
Y181484D01*
G01X1876747Y187974D02*
X1881416Y183305D01*
G01X1862418Y187974D02*
X1876747D01*
G01X1858243Y192149D02*
X1862418Y187974D01*
G01X1852800Y192149D02*
X1858243D01*
G01X1851041Y193908D02*
X1852800Y192149D01*
G01X1841840Y195160D02*
X1840433Y196567D01*
G01X1847187Y195160D02*
X1841840D01*
G01X1851729Y199702D02*
X1847187Y195160D01*
G01X1856559Y199702D02*
X1851729D01*
G01X1863650Y192611D02*
X1856559Y199702D01*
G01X1863650Y189750D02*
Y192611D01*
G01X1884566Y158566D02*
X1883800Y157800D01*
G01X1886571Y158566D02*
X1884566D01*
G01X1891621Y163616D02*
X1886571Y158566D01*
G01X1924406Y163616D02*
X1891621D01*
G01X1893242Y211144D02*
X1898045D01*
G01X1889246Y207148D02*
X1893242Y211144D01*
G01X1880416Y207148D02*
X1889246D01*
G01X1877316Y210248D02*
X1880416Y207148D01*
G01X1867463Y210248D02*
X1877316D01*
G01X1866739Y209524D02*
X1867463Y210248D01*
G01X1860947Y209524D02*
X1866739D01*
G01X1855805Y214666D02*
X1860947Y209524D01*
G01X1848822Y214666D02*
X1855805D01*
G01X1840465Y223023D02*
X1848822Y214666D01*
G01X1881963Y217866D02*
X1879818Y220011D01*
G01X1869125Y201861D02*
X1864637D01*
G01X1873375Y197611D02*
X1869125Y201861D01*
G01X1892618Y197611D02*
X1873375D01*
G01X1893674Y198667D02*
X1892618Y197611D01*
G01X1896023Y198667D02*
X1893674D01*
G01X1898987Y201631D02*
X1896023Y198667D01*
G01X1853735Y175900D02*
X1842607Y187028D01*
G01X1854900Y175900D02*
X1853735D01*
G01X1842975Y162460D02*
X1839873Y159358D01*
G01X1855505Y162460D02*
X1842975D01*
G01X1859548Y158417D02*
X1855505Y162460D01*
G01X1859548Y156983D02*
Y158417D01*
G01X1845100Y216511D02*
X1839340Y222271D01*
G01X1845100Y213236D02*
Y216511D01*
G01X1847289Y211047D02*
X1845100Y213236D01*
G01X1858355Y211047D02*
X1847289D01*
G01X1860630Y208772D02*
X1858355Y211047D01*
G01X1867232Y208772D02*
X1860630D01*
G01X1867956Y209496D02*
X1867232Y208772D01*
G01X1869496Y209496D02*
X1867956D01*
G01X1870419Y208573D02*
X1869496Y209496D01*
G01X1870419Y207352D02*
Y208573D01*
G01X1871747Y206024D02*
X1870419Y207352D01*
G01X1894218Y206024D02*
X1871747D01*
G01X1903116Y214922D02*
X1894218Y206024D01*
G01X1843646Y205604D02*
X1847200Y202050D01*
G01X1848532Y203218D02*
X1845386Y206364D01*
G01X1860382Y203218D02*
X1848532D01*
G01X1864390Y199210D02*
X1860382Y203218D01*
G01X1864390Y198540D02*
Y199210D01*
G01X1864464Y198466D02*
X1864390Y198540D01*
G01X1876602Y213663D02*
X1878789D01*
G01X1874095Y216170D02*
X1876602Y213663D01*
G01X1871890Y216170D02*
X1874095D01*
G01X1870107Y214387D02*
X1871890Y216170D01*
G01X1869609Y214387D02*
X1870107D01*
G01X1867097Y216899D02*
X1869609Y214387D01*
G01X1861563Y216899D02*
X1867097D01*
G01X1860834Y216170D02*
X1861563Y216899D01*
G01X1849446Y216170D02*
X1860834D01*
G01X1846402Y219214D02*
X1849446Y216170D01*
G01X1844347Y216200D02*
X1839028Y221519D01*
G01X1844347Y212925D02*
Y216200D01*
G01X1847068Y210204D02*
X1844347Y212925D01*
G01X1858065Y210204D02*
X1847068D01*
G01X1860617Y207652D02*
X1858065Y210204D01*
G01X1868575Y207652D02*
X1860617D01*
G01X1868843Y207920D02*
X1868575Y207652D01*
G01X1854868Y184667D02*
X1848131Y191404D01*
G01X1881387Y212988D02*
X1883800Y210575D01*
G01X1881387Y214288D02*
Y212988D01*
G01X1880436Y215239D02*
X1881387Y214288D01*
G01X1876160Y215239D02*
X1880436D01*
G01X1873748Y217651D02*
X1876160Y215239D01*
G01X1861251Y217651D02*
X1873748D01*
G01X1860522Y216922D02*
X1861251Y217651D01*
G01X1849758Y216922D02*
X1860522D01*
G01X1847154Y219526D02*
X1849758Y216922D01*
G01X1853781Y180079D02*
X1843708Y190152D01*
G01X1858388Y180079D02*
X1853781D01*
G01X1858686Y180377D02*
X1858388Y180079D01*
G01X1893680Y181480D02*
X1940384D01*
G01X1886761Y174561D02*
X1893680Y181480D01*
G01X1883277Y174561D02*
X1886761D01*
G01X1879700Y178138D02*
X1883277Y174561D01*
G01X1879700Y183029D02*
Y178138D01*
G01X1876163Y186566D02*
X1879700Y183029D01*
G01X1861834Y186566D02*
X1876163D01*
G01X1857657Y190743D02*
X1861834Y186566D01*
G01X1851635Y190743D02*
X1857657D01*
G01X1849722Y192656D02*
X1851635Y190743D01*
G01X1864420Y173920D02*
X1865100Y174600D01*
G01X1860904Y173920D02*
X1864420D01*
G01X1859596Y172612D02*
X1860904Y173920D01*
G01X1853376Y172612D02*
X1859596D01*
G01X1850640Y175348D02*
X1853376Y172612D01*
G01X1835831Y175348D02*
X1850640D01*
G01X1855720Y177580D02*
X1857400Y175900D01*
G01X1853273Y177580D02*
X1855720D01*
G01X1843073Y187780D02*
X1853273Y177580D01*
G01X1861168Y178332D02*
X1862000Y177500D01*
G01X1853898Y178332D02*
X1861168D01*
G01X1843698Y188532D02*
X1853898Y178332D01*
G01X1892101Y169600D02*
X1912536D01*
G01X1887135Y164634D02*
X1892101Y169600D01*
G01X1883454Y164634D02*
X1887135D01*
G01X1872688Y175400D02*
X1883454Y164634D01*
G01X1868200Y175400D02*
X1872688D01*
G01X1865128Y172328D02*
X1868200Y175400D01*
G01X1860942Y172328D02*
X1865128D01*
G01X1860440Y171826D02*
X1860942Y172328D01*
G01X1852970Y171826D02*
X1860440D01*
G01X1850351Y174445D02*
X1852970Y171826D01*
G01X1836395Y174445D02*
X1850351D01*
G01X1884027Y216050D02*
X1886952Y213125D01*
G01X1876413Y216050D02*
X1884027D01*
G01X1874060Y218403D02*
X1876413Y216050D01*
G01X1859852Y217674D02*
X1860581Y218403D01*
G01X1850070Y217674D02*
X1859852D01*
G01X1847906Y219838D02*
X1850070Y217674D01*
G01X1842035Y200466D02*
X1838492Y204009D01*
G01X1849037Y200466D02*
X1842035D01*
G01X1850994Y202423D02*
X1849037Y200466D01*
G01X1852590Y202423D02*
X1850994D01*
G01X1852595Y202428D02*
X1852590Y202423D01*
G01X1859465Y202428D02*
X1852595D01*
G01X1859470Y202423D02*
X1859465Y202428D01*
G01X1859688Y202423D02*
X1859470D01*
G01X1862824Y199287D02*
X1859688Y202423D01*
G01X1862824Y196683D02*
Y199287D01*
G01X1865268Y194239D02*
X1862824Y196683D01*
G01X1891819Y194239D02*
X1865268D01*
G01X1894656Y197076D02*
X1891819Y194239D01*
G01X1897153Y197076D02*
X1894656D01*
G01X1897642Y196587D02*
X1897153Y197076D01*
G01X1841491Y215015D02*
X1837843Y218663D01*
G01X1841491Y211508D02*
Y215015D01*
G01X1848986Y204013D02*
X1841491Y211508D01*
G01X1849269Y204013D02*
X1848986D01*
G01X1849275Y204007D02*
X1849269Y204013D01*
G01X1868734Y204007D02*
X1849275D01*
G01X1871827Y200914D02*
X1868734Y204007D01*
G01X1882438Y200914D02*
X1871827D01*
G01X1883539Y199813D02*
X1882438Y200914D01*
G01X1889760Y170760D02*
X1912632D01*
G01X1887424Y168424D02*
X1889760Y170760D01*
G01X1885476Y168424D02*
X1887424D01*
G01X1875400Y178500D02*
X1885476Y168424D01*
G01X1866500Y178500D02*
X1875400D01*
G01X1862672Y174672D02*
X1866500Y178500D01*
G01X1860592Y174672D02*
X1862672D01*
G01X1859320Y173400D02*
X1860592Y174672D01*
G01X1853844Y173400D02*
X1859320D01*
G01X1851223Y176021D02*
X1853844Y173400D01*
G01X1851031Y176021D02*
X1851223D01*
G01X1850952Y176100D02*
X1851031Y176021D01*
G01X1842443Y215410D02*
X1838238Y219615D01*
G01X1842443Y211903D02*
Y215410D01*
G01X1849587Y204759D02*
X1842443Y211903D01*
G01X1869787Y204759D02*
X1849587D01*
G01X1872680Y201866D02*
X1869787Y204759D01*
G01X1882806Y201866D02*
X1872680D01*
G01X1883350Y202410D02*
X1882806Y201866D01*
G01X1863311Y212728D02*
X1864170Y211869D01*
G01X1862479Y212728D02*
X1863311D01*
G01X1859789Y215418D02*
X1862479Y212728D01*
G01X1849134Y215418D02*
X1859789D01*
G01X1840452Y224100D02*
X1849134Y215418D01*
G01X1890537Y220919D02*
X1910162D01*
G01X1890381Y220763D02*
X1890537Y220919D01*
G01X1860937Y220763D02*
X1890381D01*
G01X1848600Y233100D02*
X1860937Y220763D01*
G01X1848600Y242700D02*
Y233100D01*
G01X1843700Y247600D02*
X1848600Y242700D01*
G01X1886978Y238919D02*
X1865625Y260272D01*
G01X1906620Y238919D02*
X1886978D01*
G01X1844200Y248700D02*
X1838519D01*
G01X1848700Y244200D02*
X1844200Y248700D01*
G01X1859500Y244200D02*
X1848700D01*
G01X1862630Y247330D02*
X1859500Y244200D01*
G01X1870037Y247330D02*
X1862630D01*
G01X1878992Y238375D02*
X1870037Y247330D01*
G01X1878992Y235190D02*
Y238375D01*
G01X1882345Y231837D02*
X1878992Y235190D01*
G01X1887345Y239699D02*
X1866020Y261024D01*
G01X1906904Y239699D02*
X1887345D01*
G01X1891292Y236062D02*
X1892274Y235080D01*
G01X1885794Y236062D02*
X1891292D01*
G01X1871204Y250652D02*
X1885794Y236062D01*
G01X1860705Y250652D02*
X1871204D01*
G01X1857205Y247152D02*
X1860705Y250652D01*
G01X1850095Y247152D02*
X1857205D01*
G01X1845495Y251752D02*
X1850095Y247152D01*
G01X1840195Y251752D02*
X1845495D01*
G01X1847387Y240487D02*
X1843449Y244425D01*
G01X1847387Y233113D02*
Y240487D01*
G01X1860489Y220011D02*
X1847387Y233113D01*
G01X1879818Y220011D02*
X1860489D01*
G01X1884340Y217866D02*
X1881963D01*
G01X1886500Y237767D02*
X1865147Y259120D01*
G01X1897084Y237767D02*
X1886500D01*
G01X1899816Y235035D02*
X1897084Y237767D01*
G01X1884651Y235454D02*
Y234975D01*
G01X1870405Y249700D02*
X1884651Y235454D01*
G01X1861100Y249700D02*
X1870405D01*
G01X1857600Y246200D02*
X1861100Y249700D01*
G01X1849700Y246200D02*
X1857600D01*
G01X1845100Y250800D02*
X1849700Y246200D01*
G01X1839800Y250800D02*
X1845100D01*
G01X1846402Y225279D02*
Y219214D01*
G01X1844880Y226801D02*
X1846402Y225279D01*
G01X1839052Y226801D02*
X1844880D01*
G01X1839051Y226800D02*
X1839052Y226801D01*
G01X1838429Y226800D02*
X1839051D01*
G01X1838428Y226799D02*
X1838429Y226800D01*
G01X1837806Y226799D02*
X1838428D01*
G01X1837804Y226801D02*
X1837806Y226799D01*
G01X1887548Y240660D02*
X1907007D01*
G01X1866432Y261776D02*
X1887548Y240660D01*
G01X1847154Y225591D02*
Y219526D01*
G01X1847005Y225740D02*
X1847154Y225591D01*
G01X1847005Y225741D02*
Y225740D01*
G01X1845193Y227553D02*
X1847005Y225741D01*
G01X1887860Y241412D02*
X1907888D01*
G01X1866744Y262528D02*
X1887860Y241412D01*
G01X1876350Y219155D02*
X1877517Y217988D01*
G01X1859715Y219155D02*
X1876350D01*
G01X1848470Y230400D02*
X1859715Y219155D01*
G01X1889034Y244469D02*
X1909295D01*
G01X1868319Y265184D02*
X1889034Y244469D01*
G01X1886105Y236815D02*
X1864752Y258168D01*
G01X1894794Y236815D02*
X1886105D01*
G01X1896529Y235080D02*
X1894794Y236815D01*
G01X1860581Y218403D02*
X1874060D01*
G01X1847906Y225904D02*
Y219838D01*
G01X1845505Y228305D02*
X1847906Y225904D01*
G01X1844364Y249600D02*
X1838683D01*
G01X1849012Y244952D02*
X1844364Y249600D01*
G01X1859188Y244952D02*
X1849012D01*
G01X1862318Y248082D02*
X1859188Y244952D01*
G01X1870349Y248082D02*
X1862318D01*
G01X1879829Y238602D02*
X1870349Y248082D01*
G01X1879829Y235593D02*
Y238602D01*
G01X1881362Y234060D02*
X1879829Y235593D01*
G01X1881860Y234060D02*
X1881362D01*
G01X1882200Y234400D02*
X1881860Y234060D01*
G01X1888314Y242486D02*
X1908313D01*
G01X1867320Y263480D02*
X1888314Y242486D01*
G01X1888639Y243517D02*
X1867724Y264432D01*
G01X1909183Y243517D02*
X1888639D01*
G01X1849182Y226046D02*
X1845828Y229400D01*
G01X1849182Y220791D02*
Y226046D01*
G01X1850723Y219250D02*
X1849182Y220791D01*
G01X1837737Y456696D02*
X1836317Y455276D01*
G01X1878481Y456696D02*
X1837737D01*
G01X1889484Y467699D02*
X1878481Y456696D01*
G01X1847052Y461960D02*
X1835553D01*
G01X1848833Y463741D02*
X1847052Y461960D01*
G01X1872730Y463741D02*
X1848833D01*
G01X1879561Y470572D02*
X1872730Y463741D01*
G01X1876524Y448063D02*
X1872425Y443964D01*
G01X1876524Y451395D02*
Y448063D01*
G01X1891388Y466259D02*
X1876524Y451395D01*
G01X1837113Y458200D02*
X1835693Y456780D01*
G01X1848612Y458200D02*
X1837113D01*
G01X1850393Y459981D02*
X1848612Y458200D01*
G01X1879638Y459981D02*
X1850393D01*
G01X1887791Y468134D02*
X1879638Y459981D01*
G01X1878702Y462237D02*
X1882861Y466396D01*
G01X1849457Y462237D02*
X1878702D01*
G01X1847676Y460456D02*
X1849457Y462237D01*
G01X1836177Y460456D02*
X1847676D01*
G01X1851247Y469211D02*
X1846671Y464635D01*
G01X1838049Y455944D02*
X1836629Y454524D01*
G01X1878793Y455944D02*
X1838049D01*
G01X1890236Y467387D02*
X1878793Y455944D01*
G01X1874289Y462989D02*
X1881103Y469803D01*
G01X1849145Y462989D02*
X1874289D01*
G01X1847364Y461208D02*
X1849145Y462989D01*
G01X1835865Y461208D02*
X1847364D01*
G01X1845870Y449892D02*
X1842102Y446124D01*
G01X1848797Y449892D02*
X1845870D01*
G01X1853484Y454579D02*
X1848797Y449892D01*
G01X1866423Y454579D02*
X1853484D01*
G01X1868015Y452987D02*
X1866423Y454579D01*
G01X1848300Y458952D02*
X1836801D01*
G01X1850081Y460733D02*
X1848300Y458952D01*
G01X1879326Y460733D02*
X1850081D01*
G01X1887039Y468446D02*
X1879326Y460733D01*
G01X1874696Y447299D02*
X1872113Y444716D01*
G01X1874696Y452396D02*
Y447299D01*
G01X1875900Y453600D02*
X1874696Y452396D01*
G01X1879950Y459229D02*
X1888732Y468011D01*
G01X1850705Y459229D02*
X1879950D01*
G01X1848924Y457448D02*
X1850705Y459229D01*
G01X1837425Y457448D02*
X1848924D01*
G01X1836005Y456028D02*
X1837425Y457448D01*
G01X1847988Y459704D02*
X1836489D01*
G01X1849769Y461485D02*
X1847988Y459704D01*
G01X1879014Y461485D02*
X1849769D01*
G01X1883613Y466084D02*
X1879014Y461485D01*
G01X1847339Y463311D02*
X1849229Y465201D01*
G01X1874277Y510019D02*
Y540943D01*
G01X1877976Y506320D02*
X1874277Y510019D01*
G01X1877976Y499611D02*
Y506320D01*
G01X1875695Y497330D02*
X1877976Y499611D01*
G01X1869966Y497330D02*
X1875695D01*
G01X1852195Y479559D02*
X1869966Y497330D01*
G01X1889484Y472907D02*
Y467699D01*
G01X1909350Y492773D02*
X1889484Y472907D01*
G01X1851942Y481292D02*
X1839376D01*
G01X1871550Y500900D02*
X1851942Y481292D01*
G01X1873610Y500900D02*
X1871550D01*
G01X1873610Y500904D02*
Y500900D01*
G01X1873632Y500904D02*
X1873610D01*
G01X1841300Y517900D02*
Y525100D01*
G01X1842400Y516800D02*
X1841300Y517900D01*
G01X1879561Y475907D02*
Y470572D01*
G01X1888000Y484346D02*
X1879561Y475907D01*
G01X1888000Y501201D02*
Y484346D01*
G01X1894299Y507500D02*
X1888000Y501201D01*
G01X1913900Y507500D02*
X1894299D01*
G01X1891388Y472117D02*
Y466259D01*
G01X1896471Y477200D02*
X1891388Y472117D01*
G01X1900890Y477200D02*
X1896471D01*
G01X1841900Y498800D02*
X1838824Y495724D01*
G01X1887791Y474513D02*
Y468134D01*
G01X1899772Y486494D02*
X1887791Y474513D01*
G01X1894052Y503552D02*
X1912351D01*
G01X1890000Y499500D02*
X1894052Y503552D01*
G01X1890000Y483764D02*
Y499500D01*
G01X1882861Y476625D02*
X1890000Y483764D01*
G01X1882861Y466396D02*
Y476625D01*
G01X1864411Y469211D02*
X1851247D01*
G01X1878500Y483300D02*
X1864411Y469211D01*
G01X1878500Y494307D02*
Y483300D01*
G01X1896993Y512800D02*
X1878500Y494307D01*
G01X1912300Y512800D02*
X1896993D01*
G01X1890236Y472029D02*
Y467387D01*
G01X1910250Y492043D02*
X1890236Y472029D01*
G01X1875946Y514560D02*
Y526903D01*
G01X1878728Y511778D02*
X1875946Y514560D01*
G01X1878728Y499299D02*
Y511778D01*
G01X1875732Y496303D02*
X1878728Y499299D01*
G01X1871856Y496303D02*
X1875732D01*
G01X1853422Y477869D02*
X1871856Y496303D01*
G01X1835879Y477869D02*
X1853422D01*
G01X1895000Y506500D02*
X1914100D01*
G01X1889000Y500500D02*
X1895000Y506500D01*
G01X1889000Y483828D02*
Y500500D01*
G01X1881103Y475931D02*
X1889000Y483828D01*
G01X1881103Y469803D02*
Y475931D01*
G01X1887039Y474825D02*
Y468446D01*
G01X1899000Y486786D02*
X1887039Y474825D01*
G01X1881677Y523676D02*
X1887566Y529565D01*
G01X1881677Y499075D02*
Y523676D01*
G01X1877400Y494798D02*
X1881677Y499075D01*
G01X1877400Y483700D02*
Y494798D01*
G01X1871800Y478100D02*
X1877400Y483700D01*
G01X1858900Y478100D02*
X1871800D01*
G01X1851500Y470700D02*
X1858900Y478100D01*
G01X1860272Y481102D02*
X1853022Y473852D01*
G01X1860272Y481131D02*
Y481102D01*
G01X1861869Y482728D02*
X1860272Y481131D01*
G01X1861898Y482728D02*
X1861869D01*
G01X1874091Y494921D02*
X1861898Y482728D01*
G01X1876024Y494921D02*
X1874091D01*
G01X1880887Y499784D02*
X1876024Y494921D01*
G01X1880887Y532910D02*
Y499784D01*
G01X1856220Y525740D02*
X1845000Y536960D01*
G01X1856220Y487574D02*
Y525740D01*
G01X1851720Y483074D02*
X1856220Y487574D01*
G01X1839236Y483074D02*
X1851720D01*
G01X1888732Y474390D02*
X1900524Y486182D01*
G01X1888732Y468011D02*
Y474390D01*
G01X1883613Y476313D02*
Y466084D01*
G01X1898000Y490700D02*
X1883613Y476313D01*
G01X1893940Y508400D02*
X1913099D01*
G01X1887000Y501460D02*
X1893940Y508400D01*
G01X1887000Y501451D02*
Y501460D01*
G01X1879600Y494051D02*
X1887000Y501451D01*
G01X1879600Y478300D02*
Y494051D01*
G01X1877500Y476200D02*
X1879600Y478300D01*
G01X1872929Y476200D02*
X1877500D01*
G01X1861930Y465201D02*
X1872929Y476200D01*
G01X1849229Y465201D02*
X1861930D01*
G01X1874277Y540943D02*
X1873510Y541710D01*
G01X1883517Y566767D02*
X1882300Y565550D01*
G01X1888832Y566767D02*
X1883517D01*
G01X1908525Y586460D02*
X1888832Y566767D01*
G01X1873350Y580640D02*
X1880870Y588160D01*
G01X1846260Y580640D02*
X1873350D01*
G01X1840220Y586680D02*
X1846260Y580640D01*
G01X1840220Y593970D02*
Y586680D01*
G01X1888645Y569772D02*
X1907122Y588249D01*
G01X1873426Y569772D02*
X1888645D01*
G01X1861428Y557774D02*
X1873426Y569772D01*
G01X1860962Y557774D02*
X1861428D01*
G01X1858212Y555024D02*
X1860962Y557774D01*
G01X1858085Y555024D02*
X1858212D01*
G01X1858073Y555036D02*
X1858085Y555024D01*
G01X1856900Y555036D02*
X1858073D01*
G01X1854284Y557652D02*
X1856900Y555036D01*
G01X1854278Y557652D02*
X1854284D01*
G01X1854156Y557774D02*
X1854278Y557652D01*
G01X1850196Y557774D02*
X1854156D01*
G01X1849204Y558766D02*
X1850196Y557774D01*
G01X1846947Y548200D02*
X1840719Y541972D01*
G01X1848900Y548200D02*
X1846947D01*
G01X1853881Y537610D02*
X1847070D01*
G01X1867671Y551400D02*
X1853881Y537610D01*
G01X1891700Y551400D02*
X1867671D01*
G01X1894300Y548800D02*
X1891700Y551400D01*
G01X1897300Y548800D02*
X1894300D01*
G01X1840324Y542924D02*
X1848800Y551400D01*
G01X1892500Y538900D02*
X1898850Y545250D01*
G01X1882270Y538900D02*
X1892500D01*
G01X1875946Y532576D02*
X1882270Y538900D01*
G01X1875946Y528217D02*
Y532576D01*
G01X1875942Y528213D02*
X1875946Y528217D01*
G01X1875942Y526907D02*
Y528213D01*
G01X1875946Y526903D02*
X1875942Y526907D01*
G01X1888957Y569020D02*
X1908071Y588134D01*
G01X1874569Y569020D02*
X1888957D01*
G01X1867450Y561901D02*
X1874569Y569020D01*
G01X1867450Y559450D02*
Y561901D01*
G01X1869800Y557100D02*
X1867450Y559450D01*
G01X1869600Y556900D02*
X1869800Y557100D01*
G01X1861152Y556900D02*
X1869600D01*
G01X1858524Y554272D02*
X1861152Y556900D01*
G01X1857773Y554272D02*
X1858524D01*
G01X1857761Y554284D02*
X1857773Y554272D01*
G01X1856588Y554284D02*
X1857761D01*
G01X1853972Y556900D02*
X1856588Y554284D01*
G01X1844438Y556900D02*
X1853972D01*
G01X1842400Y554862D02*
X1844438Y556900D01*
G01X1892903Y535444D02*
X1907416Y549957D01*
G01X1892903Y531308D02*
Y535444D01*
G01X1891160Y529565D02*
X1892903Y531308D01*
G01X1887566Y529565D02*
X1891160D01*
G01X1885177Y537200D02*
X1880887Y532910D01*
G01X1893029Y537200D02*
X1885177D01*
G01X1901500Y545671D02*
X1893029Y537200D01*
G01X1895618Y561300D02*
X1901500Y555418D01*
G01X1880821Y561300D02*
X1895618D01*
G01X1877299Y564822D02*
X1880821Y561300D01*
G01X1877299Y565751D02*
Y564822D01*
G01X1875850Y567200D02*
X1877299Y565751D01*
G01X1852400Y550900D02*
Y554900D01*
G01X1854000Y549300D02*
X1852400Y550900D01*
G01X1854000Y546900D02*
Y549300D01*
G01X1845000Y537900D02*
X1854000Y546900D01*
G01X1845000Y536960D02*
Y537900D01*
G01X1880626Y563724D02*
X1878875Y565475D01*
G01X1894838Y563724D02*
X1880626D01*
G01X1905169Y553393D02*
X1894838Y563724D01*
G01X1842953Y566053D02*
X1840700Y563800D01*
G01X1849932Y566053D02*
X1842953D01*
G01X1850037Y565948D02*
X1849932Y566053D01*
G01X1852463Y565948D02*
X1850037D01*
G01X1852568Y566053D02*
X1852463Y565948D01*
G01X1862325Y566053D02*
X1852568D01*
G01X1867022Y570750D02*
X1862325Y566053D01*
G01X1888276Y570750D02*
X1867022D01*
G01X1906170Y588644D02*
X1888276Y570750D01*
G01X1895690Y588160D02*
X1914650Y607120D01*
G01X1880870Y588160D02*
X1895690D01*
G01X1939527Y95736D02*
X1912037Y68246D01*
G01X1901883Y72566D02*
X1900989Y73460D01*
G01X1910797Y72566D02*
X1901883D01*
G01X1928612Y90381D02*
X1910797Y72566D01*
G01X1928612Y101828D02*
Y90381D01*
G01X1921700Y92613D02*
X1918210Y96103D01*
G01X1921700Y89000D02*
Y92613D01*
G01X1920200Y87500D02*
X1921700Y89000D01*
G01X1915900Y87500D02*
X1920200D01*
G01X1913438Y89962D02*
X1915900Y87500D01*
G01X1913438Y97315D02*
Y89962D01*
G01X1930991Y90066D02*
Y101513D01*
G01X1911075Y70150D02*
X1930991Y90066D01*
G01X1927860Y90693D02*
Y101516D01*
G01X1910485Y73318D02*
X1927860Y90693D01*
G01X1902195Y73318D02*
X1910485D01*
G01X1899863Y75650D02*
X1902195Y73318D01*
G01X1930039Y90461D02*
X1910978Y71400D01*
G01X1930039Y101908D02*
Y90461D01*
G01X1914589Y90911D02*
Y97511D01*
G01X1916200Y89300D02*
X1914589Y90911D01*
G01X1918352Y89300D02*
X1916200D01*
G01X1922709Y93709D02*
X1923300Y94300D01*
G01X1922709Y88309D02*
Y93709D01*
G01X1920900Y86500D02*
X1922709Y88309D01*
G01X1915301Y86500D02*
X1920900D01*
G01X1912486Y89315D02*
X1915301Y86500D01*
G01X1912486Y96920D02*
Y89315D01*
G01X1925636Y89816D02*
Y117001D01*
G01X1910090Y74270D02*
X1925636Y89816D01*
G01X1902590Y74270D02*
X1910090D01*
G01X1899634Y77226D02*
X1902590Y74270D01*
G01X1913849Y65189D02*
X1901871D01*
G01X1918602Y69942D02*
X1913849Y65189D01*
G01X1922380Y69942D02*
X1918602D01*
G01X1927298Y65024D02*
X1922380Y69942D01*
G01X1943908Y65024D02*
X1927298D01*
G01X1948826Y69942D02*
X1943908Y65024D01*
G01X1970629Y69942D02*
X1948826D01*
G01X1911470Y69198D02*
X1937728Y95456D01*
G01X1940279Y95424D02*
X1912349Y67494D01*
G01X1913143Y66342D02*
X1901394D01*
G01X1917943Y71142D02*
X1913143Y66342D01*
G01X1923397Y71142D02*
X1917943D01*
G01X1928187Y66352D02*
X1923397Y71142D01*
G01X1943606Y66352D02*
X1928187D01*
G01X1948348Y71094D02*
X1943606Y66352D01*
G01X1969069Y71094D02*
X1948348D01*
G01X1947484Y154584D02*
Y177092D01*
G01X1944600Y151700D02*
X1947484Y154584D01*
G01X1912642Y111442D02*
X1914500Y113300D01*
G01X1905858Y111442D02*
X1912642D01*
G01X1903566Y109150D02*
X1905858Y111442D01*
G01X1897651Y109150D02*
X1903566D01*
G01X1899935Y140150D02*
X1897488Y137703D01*
G01X1900935Y140150D02*
X1899935D01*
G01X1901511Y140726D02*
X1900935Y140150D01*
G01X1901511Y142990D02*
Y140726D01*
G01X1903155Y144634D02*
X1901511Y142990D01*
G01X1912520Y144634D02*
X1903155D01*
G01X1914267Y142887D02*
X1912520Y144634D01*
G01X1914267Y142383D02*
Y142887D01*
G01X1919195Y137455D02*
X1914267Y142383D01*
G01X1919195Y134396D02*
Y137455D01*
G01X1925703Y154800D02*
X1926952Y156049D01*
G01X1939527Y111242D02*
Y95736D01*
G01X1938448Y112321D02*
X1939527Y111242D01*
G01X1938448Y127252D02*
Y112321D01*
G01X1945500Y134304D02*
X1938448Y127252D01*
G01X1945500Y141408D02*
Y134304D01*
G01X1940768Y146140D02*
X1945500Y141408D01*
G01X1940768Y154832D02*
Y146140D01*
G01X1930100Y165500D02*
X1940768Y154832D01*
G01X1929737Y128337D02*
X1929736D01*
G01X1929737Y128355D02*
Y128337D01*
G01X1927756Y128355D02*
X1929737D01*
G01X1919937Y120536D02*
X1927756Y128355D01*
G01X1902778Y120536D02*
X1919937D01*
G01X1900820Y122494D02*
X1902778Y120536D01*
G01X1900820Y125964D02*
Y122494D01*
G01X1939816Y153913D02*
X1933229Y160500D01*
G01X1939816Y145261D02*
Y153913D01*
G01X1940700Y144377D02*
X1939816Y145261D01*
G01X1940700Y136300D02*
Y144377D01*
G01X1935592Y108808D02*
X1928612Y101828D01*
G01X1935592Y120547D02*
Y108808D01*
G01X1932968Y123171D02*
X1935592Y120547D01*
G01X1932968Y132118D02*
Y123171D01*
G01X1930700Y134386D02*
X1932968Y132118D01*
G01X1924711Y134386D02*
X1930700D01*
G01X1921674Y131349D02*
X1924711Y134386D01*
G01X1921674Y131185D02*
Y131349D01*
G01X1921669Y131180D02*
X1921674Y131185D01*
G01X1921669Y125236D02*
Y131180D01*
G01X1920625Y124192D02*
X1921669Y125236D01*
G01X1918226Y124192D02*
X1920625D01*
G01X1914876Y127542D02*
X1918226Y124192D01*
G01X1914876Y136893D02*
Y127542D01*
G01X1913096Y138673D02*
X1914876Y136893D01*
G01X1908618Y138673D02*
X1913096D01*
G01X1906271Y136326D02*
X1908618Y138673D01*
G01X1901601Y136326D02*
X1906271D01*
G01X1900534Y135259D02*
X1901601Y136326D01*
G01X1900534Y133566D02*
Y135259D01*
G01X1898308Y131340D02*
X1900534Y133566D01*
G01X1905481Y138230D02*
X1900977D01*
G01X1907828Y140577D02*
X1905481Y138230D01*
G01X1913096Y140577D02*
X1907828D01*
G01X1913097Y140578D02*
X1913096Y140577D01*
G01X1913885Y140578D02*
X1913097D01*
G01X1916780Y137683D02*
X1913885Y140578D01*
G01X1916780Y132820D02*
Y137683D01*
G01X1917899Y131701D02*
X1916780Y132820D01*
G01X1919514Y131701D02*
X1917899D01*
G01X1911493Y99260D02*
X1913438Y97315D01*
G01X1901176Y99260D02*
X1911493D01*
G01X1901076Y148096D02*
X1898980D01*
G01X1902224Y146948D02*
X1901076Y148096D01*
G01X1911085Y146948D02*
X1902224D01*
G01X1911086Y146949D02*
X1911085Y146948D01*
G01X1911874Y146949D02*
X1911086D01*
G01X1911875Y146948D02*
X1911874Y146949D01*
G01X1912900Y146948D02*
X1911875D01*
G01X1916172Y143676D02*
X1912900Y146948D01*
G01X1916172Y143172D02*
Y143676D01*
G01X1920738Y138606D02*
X1916172Y143172D01*
G01X1933169Y138606D02*
X1920738D01*
G01X1936300Y135475D02*
X1933169Y138606D01*
G01X1936300Y122533D02*
Y135475D01*
G01X1937496Y121337D02*
X1936300Y122533D01*
G01X1937496Y108018D02*
Y121337D01*
G01X1930991Y101513D02*
X1937496Y108018D01*
G01X1955198Y142439D02*
Y175202D01*
G01X1962167Y135470D02*
X1955198Y142439D01*
G01X1954665Y104425D02*
X1963434Y113194D01*
G01X1954665Y101632D02*
Y104425D01*
G01X1954313Y101280D02*
X1954665Y101632D01*
G01X1946760Y101280D02*
X1954313D01*
G01X1943660Y98180D02*
X1946760Y101280D01*
G01X1918002Y102162D02*
Y98902D01*
G01X1910414Y109750D02*
X1918002Y102162D01*
G01X1905513Y109750D02*
X1910414D01*
G01X1901572Y126364D02*
X1897510Y130426D01*
G01X1901572Y122806D02*
Y126364D01*
G01X1902977Y121401D02*
X1901572Y122806D01*
G01X1919738Y121401D02*
X1902977D01*
G01X1922426Y124089D02*
X1919738Y121401D01*
G01X1922426Y131037D02*
Y124089D01*
G01X1924947Y133558D02*
X1922426Y131037D01*
G01X1930464Y133558D02*
X1924947D01*
G01X1932216Y131806D02*
X1930464Y133558D01*
G01X1932216Y122859D02*
Y131806D01*
G01X1934840Y120235D02*
X1932216Y122859D01*
G01X1934840Y109156D02*
Y120235D01*
G01X1927860Y102176D02*
X1934840Y109156D01*
G01X1927860Y102140D02*
Y102176D01*
G01X1927859Y102139D02*
X1927860Y102140D01*
G01X1927859Y101517D02*
Y102139D01*
G01X1927860Y101516D02*
X1927859Y101517D01*
G01X1934544Y135487D02*
Y127957D01*
G01X1932377Y137654D02*
X1934544Y135487D01*
G01X1920343Y137654D02*
X1932377D01*
G01X1915220Y142777D02*
X1920343Y137654D01*
G01X1915220Y143281D02*
Y142777D01*
G01X1912505Y145996D02*
X1915220Y143281D01*
G01X1901829Y145996D02*
X1912505D01*
G01X1900681Y147144D02*
X1901829Y145996D01*
G01X1899375Y147144D02*
X1900681D01*
G01X1936544Y108413D02*
X1930039Y101908D01*
G01X1936544Y120942D02*
Y108413D01*
G01X1934544Y122942D02*
X1936544Y120942D01*
G01X1934544Y127957D02*
Y122942D01*
G01X1909364Y102736D02*
X1903305D01*
G01X1914589Y97511D02*
X1909364Y102736D01*
G01X1911098Y98308D02*
X1912486Y96920D01*
G01X1901571Y98308D02*
X1911098D01*
G01X1905821Y113458D02*
X1902763Y110400D01*
G01X1908391Y113458D02*
X1905821D01*
G01X1913560Y118627D02*
X1908391Y113458D01*
G01X1921179Y118627D02*
X1913560D01*
G01X1926096Y123544D02*
X1921179Y118627D01*
G01X1927810Y123544D02*
X1926096D01*
G01X1943024Y150769D02*
X1944609Y149184D01*
G01X1943024Y152353D02*
Y150769D01*
G01X1946732Y156061D02*
X1943024Y152353D01*
G01X1946732Y176780D02*
Y156061D01*
G01X1947613Y152188D02*
X1944609Y149184D01*
G01X1947613Y153259D02*
Y152188D01*
G01X1948236Y153882D02*
X1947613Y153259D01*
G01X1948236Y177404D02*
Y153882D01*
G01X1956350Y143261D02*
Y176250D01*
G01X1962529Y137082D02*
X1956350Y143261D01*
G01X1955817Y103947D02*
X1963912Y112042D01*
G01X1955817Y101154D02*
Y103947D01*
G01X1954791Y100128D02*
X1955817Y101154D01*
G01X1948748Y100128D02*
X1954791D01*
G01X1946770Y98150D02*
X1948748Y100128D01*
G01X1925636Y117001D02*
X1923837Y118800D01*
G01X1937728Y95456D02*
Y99441D01*
G01X1940279Y110930D02*
Y95424D01*
G01X1940280Y110931D02*
X1940279Y110930D01*
G01X1940280Y111553D02*
Y110931D01*
G01X1940279Y111554D02*
X1940280Y111553D01*
G01X1940279Y111820D02*
Y111554D01*
G01X1939200Y112899D02*
X1940279Y111820D01*
G01X1939200Y126731D02*
Y112899D01*
G01X1949338Y136869D02*
X1939200Y126731D01*
G01X1949338Y139241D02*
Y136869D01*
G01X1948606Y139973D02*
X1949338Y139241D01*
G01X1948606Y143223D02*
Y139973D01*
G01X1946149Y145680D02*
X1948606Y143223D01*
G01X1944820Y145680D02*
X1946149D01*
G01X1941520Y148980D02*
X1944820Y145680D01*
G01X1941520Y152977D02*
Y148980D01*
G01X1942223Y153680D02*
X1941520Y152977D01*
G01X1942223Y173413D02*
Y153680D01*
G01X1900068Y122990D02*
Y125587D01*
G01X1900067Y122989D02*
X1900068Y122990D01*
G01X1900067Y122183D02*
Y122989D01*
G01X1902670Y119580D02*
X1900067Y122183D01*
G01X1920681Y119580D02*
X1902670D01*
G01X1927257Y126156D02*
X1920681Y119580D01*
G01X1927918Y126156D02*
X1927257D01*
G01X1952726Y104396D02*
Y102950D01*
G01X1949413Y107709D02*
X1952726Y104396D01*
G01X1946091Y107709D02*
X1949413D01*
G01X1939952Y113848D02*
X1946091Y107709D01*
G01X1939952Y125989D02*
Y113848D01*
G01X1950245Y136282D02*
X1939952Y125989D01*
G01X1950245Y139426D02*
Y136282D01*
G01X1949358Y140313D02*
X1950245Y139426D01*
G01X1949358Y143718D02*
Y140313D01*
G01X1946644Y146432D02*
X1949358Y143718D01*
G01X1946461Y146432D02*
X1946644D01*
G01X1946460Y146433D02*
X1946461Y146432D01*
G01X1945838Y146433D02*
X1946460D01*
G01X1945837Y146432D02*
X1945838Y146433D01*
G01X1945132Y146432D02*
X1945837D01*
G01X1942272Y149292D02*
X1945132Y146432D01*
G01X1942272Y152665D02*
Y149292D01*
G01X1943400Y153793D02*
X1942272Y152665D01*
G01X1943400Y174000D02*
Y153793D01*
G01X1958500Y143109D02*
X1963131Y138478D01*
G01X1958500Y181870D02*
Y143109D01*
G01X1943950Y178978D02*
X1940696Y182232D01*
G01X1945598Y178978D02*
X1943950D01*
G01X1947484Y177092D02*
X1945598Y178978D01*
G01X1932794Y212745D02*
X1906620Y238919D01*
G01X1932794Y208041D02*
Y212745D01*
G01X1929370Y204617D02*
X1932794Y208041D01*
G01X1916013Y204617D02*
X1929370D01*
G01X1914166Y202770D02*
X1916013Y204617D01*
G01X1914166Y202248D02*
Y202770D01*
G01X1898218Y186300D02*
X1914166Y202248D01*
G01X1924396Y157004D02*
X1924044Y156652D01*
G01X1924396Y158113D02*
Y157004D01*
G01X1924005Y158504D02*
X1924396Y158113D01*
G01X1923712Y160708D02*
X1923360Y160356D01*
G01X1923712Y161837D02*
Y160708D01*
G01X1923341Y162208D02*
X1923712Y161837D01*
G01X1933746Y212857D02*
X1906904Y239699D01*
G01X1933746Y207699D02*
Y212857D01*
G01X1929312Y203265D02*
X1933746Y207699D01*
G01X1916165Y203265D02*
X1929312D01*
G01X1914918Y202018D02*
X1916165Y203265D01*
G01X1914918Y201936D02*
Y202018D01*
G01X1898330Y185348D02*
X1914918Y201936D01*
G01X1927522Y160500D02*
X1924406Y163616D01*
G01X1933229Y160500D02*
X1927522D01*
G01X1913969Y215674D02*
X1918143Y219848D01*
G01X1902575Y215674D02*
X1913969D01*
G01X1898045Y211144D02*
X1902575Y215674D01*
G01X1898987Y208476D02*
Y201631D01*
G01X1904029Y213518D02*
X1898987Y208476D01*
G01X1917484Y213518D02*
X1904029D01*
G01X1918489Y212513D02*
X1917484Y213518D01*
G01X1955198Y175202D02*
X1948800Y181600D01*
G01X1944353D02*
X1948800D01*
G01X1934100Y191853D02*
X1944353Y181600D01*
G01X1934100Y193400D02*
Y191853D01*
G01X1920440Y214922D02*
X1903116D01*
G01X1924908Y210454D02*
X1920440Y214922D01*
G01X1929510Y210454D02*
X1924908D01*
G01X1930500Y209464D02*
X1929510Y210454D01*
G01X1918653Y202300D02*
X1917568Y201215D01*
G01X1930300Y202300D02*
X1918653D01*
G01X1934562Y206562D02*
X1930300Y202300D01*
G01X1934562Y213105D02*
Y206562D01*
G01X1907007Y240660D02*
X1934562Y213105D01*
G01X1945286Y178226D02*
X1946732Y176780D01*
G01X1943638Y178226D02*
X1945286D01*
G01X1940384Y181480D02*
X1943638Y178226D01*
G01X1945910Y179730D02*
X1948236Y177404D01*
G01X1944541Y179730D02*
X1945910D01*
G01X1932000Y192271D02*
X1944541Y179730D01*
G01X1932000Y196107D02*
Y192271D01*
G01X1929907Y198200D02*
X1932000Y196107D01*
G01X1929907Y200843D02*
Y198200D01*
G01X1935474Y206410D02*
X1929907Y200843D01*
G01X1935474Y217360D02*
Y206410D01*
G01X1931434Y221400D02*
X1935474Y217360D01*
G01X1956350Y176250D02*
X1944800Y187800D01*
G01X1937424Y196424D02*
X1939400Y198400D01*
G01X1937424Y191876D02*
Y196424D01*
G01X1941500Y187800D02*
X1937424Y191876D01*
G01X1944800Y187800D02*
X1941500D01*
G01X1953354Y202600D02*
X1961472Y194482D01*
G01X1950100Y202600D02*
X1953354D01*
G01X1946500Y206200D02*
X1950100Y202600D01*
G01X1946500Y225347D02*
Y206200D01*
G01X1941000Y174636D02*
X1942223Y173413D01*
G01X1941000Y177829D02*
Y174636D01*
G01X1938857Y179972D02*
X1941000Y177829D01*
G01X1922908Y179972D02*
X1938857D01*
G01X1912536Y169600D02*
X1922908Y179972D01*
G01X1906344Y196587D02*
X1897642D01*
G01X1915676Y205919D02*
X1906344Y196587D01*
G01X1925419Y205919D02*
X1915676D01*
G01X1927064Y207564D02*
X1925419Y205919D01*
G01X1943500Y211515D02*
Y209500D01*
G01X1932663Y222352D02*
X1943500Y211515D01*
G01X1942300Y175100D02*
X1943400Y174000D01*
G01X1942300Y178500D02*
Y175100D01*
G01X1940072Y180728D02*
X1942300Y178500D01*
G01X1922600Y180728D02*
X1940072D01*
G01X1912632Y170760D02*
X1922600Y180728D01*
G01X1960320Y183690D02*
X1958500Y181870D01*
G01X1953024Y201300D02*
X1960320Y194004D01*
G01X1949770Y201300D02*
X1953024D01*
G01X1945348Y205722D02*
X1949770Y201300D01*
G01X1945348Y225300D02*
Y205722D01*
G01X1910162Y220919D02*
X1910340Y220741D01*
G01X1927900Y221400D02*
X1931434D01*
G01X1907888Y241412D02*
X1927900Y221400D01*
G01X1946501Y225348D02*
X1946500Y225347D01*
G01X1946501Y226654D02*
Y225348D01*
G01X1946500Y226655D02*
X1946501Y226654D01*
G01X1946500Y227500D02*
Y226655D01*
G01X1945542Y228458D02*
X1946500Y227500D01*
G01X1944463Y228458D02*
X1945542D01*
G01X1924947Y232847D02*
X1925835Y233735D01*
G01X1920917Y232847D02*
X1924947D01*
G01X1909295Y244469D02*
X1920917Y232847D01*
G01X1928447Y222352D02*
X1932663D01*
G01X1908313Y242486D02*
X1928447Y222352D01*
G01X1920605Y232095D02*
X1909183Y243517D01*
G01X1925205Y232095D02*
X1920605D01*
G01X1926100Y231200D02*
X1925205Y232095D01*
G01X1945000Y225648D02*
X1945348Y225300D01*
G01X1945000Y226000D02*
Y225648D01*
G01X1944924Y226000D02*
X1945000D01*
G01X1944924Y226001D02*
Y226000D01*
G01X1944925Y226001D02*
X1944924D01*
G01X1938510Y460935D02*
X1946000Y468425D01*
G01X1938510Y449810D02*
Y460935D01*
G01X1931208Y442508D02*
X1938510Y449810D01*
G01X1907572Y442508D02*
X1931208D01*
G01X1902960Y437896D02*
X1907572Y442508D01*
G01X1939510Y460520D02*
X1947000Y468010D01*
G01X1939510Y449463D02*
Y460520D01*
G01X1931603Y441556D02*
X1939510Y449463D01*
G01X1907967Y441556D02*
X1931603D01*
G01X1903555Y437144D02*
X1907967Y441556D01*
G01X1908845Y440804D02*
X1904428Y436387D01*
G01X1941696Y440804D02*
X1908845D01*
G01X1942000Y440500D02*
X1941696Y440804D01*
G01X1907447Y437776D02*
X1904906Y435235D01*
G01X1958336Y437776D02*
X1907447D01*
G01X1972780Y452220D02*
X1958336Y437776D01*
G01X1909350Y496600D02*
Y492773D01*
G01X1912390Y499640D02*
X1909350Y496600D01*
G01X1934848Y499640D02*
X1912390D01*
G01X1940493Y505285D02*
X1934848Y499640D01*
G01X1940493Y520389D02*
Y505285D01*
G01X1949904Y529800D02*
X1940493Y520389D01*
G01X1946000Y473000D02*
X1945000Y474000D01*
G01X1946000Y468425D02*
Y473000D01*
G01X1921760Y515360D02*
X1913900Y507500D01*
G01X1923419Y515360D02*
X1921760D01*
G01X1928006Y519947D02*
X1923419Y515360D01*
G01X1932003Y519947D02*
X1928006D01*
G01X1937967Y525911D02*
X1932003Y519947D01*
G01X1937967Y536857D02*
Y525911D01*
G01X1947000Y473100D02*
X1948200Y474300D01*
G01X1947000Y468010D02*
Y473100D01*
G01X1941424Y479024D02*
X1939000Y476600D01*
G01X1941424Y503168D02*
Y479024D01*
G01X1946400Y508144D02*
X1941424Y503168D01*
G01X1946400Y523360D02*
Y508144D01*
G01X1953476Y530436D02*
X1946400Y523360D01*
G01X1899772Y495336D02*
Y486494D01*
G01X1905732Y501296D02*
X1899772Y495336D01*
G01X1934376Y501296D02*
X1905732D01*
G01X1938900Y505820D02*
X1934376Y501296D01*
G01X1938900Y520924D02*
Y505820D01*
G01X1948400Y530424D02*
X1938900Y520924D01*
G01X1933032Y518248D02*
X1945600Y530816D01*
G01X1928582Y518248D02*
X1933032D01*
G01X1924190Y513856D02*
X1928582Y518248D01*
G01X1922655Y513856D02*
X1924190D01*
G01X1912351Y503552D02*
X1922655Y513856D01*
G01X1915500Y516000D02*
X1912300Y512800D01*
G01X1915500Y520000D02*
Y516000D01*
G01X1918000Y522500D02*
X1915500Y520000D01*
G01X1931099Y522500D02*
X1918000D01*
G01X1935000Y526401D02*
X1931099Y522500D01*
G01X1910250Y496300D02*
Y492043D01*
G01X1912728Y498778D02*
X1910250Y496300D01*
G01X1935050Y498778D02*
X1912728D01*
G01X1945600Y509328D02*
X1935050Y498778D01*
G01X1945600Y523860D02*
Y509328D01*
G01X1951900Y530160D02*
X1945600Y523860D01*
G01X1939110Y525390D02*
Y537910D01*
G01X1932720Y519000D02*
X1939110Y525390D01*
G01X1928270Y519000D02*
X1932720D01*
G01X1923878Y514608D02*
X1928270Y519000D01*
G01X1922208Y514608D02*
X1923878D01*
G01X1914100Y506500D02*
X1922208Y514608D01*
G01X1899000Y494150D02*
Y486786D01*
G01X1899020Y494170D02*
X1899000Y494150D01*
G01X1899020Y495648D02*
Y494170D01*
G01X1905420Y502048D02*
X1899020Y495648D01*
G01X1932037Y502048D02*
X1905420D01*
G01X1935600Y505611D02*
X1932037Y502048D01*
G01X1935600Y518688D02*
Y505611D01*
G01X1947500Y530588D02*
X1935600Y518688D01*
G01X1939741Y520701D02*
X1949152Y530112D01*
G01X1939741Y505597D02*
Y520701D01*
G01X1934608Y500464D02*
X1939741Y505597D01*
G01X1905964Y500464D02*
X1934608D01*
G01X1900524Y495024D02*
X1905964Y500464D01*
G01X1900524Y486182D02*
Y495024D01*
G01X1898000Y496748D02*
Y490700D01*
G01X1904052Y502800D02*
X1898000Y496748D01*
G01X1912810Y502800D02*
X1904052D01*
G01X1923114Y513104D02*
X1912810Y502800D01*
G01X1924502Y513104D02*
X1923114D01*
G01X1928894Y517496D02*
X1924502Y513104D01*
G01X1933344Y517496D02*
X1928894D01*
G01X1946500Y530652D02*
X1933344Y517496D01*
G01X1935988Y525530D02*
Y537113D01*
G01X1932006Y521548D02*
X1935988Y525530D01*
G01X1918395Y521548D02*
X1932006D01*
G01X1916452Y519605D02*
X1918395Y521548D01*
G01X1916452Y511753D02*
Y519605D01*
G01X1913099Y508400D02*
X1916452Y511753D01*
G01X1918880Y586460D02*
X1908525D01*
G01X1949904Y535276D02*
Y529800D01*
G01X1951180Y536552D02*
X1949904Y535276D01*
G01X1951180Y541984D02*
Y536552D01*
G01X1934544Y558620D02*
X1951180Y541984D01*
G01X1931380Y558620D02*
X1934544D01*
G01X1924900Y565100D02*
X1931380Y558620D01*
G01X1923600Y565100D02*
X1924900D01*
G01X1935029Y539795D02*
X1937967Y536857D01*
G01X1935029Y546071D02*
Y539795D01*
G01X1919629Y561471D02*
X1935029Y546071D01*
G01X1919629Y575729D02*
Y561471D01*
G01X1923400Y579500D02*
X1919629Y575729D01*
G01X1923500Y579500D02*
X1923400D01*
G01X1958420Y573840D02*
X1964890Y567370D01*
G01X1958420Y595500D02*
Y573840D01*
G01X1953476Y541224D02*
Y530436D01*
G01X1949000Y545700D02*
X1953476Y541224D01*
G01X1949000Y549501D02*
Y545700D01*
G01X1946525Y551976D02*
X1949000Y549501D01*
G01X1942489Y551976D02*
X1946525D01*
G01X1935093Y559372D02*
X1942489Y551976D01*
G01X1932281Y559372D02*
X1935093D01*
G01X1927769Y563884D02*
X1932281Y559372D01*
G01X1927769Y586856D02*
Y563884D01*
G01X1927671Y586954D02*
X1927769Y586856D01*
G01X1927671Y590562D02*
Y586954D01*
G01X1948400Y535900D02*
Y530424D01*
G01X1949676Y537176D02*
X1948400Y535900D01*
G01X1949676Y541224D02*
Y537176D01*
G01X1936500Y554400D02*
X1949676Y541224D01*
G01X1935493Y554400D02*
X1936500D01*
G01X1932777Y557116D02*
X1935493Y554400D01*
G01X1928986Y557116D02*
X1932777D01*
G01X1926602Y559500D02*
X1928986Y557116D01*
G01X1926600Y559500D02*
X1926602D01*
G01X1925076Y581324D02*
X1923400Y583000D01*
G01X1925076Y578847D02*
Y581324D01*
G01X1923679Y577450D02*
X1925076Y578847D01*
G01X1923321Y577450D02*
X1923679D01*
G01X1920381Y574510D02*
X1923321Y577450D01*
G01X1920381Y562426D02*
Y574510D01*
G01X1934707Y548100D02*
X1920381Y562426D01*
G01X1940299Y548100D02*
X1934707D01*
G01X1945600Y542799D02*
X1940299Y548100D01*
G01X1945600Y530816D02*
Y542799D01*
G01X1935000Y536399D02*
Y526401D01*
G01X1930599Y540800D02*
X1935000Y536399D01*
G01X1918100Y540800D02*
X1930599D01*
G01X1914750Y544150D02*
X1918100Y540800D01*
G01X1914750Y544863D02*
Y544150D01*
G01X1951900Y534900D02*
Y530160D01*
G01X1940500Y546300D02*
X1939800D01*
G01X1943000Y543800D02*
X1940500Y546300D01*
G01X1943000Y541800D02*
Y543800D01*
G01X1939110Y537910D02*
X1943000Y541800D01*
G01X1947500Y538100D02*
Y530588D01*
G01X1948100Y538700D02*
X1947500Y538100D01*
G01X1915793Y549957D02*
X1922000Y543750D01*
G01X1907416Y549957D02*
X1915793D01*
G01X1901500Y555418D02*
Y545671D01*
G01X1921885Y567585D02*
X1923000Y568700D01*
G01X1921885Y564086D02*
Y567585D01*
G01X1923771Y562200D02*
X1921885Y564086D01*
G01X1926736Y562200D02*
X1923771D01*
G01X1931068Y557868D02*
X1926736Y562200D01*
G01X1933089Y557868D02*
X1931068D01*
G01X1935457Y555500D02*
X1933089Y557868D01*
G01X1936600Y555500D02*
X1935457D01*
G01X1950428Y541672D02*
X1936600Y555500D01*
G01X1950428Y536864D02*
Y541672D01*
G01X1949152Y535588D02*
X1950428Y536864D01*
G01X1949152Y530112D02*
Y535588D01*
G01X1946500Y543300D02*
Y530652D01*
G01X1936500Y553300D02*
X1946500Y543300D01*
G01X1935529Y553300D02*
X1936500D01*
G01X1932465Y556364D02*
X1935529Y553300D01*
G01X1927507Y556364D02*
X1932465D01*
G01X1921133Y562738D02*
X1927507Y556364D01*
G01X1921133Y573033D02*
Y562738D01*
G01X1923600Y575500D02*
X1921133Y573033D01*
G01X1919708Y553393D02*
X1905169D01*
G01X1935988Y537113D02*
X1919708Y553393D01*
G01X1928623Y587349D02*
Y591755D01*
G01X1928721Y587251D02*
X1928623Y587349D01*
G01X1928721Y564279D02*
Y587251D01*
G01X1932676Y560324D02*
X1928721Y564279D01*
G01X1935676Y560324D02*
X1932676D01*
G01X1943072Y552928D02*
X1935676Y560324D01*
G01X1946971Y552928D02*
X1943072D01*
G01X1957300Y542599D02*
X1946971Y552928D01*
G01X1957300Y536200D02*
Y542599D01*
G01X1958500Y535000D02*
X1957300Y536200D01*
G01X1957156Y552259D02*
Y599534D01*
G01X1962609Y546806D02*
X1957156Y552259D01*
G01X1961580Y598660D02*
X1958420Y595500D01*
G01X1954680Y612840D02*
X1961580Y605940D01*
G01X1934410Y612840D02*
X1954680D01*
G01X1928690Y607120D02*
X1934410Y612840D01*
G01X1914650Y607120D02*
X1928690D01*
G01X1922057Y596176D02*
X1927671Y590562D01*
G01X1911212Y596176D02*
X1922057D01*
G01X1907122Y592086D02*
X1911212Y596176D01*
G01X1907122Y588249D02*
Y592086D01*
G01X1910700Y594600D02*
X1914700D01*
G01X1908071Y591971D02*
X1910700Y594600D01*
G01X1908071Y588134D02*
Y591971D01*
G01X1906170Y592656D02*
Y588644D01*
G01X1911041Y597527D02*
X1906170Y592656D01*
G01X1922851Y597527D02*
X1911041D01*
G01X1928623Y591755D02*
X1922851Y597527D01*
G01X1938289Y601639D02*
X1938130Y601480D01*
G01X1955051Y601639D02*
X1938289D01*
G01X1957156Y599534D02*
X1955051Y601639D01*
G01X1974309Y73622D02*
X1970629Y69942D01*
G01X1974309Y132075D02*
Y73622D01*
G01X1973157Y75182D02*
X1969069Y71094D01*
G01X1973157Y130573D02*
Y75182D01*
G01X1964883Y135470D02*
X1962167D01*
G01X1970853Y129500D02*
X1964883Y135470D01*
G01X1970853Y116716D02*
Y129500D01*
G01X1967331Y113194D02*
X1970853Y116716D01*
G01X1963434Y113194D02*
X1967331D01*
G01X1965018Y137082D02*
X1962529D01*
G01X1972005Y130095D02*
X1965018Y137082D01*
G01X1972005Y116238D02*
Y130095D01*
G01X1967809Y112042D02*
X1972005Y116238D01*
G01X1963912Y112042D02*
X1967809D01*
G01X1967013Y139371D02*
X1974309Y132075D01*
G01X1967013Y143817D02*
Y139371D01*
G01X1965257Y145573D02*
X1967013Y143817D01*
G01X1961657Y145573D02*
X1965257D01*
G01X1959652Y147578D02*
X1961657Y145573D01*
G01X1959652Y181392D02*
Y147578D01*
G01X1965252Y138478D02*
X1973157Y130573D01*
G01X1963131Y138478D02*
X1965252D01*
G01X1961472Y183212D02*
X1959652Y181392D01*
G01X1961472Y194482D02*
Y183212D01*
G01X1960320Y194004D02*
Y183690D01*
G01X1972780Y518343D02*
Y452220D01*
G01X1971150Y519973D02*
X1972780Y518343D01*
G01X1971150Y548400D02*
Y519973D01*
G01X1962609Y525969D02*
Y546806D01*
G01X1959395Y522755D02*
X1962609Y525969D01*
G01X1959395Y518095D02*
Y522755D01*
G01X1959300Y518000D02*
X1959395Y518095D01*
G01X1964890Y567370D02*
Y534940D01*
G01X1972700Y549950D02*
X1971150Y548400D01*
G01X1961580Y605940D02*
Y598660D01*
G54D14*
G01X65550Y-47300D02*
X60500Y-42250D01*
G01X144200Y-47300D02*
X65550D01*
G01X145585Y-45915D02*
X144200Y-47300D01*
G01X443146Y-45915D02*
X145585D01*
G01X146299Y-42355D02*
X443146D01*
G01X125420Y91692D02*
Y125729D01*
G01X124784Y91056D02*
X125420Y91692D01*
G01X124784Y89596D02*
Y91056D01*
G01X126666Y87714D02*
X124784Y89596D01*
G01X127892Y86488D02*
X126666Y87714D01*
G01X127892Y73475D02*
Y86488D01*
G01X128667Y72700D02*
X127892Y73475D01*
G01X128667Y71076D02*
Y72700D01*
G01X127091Y69500D02*
X128667Y71076D01*
G01X125867Y69500D02*
X127091D01*
G01X123620Y67253D02*
X125867Y69500D01*
G01X123620Y65699D02*
Y67253D01*
G01X168903Y72367D02*
X169770Y71500D01*
G01X168903Y74668D02*
Y72367D01*
G01X167270Y76301D02*
X168903Y74668D01*
G01X167270Y77600D02*
Y76301D01*
G01X168620Y78950D02*
X167270Y77600D01*
G01X168620Y79850D02*
Y78950D01*
G01X167370Y81100D02*
X168620Y79850D01*
G01X167370Y82299D02*
Y81100D01*
G01X168903Y83832D02*
X167370Y82299D01*
G01X168903Y85800D02*
Y83832D01*
G01X166003Y88700D02*
X168903Y85800D01*
G01X166003Y91636D02*
Y88700D01*
G01X167124Y92757D02*
X166003Y91636D01*
G01X160431Y67253D02*
Y65699D01*
G01X162678Y69500D02*
X160431Y67253D01*
G01X163902Y69500D02*
X162678D01*
G01X165478Y71076D02*
X163902Y69500D01*
G01X165478Y72700D02*
Y71076D01*
G01X164703Y73475D02*
X165478Y72700D01*
G01X164703Y86488D02*
Y73475D01*
G01X163477Y87714D02*
X164703Y86488D01*
G01X122856Y93521D02*
Y131284D01*
G01X123620Y92757D02*
X122856Y93521D01*
G01X122692Y91829D02*
X123620Y92757D01*
G01X122692Y88701D02*
Y91829D01*
G01X125492Y85901D02*
X122692Y88701D01*
G01X125492Y84032D02*
Y85901D01*
G01X124109Y82649D02*
X125492Y84032D01*
G01X124109Y81250D02*
Y82649D01*
G01X125559Y79800D02*
X124109Y81250D01*
G01X125559Y78600D02*
Y79800D01*
G01X124059Y77100D02*
X125559Y78600D01*
G01X124059Y75901D02*
Y77100D01*
G01X125492Y74468D02*
X124059Y75901D01*
G01X125492Y72588D02*
Y74468D01*
G01X126580Y71500D02*
X125492Y72588D01*
G01X132092Y72367D02*
X132959Y71500D01*
G01X132092Y74668D02*
Y72367D01*
G01X130459Y76301D02*
X132092Y74668D01*
G01X130459Y77600D02*
Y76301D01*
G01X131809Y78950D02*
X130459Y77600D01*
G01X131809Y79850D02*
Y78950D01*
G01X130559Y81100D02*
X131809Y79850D01*
G01X130559Y82299D02*
Y81100D01*
G01X132092Y83832D02*
X130559Y82299D01*
G01X132092Y85800D02*
Y83832D01*
G01X129192Y88700D02*
X132092Y85800D01*
G01X129192Y91636D02*
Y88700D01*
G01X130313Y92757D02*
X129192Y91636D01*
G01X130313Y92757D02*
X127920Y95150D01*
G01X155517Y73467D02*
X157084Y71900D01*
G01X155517Y74668D02*
Y73467D01*
G01X154159Y76026D02*
X155517Y74668D01*
G01X154159Y77399D02*
Y76026D01*
G01X155359Y78599D02*
X154159Y77399D01*
G01X155359Y79725D02*
Y78599D01*
G01X154159Y80925D02*
X155359Y79725D01*
G01X154159Y82500D02*
Y80925D01*
G01X155959Y84300D02*
X154159Y82500D01*
G01X155959Y85358D02*
Y84300D01*
G01X152617Y88700D02*
X155959Y85358D01*
G01X152617Y91636D02*
Y88700D01*
G01X153738Y92757D02*
X152617Y91636D01*
G01X155438Y94457D02*
Y96347D01*
G01X153738Y92757D02*
X155438Y94457D01*
G01X149545Y92117D02*
Y112100D01*
G01X148584Y91156D02*
X149545Y92117D01*
G01X148584Y89521D02*
Y91156D01*
G01X150391Y87714D02*
X148584Y89521D01*
G01X151780Y86325D02*
X150391Y87714D01*
G01X151780Y73312D02*
Y86325D01*
G01X152392Y72700D02*
X151780Y73312D01*
G01X152392Y71300D02*
Y72700D01*
G01X150592Y69500D02*
X152392Y71300D01*
G01X149592Y69500D02*
X150592D01*
G01X148292Y68200D02*
X149592Y69500D01*
G01X148292Y66946D02*
Y68200D01*
G01X147045Y65699D02*
X148292Y66946D01*
G01X132380Y92388D02*
Y99752D01*
G01X131084Y91092D02*
X132380Y92388D01*
G01X131084Y89589D02*
Y91092D01*
G01X132959Y87714D02*
X131084Y89589D01*
G01X134432Y86241D02*
X132959Y87714D01*
G01X134432Y73116D02*
Y86241D01*
G01X135048Y72500D02*
X134432Y73116D01*
G01X135048Y71156D02*
Y72500D01*
G01X133592Y69700D02*
X135048Y71156D01*
G01X132192Y69700D02*
X133592D01*
G01X130313Y67821D02*
X132192Y69700D01*
G01X130313Y65699D02*
Y67821D01*
G01X162303Y72588D02*
X163391Y71500D01*
G01X162303Y74468D02*
Y72588D01*
G01X160870Y75901D02*
X162303Y74468D01*
G01X160870Y77100D02*
Y75901D01*
G01X162370Y78600D02*
X160870Y77100D01*
G01X162370Y79800D02*
Y78600D01*
G01X160920Y81250D02*
X162370Y79800D01*
G01X160920Y82649D02*
Y81250D01*
G01X162303Y84032D02*
X160920Y82649D01*
G01X162303Y85901D02*
Y84032D01*
G01X159503Y88701D02*
X162303Y85901D01*
G01X159503Y91829D02*
Y88701D01*
G01X160431Y92757D02*
X159503Y91829D01*
G01X155192Y91300D02*
X159792Y95900D01*
G01X155192Y89606D02*
Y91300D01*
G01X157084Y87714D02*
X155192Y89606D01*
G01X158473Y86325D02*
X157084Y87714D01*
G01X158473Y73312D02*
Y86325D01*
G01X159085Y72700D02*
X158473Y73312D01*
G01X159085Y71300D02*
Y72700D01*
G01X157285Y69500D02*
X159085Y71300D01*
G01X156285Y69500D02*
X157285D01*
G01X154985Y68200D02*
X156285Y69500D01*
G01X154985Y66946D02*
Y68200D01*
G01X153738Y65699D02*
X154985Y66946D01*
G01X146117Y91829D02*
X147045Y92757D01*
G01X146117Y88701D02*
Y91829D01*
G01X149159Y85659D02*
X146117Y88701D01*
G01X149159Y84274D02*
Y85659D01*
G01X147484Y82599D02*
X149159Y84274D01*
G01X147484Y81476D02*
Y82599D01*
G01X148984Y79976D02*
X147484Y81476D01*
G01X148984Y78624D02*
Y79976D01*
G01X147484Y77124D02*
X148984Y78624D01*
G01X147484Y75901D02*
Y77124D01*
G01X148917Y74468D02*
X147484Y75901D01*
G01X148917Y73374D02*
Y74468D01*
G01X150391Y71900D02*
X148917Y73374D01*
G01X147045Y92757D02*
Y131400D01*
G01X167124Y67821D02*
Y65699D01*
G01X169003Y69700D02*
X167124Y67821D01*
G01X170403Y69700D02*
X169003D01*
G01X129384Y145096D02*
X247151Y262863D01*
G01X129384Y129693D02*
Y145096D01*
G01X125420Y125729D02*
X129384Y129693D01*
G01X122856Y142104D02*
X246115Y265363D01*
G01X122856Y134964D02*
Y142104D01*
G01X123416Y134404D02*
X122856Y134964D01*
G01X125132Y134404D02*
X123416D01*
G01X125692Y133844D02*
X125132Y134404D01*
G01X125692Y132404D02*
Y133844D01*
G01X125132Y131844D02*
X125692Y132404D01*
G01X123416Y131844D02*
X125132D01*
G01X122856Y131284D02*
X123416Y131844D01*
G01X131884Y144060D02*
X248187Y260363D01*
G01X131884Y126624D02*
Y144060D01*
G01X131324Y126064D02*
X131884Y126624D01*
G01X129952Y126064D02*
X131324D01*
G01X129392Y125504D02*
X129952Y126064D01*
G01X129392Y124064D02*
Y125504D01*
G01X129952Y123504D02*
X129392Y124064D01*
G01X131324Y123504D02*
X129952D01*
G01X131884Y122944D02*
X131324Y123504D01*
G01X131884Y121504D02*
Y122944D01*
G01X131324Y120944D02*
X131884Y121504D01*
G01X129952Y120944D02*
X131324D01*
G01X129392Y120384D02*
X129952Y120944D01*
G01X129392Y118944D02*
Y120384D01*
G01X129952Y118384D02*
X129392Y118944D01*
G01X131324Y118384D02*
X129952D01*
G01X131884Y117824D02*
X131324Y118384D01*
G01X131884Y116384D02*
Y117824D01*
G01X131324Y115824D02*
X131884Y116384D01*
G01X129952Y115824D02*
X131324D01*
G01X129392Y115264D02*
X129952Y115824D01*
G01X129392Y113824D02*
Y115264D01*
G01X129952Y113264D02*
X129392Y113824D01*
G01X131324Y113264D02*
X129952D01*
G01X131884Y112704D02*
X131324Y113264D01*
G01X131884Y109672D02*
Y112704D01*
G01X131412Y109200D02*
X131884Y109672D01*
G01X128835Y109200D02*
X131412D01*
G01X127920Y108285D02*
X128835Y109200D01*
G01X127920Y95150D02*
Y108285D01*
G01X163584Y150717D02*
X255526Y242659D01*
G01X163584Y103200D02*
Y150717D01*
G01X162784Y102400D02*
X163584Y103200D01*
G01X161584Y102400D02*
X162784D01*
G01X160784Y103200D02*
X161584Y102400D01*
G01X160784Y124500D02*
Y103200D01*
G01X159984Y125300D02*
X160784Y124500D01*
G01X158784Y125300D02*
X159984D01*
G01X157984Y124500D02*
X158784Y125300D01*
G01X157984Y98893D02*
Y124500D01*
G01X155438Y96347D02*
X157984Y98893D01*
G01X159984Y150653D02*
X254490Y245159D01*
G01X159984Y130592D02*
Y150653D01*
G01X155484Y126092D02*
X159984Y130592D01*
G01X155484Y101239D02*
Y126092D01*
G01X154345Y100100D02*
X155484Y101239D01*
G01X153145Y100100D02*
X154345D01*
G01X152345Y100900D02*
X153145Y100100D01*
G01X152345Y112100D02*
Y100900D01*
G01X151545Y112900D02*
X152345Y112100D01*
G01X150345Y112900D02*
X151545D01*
G01X149545Y112100D02*
X150345Y112900D01*
G01X134384Y143024D02*
X249223Y257863D01*
G01X134384Y107373D02*
Y143024D01*
G01X133184Y106173D02*
X134384Y107373D01*
G01X130884Y106173D02*
X133184D01*
G01X130084Y105373D02*
X130884Y106173D01*
G01X130084Y104173D02*
Y105373D01*
G01X130884Y103373D02*
X130084Y104173D01*
G01X133184Y103373D02*
X130884D01*
G01X133984Y102573D02*
X133184Y103373D01*
G01X133984Y101356D02*
Y102573D01*
G01X132380Y99752D02*
X133984Y101356D01*
G01X169484Y133656D02*
X170284Y132856D01*
G01X169484Y148856D02*
Y133656D01*
G01X168684Y149656D02*
X169484Y148856D01*
G01X167484Y149656D02*
X168684D01*
G01X166684Y148856D02*
X167484Y149656D01*
G01X166684Y98792D02*
Y148856D01*
G01X163792Y95900D02*
X166684Y98792D01*
G01X159792Y95900D02*
X163792D01*
G01X157184Y151389D02*
X253454Y247659D01*
G01X157184Y148092D02*
Y151389D01*
G01X154792Y145700D02*
X157184Y148092D01*
G01X154792Y144000D02*
Y145700D01*
G01X157184Y141608D02*
X154792Y144000D01*
G01X157184Y131492D02*
Y141608D01*
G01X152645Y126953D02*
X157184Y131492D01*
G01X152645Y116400D02*
Y126953D01*
G01X151845Y115600D02*
X152645Y116400D01*
G01X150645Y115600D02*
X151845D01*
G01X149845Y116400D02*
X150645Y115600D01*
G01X149845Y131400D02*
Y116400D01*
G01X149045Y132200D02*
X149845Y131400D01*
G01X147845Y132200D02*
X149045D01*
G01X147045Y131400D02*
X147845Y132200D01*
G01X162192Y452500D02*
Y505100D01*
G01X213792Y400900D02*
X162192Y452500D01*
G01X134541Y456951D02*
Y477751D01*
G01X148292Y443200D02*
X134541Y456951D01*
G01X151992Y443200D02*
X148292D01*
G01X199892Y395300D02*
X151992Y443200D01*
G01X127859Y460450D02*
Y504747D01*
G01X129716Y455968D02*
X127859Y460450D01*
G01X146284Y439400D02*
X129716Y455968D01*
G01X150292Y439400D02*
X146284D01*
G01X196092Y393600D02*
X150292Y439400D01*
G01X136609Y457582D02*
Y480074D01*
G01X149091Y445100D02*
X136609Y457582D01*
G01X152791Y445100D02*
X149091D01*
G01X201892Y395999D02*
X152791Y445100D01*
G01X164780Y453400D02*
Y507000D01*
G01X165580Y452600D02*
X164780Y453400D01*
G01X167180Y452600D02*
X165580D01*
G01X167980Y453400D02*
X167180Y452600D01*
G01X167980Y470600D02*
Y453400D01*
G01X159692Y452300D02*
Y486200D01*
G01X211892Y400100D02*
X159692Y452300D01*
G01X150792Y455730D02*
Y506300D01*
G01X151618Y454904D02*
X150792Y455730D01*
G01X153218Y454904D02*
X151618D01*
G01X153992Y455678D02*
X153218Y454904D01*
G01X153992Y468070D02*
Y455678D01*
G01X157192Y452100D02*
Y468070D01*
G01X209992Y399300D02*
X157192Y452100D01*
G01X130746Y464565D02*
X130136Y465175D01*
G01X132133Y464565D02*
X130746D01*
G01X132703Y463995D02*
X132133Y464565D01*
G01X132703Y462605D02*
Y463995D01*
G01X132053Y461955D02*
X132703Y462605D01*
G01X130746Y461955D02*
X132053D01*
G01X130136Y461345D02*
X130746Y461955D01*
G01X130136Y460026D02*
Y461345D01*
G01X131350Y457094D02*
X130136Y460026D01*
G01X147144Y441300D02*
X131350Y457094D01*
G01X151192Y441300D02*
X147144D01*
G01X197992Y394500D02*
X151192Y441300D01*
G01X152033Y519862D02*
Y530049D01*
G01X153738Y518157D02*
X152033Y519862D01*
G01X152380Y516799D02*
X153738Y518157D01*
G01X152380Y514307D02*
Y516799D01*
G01X155792Y510895D02*
X152380Y514307D01*
G01X155792Y489842D02*
Y510895D01*
G01X156566Y489068D02*
X155792Y489842D01*
G01X158166Y489068D02*
X156566D01*
G01X158992Y489894D02*
X158166Y489068D01*
G01X158992Y505100D02*
Y489894D01*
G01X159792Y505900D02*
X158992Y505100D01*
G01X161392Y505900D02*
X159792D01*
G01X162192Y505100D02*
X161392Y505900D01*
G01X158726Y519862D02*
X160431Y518157D01*
G01X158726Y529835D02*
Y519862D01*
G01X128608D02*
Y530349D01*
G01X130313Y518157D02*
X128608Y519862D01*
G01X129192Y517036D02*
X130313Y518157D01*
G01X129192Y513817D02*
Y517036D01*
G01X132292Y510717D02*
X129192Y513817D01*
G01X132292Y480000D02*
Y510717D01*
G01X134541Y477751D02*
X132292Y480000D01*
G01X163389Y513114D02*
X163477D01*
G01X161703Y514800D02*
X163389Y513114D01*
G01X161703Y517000D02*
Y514800D01*
G01X162203Y517500D02*
X161703Y517000D01*
G01X162203Y519399D02*
Y517500D01*
G01X161066Y520536D02*
X162203Y519399D01*
G01X161066Y521864D02*
Y520536D01*
G01X162003Y522801D02*
X161066Y521864D01*
G01X162003Y524199D02*
Y522801D01*
G01X161066Y525136D02*
X162003Y524199D01*
G01X161066Y526364D02*
Y525136D01*
G01X162103Y527401D02*
X161066Y526364D01*
G01X121915Y522274D02*
Y529277D01*
G01X123620Y518157D02*
X121915Y522274D01*
G01X123002Y517539D02*
X123620Y518157D01*
G01X123002Y513459D02*
Y517539D01*
G01X125134Y511327D02*
X123002Y513459D01*
G01X127859Y504747D02*
X125134Y511327D01*
G01X134880Y511193D02*
X132959Y513114D01*
G01X134880Y504440D02*
Y511193D01*
G01X134121Y503681D02*
X134880Y504440D01*
G01X134121Y502291D02*
Y503681D01*
G01X134731Y501681D02*
X134121Y502291D01*
G01X136439Y501681D02*
X134731D01*
G01X137049Y501071D02*
X136439Y501681D01*
G01X137049Y499681D02*
Y501071D01*
G01X136439Y499071D02*
X137049Y499681D01*
G01X134730Y499071D02*
X136439D01*
G01X134120Y498461D02*
X134730Y499071D01*
G01X134120Y497071D02*
Y498461D01*
G01X134730Y496461D02*
X134120Y497071D01*
G01X136704Y496461D02*
X134730D01*
G01X137314Y495851D02*
X136704Y496461D01*
G01X137314Y494461D02*
Y495851D01*
G01X136704Y493851D02*
X137314Y494461D01*
G01X134757Y493851D02*
X136704D01*
G01X134147Y493241D02*
X134757Y493851D01*
G01X134147Y491851D02*
Y493241D01*
G01X134757Y491241D02*
X134147Y491851D01*
G01X136465Y491241D02*
X134757D01*
G01X137075Y490631D02*
X136465Y491241D01*
G01X137075Y489241D02*
Y490631D01*
G01X136465Y488631D02*
X137075Y489241D01*
G01X134969Y488631D02*
X136465D01*
G01X134306Y487968D02*
X134969Y488631D01*
G01X134306Y486578D02*
Y487968D01*
G01X134863Y486021D02*
X134306Y486578D01*
G01X136519Y486021D02*
X134863D01*
G01X137049Y485491D02*
X136519Y486021D01*
G01X137049Y484101D02*
Y485491D01*
G01X136359Y483411D02*
X137049Y484101D01*
G01X134889Y483411D02*
X136359D01*
G01X134279Y482801D02*
X134889Y483411D01*
G01X134279Y481411D02*
Y482801D01*
G01X134889Y480801D02*
X134279Y481411D01*
G01X135882Y480801D02*
X134889D01*
G01X136609Y480074D02*
X135882Y480801D01*
G01X130948Y526156D02*
X131892Y527100D01*
G01X130948Y524944D02*
Y526156D01*
G01X131792Y524100D02*
X130948Y524944D01*
G01X131792Y522400D02*
Y524100D01*
G01X130948Y521556D02*
X131792Y522400D01*
G01X130948Y520136D02*
Y521556D01*
G01X132092Y518992D02*
X130948Y520136D01*
G01X132092Y517399D02*
Y518992D01*
G01X131185Y516492D02*
X132092Y517399D01*
G01X131185Y514800D02*
Y516492D01*
G01X132871Y513114D02*
X131185Y514800D01*
G01X132959Y513114D02*
X132871D01*
G01X154373Y525788D02*
X155510Y526925D01*
G01X154373Y524712D02*
Y525788D01*
G01X155385Y523700D02*
X154373Y524712D01*
G01X155385Y522500D02*
Y523700D01*
G01X154373Y521488D02*
X155385Y522500D01*
G01X154373Y520412D02*
Y521488D01*
G01X155485Y519300D02*
X154373Y520412D01*
G01X155485Y516667D02*
Y519300D01*
G01X155310Y516492D02*
X155485Y516667D01*
G01X155310Y514800D02*
Y516492D01*
G01X156996Y513114D02*
X155310Y514800D01*
G01X157084Y513114D02*
X156996D01*
G01X157084Y513166D02*
Y513114D01*
G01X158380Y511870D02*
X157084Y513166D01*
G01X158380Y508600D02*
Y511870D01*
G01X158880Y508100D02*
X158380Y508600D01*
G01X163680Y508100D02*
X158880D01*
G01X164780Y507000D02*
X163680Y508100D01*
G01X168780Y471400D02*
X167980Y470600D01*
G01X170380Y471400D02*
X168780D01*
G01X151737Y511768D02*
X150391Y513114D01*
G01X151780Y511768D02*
X151737D01*
G01X151780Y508912D02*
Y511768D01*
G01X153292Y507400D02*
X151780Y508912D01*
G01X153292Y471863D02*
Y507400D01*
G01X154092Y471063D02*
X153292Y471863D01*
G01X155692Y471063D02*
X154092D01*
G01X156492Y471863D02*
X155692Y471063D01*
G01X156492Y486400D02*
Y471863D01*
G01X157192Y487100D02*
X156492Y486400D01*
G01X158792Y487100D02*
X157192D01*
G01X159692Y486200D02*
X158792Y487100D01*
G01X147680Y525788D02*
X148817Y526925D01*
G01X147680Y524712D02*
Y525788D01*
G01X148692Y523700D02*
X147680Y524712D01*
G01X148692Y522500D02*
Y523700D01*
G01X147680Y521488D02*
X148692Y522500D01*
G01X147680Y520412D02*
Y521488D01*
G01X148792Y519300D02*
X147680Y520412D01*
G01X148792Y516667D02*
Y519300D01*
G01X148617Y516492D02*
X148792Y516667D01*
G01X148617Y514800D02*
Y516492D01*
G01X150303Y513114D02*
X148617Y514800D01*
G01X150391Y513114D02*
X150303D01*
G01X146380Y517492D02*
X147045Y518157D01*
G01X146380Y513657D02*
Y517492D01*
G01X149280Y510757D02*
X146380Y513657D01*
G01X149280Y507812D02*
Y510757D01*
G01X150792Y506300D02*
X149280Y507812D01*
G01X154792Y468870D02*
X153992Y468070D01*
G01X156392Y468870D02*
X154792D01*
G01X157192Y468070D02*
X156392Y468870D01*
G01X145340Y519862D02*
Y530049D01*
G01X147045Y518157D02*
X145340Y519862D01*
G01X124255Y526364D02*
X125292Y527401D01*
G01X124255Y525136D02*
Y526364D01*
G01X125192Y524199D02*
X124255Y525136D01*
G01X125192Y523166D02*
Y524199D01*
G01X124255Y522229D02*
X125192Y523166D01*
G01X124255Y520901D02*
Y522229D01*
G01X125392Y519764D02*
X124255Y520901D01*
G01X125392Y517500D02*
Y519764D01*
G01X124892Y517000D02*
X125392Y517500D01*
G01X124892Y514800D02*
Y517000D01*
G01X126578Y513114D02*
X124892Y514800D01*
G01X126666Y513114D02*
X126578D01*
G01X128180Y511600D02*
X126666Y513114D01*
G01X128180Y508512D02*
Y511600D01*
G01X129792Y506900D02*
X128180Y508512D01*
G01X129792Y476389D02*
Y506900D01*
G01X130402Y475779D02*
X129792Y476389D01*
G01X132042Y475779D02*
X130402D01*
G01X132672Y475149D02*
X132042Y475779D01*
G01X132672Y473759D02*
Y475149D01*
G01X132082Y473169D02*
X132672Y473759D01*
G01X130402Y473169D02*
X132082D01*
G01X129792Y472559D02*
X130402Y473169D01*
G01X129792Y470373D02*
Y472559D01*
G01X130380Y469785D02*
X129792Y470373D01*
G01X131626Y469785D02*
X130380D01*
G01X132236Y469175D02*
X131626Y469785D01*
G01X132236Y467785D02*
Y469175D01*
G01X131626Y467175D02*
X132236Y467785D01*
G01X130746Y467175D02*
X131626D01*
G01X130136Y466565D02*
X130746Y467175D01*
G01X130136Y465175D02*
Y466565D01*
G01X167759Y526156D02*
X168703Y527100D01*
G01X167759Y524944D02*
Y526156D01*
G01X168603Y524100D02*
X167759Y524944D01*
G01X168603Y522400D02*
Y524100D01*
G01X167759Y521556D02*
X168603Y522400D01*
G01X167759Y520136D02*
Y521556D01*
G01X168903Y518992D02*
X167759Y520136D01*
G01X168903Y517399D02*
Y518992D01*
G01X167996Y516492D02*
X168903Y517399D01*
G01X167996Y513796D02*
Y516492D01*
G01X168678Y513114D02*
X167996Y513796D01*
G01X169770Y513114D02*
X168678D01*
G01X165419Y519862D02*
X167124Y518157D01*
G01X165419Y531515D02*
Y519862D01*
G01X152033Y530049D02*
X157084Y535100D01*
G01X159348Y530457D02*
X158726Y529835D01*
G01X159348Y531645D02*
Y530457D01*
G01X162403Y534700D02*
X159348Y531645D01*
G01X163391Y534700D02*
X162403D01*
G01X128608Y530349D02*
X132959Y534700D01*
G01X162103Y528299D02*
Y527401D01*
G01X161503Y528899D02*
X162103Y528299D01*
G01X160431Y528899D02*
X161503D01*
G01X122451Y530571D02*
X126580Y534700D01*
G01X121915Y529277D02*
X122451Y530571D01*
G01X131293Y528899D02*
X130313D01*
G01X131892Y528300D02*
X131293Y528899D01*
G01X131892Y527100D02*
Y528300D01*
G01X154810Y528899D02*
X153738D01*
G01X155510Y528199D02*
X154810Y528899D01*
G01X155510Y526925D02*
Y528199D01*
G01X148117Y528899D02*
X147045D01*
G01X148817Y528199D02*
X148117Y528899D01*
G01X148817Y526925D02*
Y528199D01*
G01X145340Y530049D02*
X150391Y535100D01*
G01X124692Y528899D02*
X123620D01*
G01X125292Y528299D02*
X124692Y528899D01*
G01X125292Y527401D02*
Y528299D01*
G01X168104Y528899D02*
X167124D01*
G01X168703Y528300D02*
X168104Y528899D01*
G01X168703Y527100D02*
Y528300D01*
G01X168604Y534700D02*
X165419Y531515D01*
G01X169770Y534700D02*
X168604D01*
G01X227360Y93780D02*
X222084Y99056D01*
G01X227360Y92757D02*
Y93780D01*
G01X226239Y91636D02*
X227360Y92757D01*
G01X226239Y88700D02*
Y91636D01*
G01X229581Y85358D02*
X226239Y88700D01*
G01X229581Y84300D02*
Y85358D01*
G01X227781Y82500D02*
X229581Y84300D01*
G01X227781Y80925D02*
Y82500D01*
G01X228981Y79725D02*
X227781Y80925D01*
G01X228981Y78599D02*
Y79725D01*
G01X227781Y77399D02*
X228981Y78599D01*
G01X227781Y76026D02*
Y77399D01*
G01X229139Y74668D02*
X227781Y76026D01*
G01X229139Y73467D02*
Y74668D01*
G01X230706Y71900D02*
X229139Y73467D01*
G01X229584Y92000D02*
Y96139D01*
G01X228802Y91218D02*
X229584Y92000D01*
G01X228802Y89618D02*
Y91218D01*
G01X230706Y87714D02*
X228802Y89618D01*
G01X232095Y86325D02*
X230706Y87714D01*
G01X230907Y69500D02*
X232707Y71300D01*
G01X229907Y69500D02*
X230907D01*
G01X228607Y68200D02*
X229907Y69500D01*
G01X228607Y66946D02*
Y68200D01*
G01X227360Y65699D02*
X228607Y66946D01*
G01X192328Y73467D02*
X193895Y71900D01*
G01X192328Y74668D02*
Y73467D01*
G01X190970Y76026D02*
X192328Y74668D01*
G01X190970Y77399D02*
Y76026D01*
G01X192170Y78599D02*
X190970Y77399D01*
G01X192170Y79725D02*
Y78599D01*
G01X190970Y80925D02*
X192170Y79725D01*
G01X190970Y82500D02*
Y80925D01*
G01X192770Y84300D02*
X190970Y82500D01*
G01X192770Y85358D02*
Y84300D01*
G01X189428Y88700D02*
X192770Y85358D01*
G01X189428Y91636D02*
Y88700D01*
G01X190549Y92757D02*
X189428Y91636D01*
G01X195684Y94315D02*
Y173341D01*
G01X197242Y92757D02*
X195684Y94315D01*
G01X196314Y91829D02*
X197242Y92757D01*
G01X196314Y88701D02*
Y91829D01*
G01X199114Y85901D02*
X196314Y88701D01*
G01X199114Y84032D02*
Y85901D01*
G01X197731Y82649D02*
X199114Y84032D01*
G01X197731Y81250D02*
Y82649D01*
G01X199181Y79800D02*
X197731Y81250D01*
G01X199181Y78600D02*
Y79800D01*
G01X197681Y77100D02*
X199181Y78600D01*
G01X197681Y75901D02*
Y77100D01*
G01X199114Y74468D02*
X197681Y75901D01*
G01X199114Y72588D02*
Y74468D01*
G01X200202Y71500D02*
X199114Y72588D01*
G01X222984Y91892D02*
Y95008D01*
G01X222184Y91092D02*
X222984Y91892D01*
G01X222184Y89543D02*
Y91092D01*
G01X224013Y87714D02*
X222184Y89543D01*
G01X225402Y86325D02*
X224013Y87714D01*
G01X225402Y73312D02*
Y86325D01*
G01X226014Y72700D02*
X225402Y73312D01*
G01X226014Y71300D02*
Y72700D01*
G01X224214Y69500D02*
X226014Y71300D01*
G01X223214Y69500D02*
X224214D01*
G01X221914Y68200D02*
X223214Y69500D01*
G01X221914Y66946D02*
Y68200D01*
G01X220667Y65699D02*
X221914Y66946D01*
G01X191796D02*
X190549Y65699D01*
G01X191796Y68200D02*
Y66946D01*
G01X193096Y69500D02*
X191796Y68200D01*
G01X194096Y69500D02*
X193096D01*
G01X195896Y71300D02*
X194096Y69500D01*
G01X195896Y72700D02*
Y71300D01*
G01X195284Y73312D02*
X195896Y72700D01*
G01X195284Y86325D02*
Y73312D01*
G01X193895Y87714D02*
X195284Y86325D01*
G01X203935Y92757D02*
X201292Y95400D01*
G01X202814Y91636D02*
X203935Y92757D01*
G01X202814Y88700D02*
Y91636D01*
G01X205714Y85800D02*
X202814Y88700D01*
G01X205714Y83832D02*
Y85800D01*
G01X204181Y82299D02*
X205714Y83832D01*
G01X204181Y81100D02*
Y82299D01*
G01X205431Y79850D02*
X204181Y81100D01*
G01X205431Y78950D02*
Y79850D01*
G01X204081Y77600D02*
X205431Y78950D01*
G01X204081Y76301D02*
Y77600D01*
G01X205714Y74668D02*
X204081Y76301D01*
G01X205714Y72367D02*
Y74668D01*
G01X206581Y71500D02*
X205714Y72367D01*
G01X185103Y66946D02*
X183856Y65699D01*
G01X185103Y68200D02*
Y66946D01*
G01X186403Y69500D02*
X185103Y68200D01*
G01X187403Y69500D02*
X186403D01*
G01X189203Y71300D02*
X187403Y69500D01*
G01X189203Y72700D02*
Y71300D01*
G01X188591Y73312D02*
X189203Y72700D01*
G01X188591Y86325D02*
Y73312D01*
G01X187202Y87714D02*
X188591Y86325D01*
G01X222539Y73374D02*
X224013Y71900D01*
G01X222539Y74468D02*
Y73374D01*
G01X221106Y75901D02*
X222539Y74468D01*
G01X221106Y77124D02*
Y75901D01*
G01X222606Y78624D02*
X221106Y77124D01*
G01X222606Y79976D02*
Y78624D01*
G01X221106Y81476D02*
X222606Y79976D01*
G01X221106Y82599D02*
Y81476D01*
G01X222781Y84274D02*
X221106Y82599D01*
G01X222781Y85659D02*
Y84274D01*
G01X219739Y88701D02*
X222781Y85659D01*
G01X219739Y91833D02*
Y88701D01*
G01X220667Y92761D02*
X219739Y91833D01*
G01X220667Y94325D02*
Y92761D01*
G01X216984Y98008D02*
X220667Y94325D01*
G01X205866Y93774D02*
X204784Y94856D01*
G01X205866Y92174D02*
Y93774D01*
G01X204684Y90992D02*
X205866Y92174D01*
G01X204684Y89611D02*
Y90992D01*
G01X206581Y87714D02*
X204684Y89611D01*
G01X208054Y86241D02*
X206581Y87714D01*
G01X208054Y73116D02*
Y86241D01*
G01X208670Y72500D02*
X208054Y73116D01*
G01X208670Y71156D02*
Y72500D01*
G01X207214Y69700D02*
X208670Y71156D01*
G01X205814Y69700D02*
X207214D01*
G01X203935Y67821D02*
X205814Y69700D01*
G01X203935Y65699D02*
Y67821D01*
G01X199184Y91992D02*
Y95801D01*
G01X198384Y91192D02*
X199184Y91992D01*
G01X198384Y89618D02*
Y91192D01*
G01X200288Y87714D02*
X198384Y89618D01*
G01X201514Y86488D02*
X200288Y87714D01*
G01X201514Y73475D02*
Y86488D01*
G01X202289Y72700D02*
X201514Y73475D01*
G01X202289Y71076D02*
Y72700D01*
G01X200713Y69500D02*
X202289Y71076D01*
G01X199489Y69500D02*
X200713D01*
G01X197242Y67253D02*
X199489Y69500D01*
G01X197242Y65699D02*
Y67253D01*
G01X182928Y91829D02*
X183856Y92757D01*
G01X182928Y88701D02*
Y91829D01*
G01X185970Y85659D02*
X182928Y88701D01*
G01X185970Y84274D02*
Y85659D01*
G01X184295Y82599D02*
X185970Y84274D01*
G01X184295Y81476D02*
Y82599D01*
G01X185795Y79976D02*
X184295Y81476D01*
G01X185795Y78624D02*
Y79976D01*
G01X184295Y77124D02*
X185795Y78624D01*
G01X184295Y75901D02*
Y77124D01*
G01X185728Y74468D02*
X184295Y75901D01*
G01X185728Y73374D02*
Y74468D01*
G01X187202Y71900D02*
X185728Y73374D01*
G01X171859Y71156D02*
X170403Y69700D01*
G01X171859Y72500D02*
Y71156D01*
G01X171243Y73116D02*
X171859Y72500D01*
G01X171243Y86241D02*
Y73116D01*
G01X169770Y87714D02*
X171243Y86241D01*
G01X227745Y112600D02*
Y169253D01*
G01X226945Y111800D02*
X227745Y112600D01*
G01X225745Y111800D02*
X226945D01*
G01X224945Y112600D02*
X225745Y111800D01*
G01X224945Y132400D02*
Y112600D01*
G01X224145Y133200D02*
X224945Y132400D01*
G01X222945Y133200D02*
X224145D01*
G01X222084Y132339D02*
X222945Y133200D01*
G01X222084Y99056D02*
Y132339D01*
G01X230245Y155002D02*
Y156392D01*
G01X230855Y154392D02*
X230245Y155002D01*
G01X231982Y154392D02*
X230855D01*
G01Y151782D02*
X231982D01*
G01X230245Y151172D02*
X230855Y151782D01*
G01X230245Y149782D02*
Y151172D01*
G01X230855Y149172D02*
X230245Y149782D01*
G01X231982Y149172D02*
X230855D01*
G01Y146562D02*
X231982D01*
G01X230245Y145952D02*
X230855Y146562D01*
G01X230245Y110400D02*
Y145952D01*
G01X229445Y109600D02*
X230245Y110400D01*
G01X225445Y109600D02*
X229445D01*
G01X224645Y108800D02*
X225445Y109600D01*
G01X224645Y99639D02*
Y108800D01*
G01X225445Y98839D02*
X224645Y99639D01*
G01X227631Y98839D02*
X225445D01*
G01X228645Y99853D02*
X227631Y98839D01*
G01X228645Y106440D02*
Y99853D01*
G01X229205Y107000D02*
X228645Y106440D01*
G01X230885Y107000D02*
X229205D01*
G01X231445Y106440D02*
X230885Y107000D01*
G01X229584Y96139D02*
X231445Y98000D01*
G01X225245Y135900D02*
Y171653D01*
G01X224445Y135100D02*
X225245Y135900D01*
G01X223245Y135100D02*
X224445D01*
G01X222445Y135900D02*
X223245Y135100D01*
G01X222445Y149413D02*
Y135900D01*
G01X221524Y150334D02*
X222445Y149413D01*
G01X220324Y150334D02*
X221524D01*
G01X219584Y149594D02*
X220324Y150334D01*
G01X219584Y98408D02*
Y149594D01*
G01X222984Y95008D02*
X219584Y98408D01*
G01X200592Y124045D02*
Y171336D01*
G01X201152Y123485D02*
X200592Y124045D01*
G01X202132Y123485D02*
X201152D01*
G01X202692Y122925D02*
X202132Y123485D01*
G01X202692Y121485D02*
Y122925D01*
G01X202132Y120925D02*
X202692Y121485D01*
G01X201152Y120925D02*
X202132D01*
G01X200592Y120365D02*
X201152Y120925D01*
G01X200592Y118925D02*
Y120365D01*
G01X201152Y118365D02*
X200592Y118925D01*
G01X202132Y118365D02*
X201152D01*
G01X202692Y117805D02*
X202132Y118365D01*
G01X202692Y116365D02*
Y117805D01*
G01X202132Y115805D02*
X202692Y116365D01*
G01X201152Y115805D02*
X202132D01*
G01X200592Y115245D02*
X201152Y115805D01*
G01X200592Y113805D02*
Y115245D01*
G01X201152Y113245D02*
X200592Y113805D01*
G01X202132Y113245D02*
X201152D01*
G01X202692Y112685D02*
X202132Y113245D01*
G01X202692Y111245D02*
Y112685D01*
G01X202132Y110685D02*
X202692Y111245D01*
G01X201152Y110685D02*
X202132D01*
G01X200592Y110125D02*
X201152Y110685D01*
G01X200592Y108685D02*
Y110125D01*
G01X201152Y108125D02*
X200592Y108685D01*
G01X202132Y108125D02*
X201152D01*
G01X202692Y107565D02*
X202132Y108125D01*
G01X202692Y106125D02*
Y107565D01*
G01X202132Y105565D02*
X202692Y106125D01*
G01X201152Y105565D02*
X202132D01*
G01X200592Y105005D02*
X201152Y105565D01*
G01X200592Y103565D02*
Y105005D01*
G01X201152Y103005D02*
X200592Y103565D01*
G01X202132Y103005D02*
X201152D01*
G01X202692Y102445D02*
X202132Y103005D01*
G01X202692Y101005D02*
Y102445D01*
G01X202132Y100445D02*
X202692Y101005D01*
G01X201152Y100445D02*
X202132D01*
G01X200592Y99885D02*
X201152Y100445D01*
G01X200592Y97800D02*
Y99885D01*
G01X201292Y97100D02*
X200592Y97800D01*
G01X201292Y95400D02*
Y97100D01*
G01X216984Y151930D02*
Y98008D01*
G01X217544Y152490D02*
X216984Y151930D01*
G01X222732Y152490D02*
X217544D01*
G01X223292Y153050D02*
X222732Y152490D01*
G01X223292Y154490D02*
Y153050D01*
G01X222732Y155050D02*
X223292Y154490D01*
G01X217544Y155050D02*
X222732D01*
G01X216984Y155610D02*
X217544Y155050D01*
G01X216984Y157050D02*
Y155610D01*
G01X203384Y129773D02*
Y168292D01*
G01X204784Y128373D02*
X203384Y129773D01*
G01X204784Y94856D02*
Y128373D01*
G01X198642Y96343D02*
Y172301D01*
G01X199184Y95801D02*
X198642Y96343D01*
G01X172284Y155881D02*
X256562Y240159D01*
G01X172284Y133656D02*
Y155881D01*
G01X171484Y132856D02*
X172284Y133656D01*
G01X170284Y132856D02*
X171484D01*
G01X227745Y169253D02*
X245092Y186600D01*
G01X230245Y168053D02*
X244792Y182600D01*
G01X230245Y165442D02*
Y168053D01*
G01X230855Y164832D02*
X230245Y165442D01*
G01X231982Y164832D02*
X230855D01*
G01Y162222D02*
X231982D01*
G01X230245Y161612D02*
X230855Y162222D01*
G01X230245Y160222D02*
Y161612D01*
G01X230855Y159612D02*
X230245Y160222D01*
G01X231982Y159612D02*
X230855D01*
G01Y157002D02*
X231982D01*
G01X230245Y156392D02*
X230855Y157002D01*
G01X195684Y173341D02*
X255295Y232952D01*
G01X225245Y171653D02*
X244592Y191000D01*
G01X200592Y171336D02*
X257108Y227852D01*
G01X217544Y157610D02*
X216984Y157050D01*
G01X222732Y157610D02*
X217544D01*
G01X223292Y158170D02*
X222732Y157610D01*
G01X223292Y159610D02*
Y158170D01*
G01X222732Y160170D02*
X223292Y159610D01*
G01X217544Y160170D02*
X222732D01*
G01X216984Y160730D02*
X217544Y160170D01*
G01X216984Y162170D02*
Y160730D01*
G01X217544Y162730D02*
X216984Y162170D01*
G01X222732Y162730D02*
X217544D01*
G01X223292Y163290D02*
X222732Y162730D01*
G01X223292Y164730D02*
Y163290D01*
G01X222732Y165290D02*
X223292Y164730D01*
G01X217544Y165290D02*
X222732D01*
G01X216984Y165850D02*
X217544Y165290D01*
G01X216984Y168192D02*
Y165850D01*
G01X244830Y196038D02*
X216984Y168192D01*
G01X203384Y168292D02*
X257092Y222000D01*
G01X198642Y172301D02*
X256743Y230402D01*
G01X218687Y398085D02*
Y404505D01*
G01X258941Y357831D02*
X218687Y398085D01*
G01X213792Y394524D02*
Y400900D01*
G01X256856Y351460D02*
X213792Y394524D01*
G01X220572Y398866D02*
Y406198D01*
G01X259057Y360381D02*
X220572Y398866D01*
G01X224342Y400428D02*
Y409524D01*
G01X259143Y365627D02*
X224342Y400428D01*
G01X222457Y399647D02*
Y407873D01*
G01X259028Y363076D02*
X222457Y399647D01*
G01X199892Y389426D02*
Y395300D01*
G01X254482Y334836D02*
X199892Y389426D01*
G01X196092Y387894D02*
Y393600D01*
G01X253739Y330247D02*
X196092Y387894D01*
G01X201892Y390093D02*
Y395999D01*
G01X254649Y337336D02*
X201892Y390093D01*
G01X215677Y401682D02*
X171180Y446179D01*
G01X215677Y395306D02*
Y401682D01*
G01X256983Y354000D02*
X215677Y395306D01*
G01X211892Y393758D02*
Y400100D01*
G01X256034Y349616D02*
X211892Y393758D01*
G01X209992Y392992D02*
Y399300D01*
G01X255424Y347560D02*
X209992Y392992D01*
G01X197992Y388660D02*
Y394500D01*
G01X254316Y332336D02*
X197992Y388660D01*
G01X192792Y430400D02*
Y505023D01*
G01X218687Y404505D02*
X192792Y430400D01*
G01X195292Y431478D02*
Y500712D01*
G01X220572Y406198D02*
X195292Y431478D01*
G01X200492Y433374D02*
Y485646D01*
G01X224342Y409524D02*
X200492Y433374D01*
G01X197892Y432438D02*
Y497300D01*
G01X222457Y407873D02*
X197892Y432438D01*
G01X228992Y464000D02*
X224592Y468400D01*
G01X228992Y428237D02*
Y464000D01*
G01X238354Y418875D02*
X228992Y428237D01*
G01X230892Y429901D02*
Y468017D01*
G01X232546Y428247D02*
X230892Y429901D01*
G01X171180Y446179D02*
Y470600D01*
G01X214492Y446700D02*
Y499299D01*
G01X215292Y445900D02*
X214492Y446700D01*
G01X216792Y445900D02*
X215292D01*
G01X217592Y446700D02*
X216792Y445900D01*
G01X217592Y455300D02*
Y446700D01*
G01X218392Y456100D02*
X217592Y455300D01*
G01X219992Y456100D02*
X218392D01*
G01X220792Y455300D02*
X219992Y456100D01*
G01X220792Y437800D02*
Y455300D01*
G01X219592Y436600D02*
X220792Y437800D01*
G01X219592Y435300D02*
Y436600D01*
G01X220792Y434100D02*
X219592Y435300D01*
G01X220792Y429136D02*
Y434100D01*
G01X233192Y416736D02*
X220792Y429136D01*
G01X227092Y463200D02*
X222692Y467600D01*
G01X227092Y459737D02*
Y463200D01*
G01X226532Y459177D02*
X227092Y459737D01*
G01X223452Y459177D02*
X226532D01*
G01X222892Y458617D02*
X223452Y459177D01*
G01X222892Y457177D02*
Y458617D01*
G01X223452Y456617D02*
X222892Y457177D01*
G01X226532Y456617D02*
X223452D01*
G01X227092Y456057D02*
X226532Y456617D01*
G01X227092Y454617D02*
Y456057D01*
G01X226532Y454057D02*
X227092Y454617D01*
G01X223452Y454057D02*
X226532D01*
G01X222892Y453497D02*
X223452Y454057D01*
G01X222892Y452057D02*
Y453497D01*
G01X223452Y451497D02*
X222892Y452057D01*
G01X226532Y451497D02*
X223452D01*
G01X227092Y450937D02*
X226532Y451497D01*
G01X227092Y449497D02*
Y450937D01*
G01X226532Y448937D02*
X227092Y449497D01*
G01X223452Y448937D02*
X226532D01*
G01X222892Y448377D02*
X223452Y448937D01*
G01X222892Y446937D02*
Y448377D01*
G01X223452Y446377D02*
X222892Y446937D01*
G01X226532Y446377D02*
X223452D01*
G01X227092Y445817D02*
X226532Y446377D01*
G01X227092Y444377D02*
Y445817D01*
G01X226532Y443817D02*
X227092Y444377D01*
G01X223452Y443817D02*
X226532D01*
G01X222892Y443257D02*
X223452Y443817D01*
G01X222892Y441817D02*
Y443257D01*
G01X223452Y441257D02*
X222892Y441817D01*
G01X226532Y441257D02*
X223452D01*
G01X227092Y440697D02*
X226532Y441257D01*
G01X227092Y439257D02*
Y440697D01*
G01X226532Y438697D02*
X227092Y439257D01*
G01X223452Y438697D02*
X226532D01*
G01X222892Y438137D02*
X223452Y438697D01*
G01X222892Y436697D02*
Y438137D01*
G01X223452Y436137D02*
X222892Y436697D01*
G01X226532Y436137D02*
X223452D01*
G01X227092Y435577D02*
X226532Y436137D01*
G01X227092Y426437D02*
Y435577D01*
G01X235738Y417791D02*
X227092Y426437D01*
G01X195537Y520554D02*
Y529835D01*
G01X197242Y518849D02*
X195537Y520554D01*
G01X197242Y518157D02*
Y518849D01*
G01X196753Y516976D02*
X197242Y518157D01*
G01X196753Y514587D02*
Y516976D01*
G01X192792Y505023D02*
X196753Y514587D01*
G01X191184Y525788D02*
X192321Y526925D01*
G01X191184Y524712D02*
Y525788D01*
G01X192196Y523700D02*
X191184Y524712D01*
G01X192196Y522500D02*
Y523700D01*
G01X191184Y521488D02*
X192196Y522500D01*
G01X191184Y520412D02*
Y521488D01*
G01X192296Y519300D02*
X191184Y520412D01*
G01X192296Y516667D02*
Y519300D01*
G01X192121Y516492D02*
X192296Y516667D01*
G01X192121Y514800D02*
Y516492D01*
G01X193807Y513114D02*
X192121Y514800D01*
G01X193895Y513114D02*
X193807D01*
G01X197877Y526364D02*
X198914Y527401D01*
G01X197877Y525136D02*
Y526364D01*
G01X198814Y524199D02*
X197877Y525136D01*
G01X198814Y522801D02*
Y524199D01*
G01X197877Y521864D02*
X198814Y522801D01*
G01X197877Y520536D02*
Y521864D01*
G01X199014Y519399D02*
X197877Y520536D01*
G01X199014Y517500D02*
Y519399D01*
G01X198514Y517000D02*
X199014Y517500D01*
G01X198514Y514800D02*
Y517000D01*
G01X200200Y513114D02*
X198514Y514800D01*
G01X200288Y513114D02*
X200200D01*
G01X200288Y507996D02*
Y513114D01*
G01X198684Y506392D02*
X200288Y507996D01*
G01X196052Y506392D02*
X198684D01*
G01X195492Y505832D02*
X196052Y506392D01*
G01X195492Y504392D02*
Y505832D01*
G01X196052Y503832D02*
X195492Y504392D01*
G01X198632Y503832D02*
X196052D01*
G01X199192Y503272D02*
X198632Y503832D01*
G01X199192Y501832D02*
Y503272D01*
G01X198632Y501272D02*
X199192Y501832D01*
G01X195852Y501272D02*
X198632D01*
G01X195292Y500712D02*
X195852Y501272D01*
G01X204570Y526156D02*
X205514Y527100D01*
G01X204570Y524944D02*
Y526156D01*
G01X205414Y524100D02*
X204570Y524944D01*
G01X205414Y522400D02*
Y524100D01*
G01X204570Y521556D02*
X205414Y522400D01*
G01X204570Y520136D02*
Y521556D01*
G01X205714Y518992D02*
X204570Y520136D01*
G01X205714Y517399D02*
Y518992D01*
G01X204807Y516492D02*
X205714Y517399D01*
G01X204807Y514800D02*
Y516492D01*
G01X206493Y513114D02*
X204807Y514800D01*
G01X206581Y513114D02*
X206493D01*
G01X208092Y511603D02*
X206581Y513114D01*
G01X208092Y508000D02*
Y511603D01*
G01X203692Y503600D02*
X208092Y508000D01*
G01X203692Y497900D02*
Y503600D01*
G01X202892Y497100D02*
X203692Y497900D01*
G01X201292Y497100D02*
X202892D01*
G01X200492Y496300D02*
X201292Y497100D01*
G01X200492Y494446D02*
Y496300D01*
G01X201052Y493886D02*
X200492Y494446D01*
G01X204432Y493886D02*
X201052D01*
G01X204992Y493326D02*
X204432Y493886D01*
G01X204992Y491886D02*
Y493326D01*
G01X204432Y491326D02*
X204992Y491886D01*
G01X201052Y491326D02*
X204432D01*
G01X200492Y490766D02*
X201052Y491326D01*
G01X200492Y489326D02*
Y490766D01*
G01X201052Y488766D02*
X200492Y489326D01*
G01X204432Y488766D02*
X201052D01*
G01X204992Y488206D02*
X204432Y488766D01*
G01X204992Y486766D02*
Y488206D01*
G01X204432Y486206D02*
X204992Y486766D01*
G01X201052Y486206D02*
X204432D01*
G01X200492Y485646D02*
X201052Y486206D01*
G01X202230Y519862D02*
Y531515D01*
G01X203935Y518157D02*
X202230Y519862D01*
G01X203733Y518157D02*
X203935D01*
G01X202502Y516926D02*
X203733Y518157D01*
G01X202502Y513990D02*
Y516926D01*
G01X205592Y510900D02*
X202502Y513990D01*
G01X205592Y508700D02*
Y510900D01*
G01X201092Y504200D02*
X205592Y508700D01*
G01X201092Y500500D02*
Y504200D01*
G01X197892Y497300D02*
X201092Y500500D01*
G01X225655Y519862D02*
Y530049D01*
G01X227360Y518157D02*
X225655Y519862D01*
G01X226002Y516799D02*
X227360Y518157D01*
G01X226002Y514307D02*
Y516799D01*
G01X229402Y510907D02*
X226002Y514307D01*
G01X229402Y506610D02*
Y510907D01*
G01X228392Y505600D02*
X229402Y506610D01*
G01X228392Y500400D02*
Y505600D01*
G01X227692Y499700D02*
X228392Y500400D01*
G01X221792Y499700D02*
X227692D01*
G01X219592Y497500D02*
X221792Y499700D01*
G01X219592Y496206D02*
Y497500D01*
G01X220152Y495646D02*
X219592Y496206D01*
G01X223332Y495646D02*
X220152D01*
G01X223892Y495086D02*
X223332Y495646D01*
G01X223892Y493646D02*
Y495086D01*
G01X223332Y493086D02*
X223892Y493646D01*
G01X220152Y493086D02*
X223332D01*
G01X219592Y492526D02*
X220152Y493086D01*
G01X219592Y491086D02*
Y492526D01*
G01X220152Y490526D02*
X219592Y491086D01*
G01X223332Y490526D02*
X220152D01*
G01X223892Y489966D02*
X223332Y490526D01*
G01X223892Y488526D02*
Y489966D01*
G01X223332Y487966D02*
X223892Y488526D01*
G01X220152Y487966D02*
X223332D01*
G01X219592Y487406D02*
X220152Y487966D01*
G01X219592Y485966D02*
Y487406D01*
G01X220152Y485406D02*
X219592Y485966D01*
G01X223332Y485406D02*
X220152D01*
G01X223892Y484846D02*
X223332Y485406D01*
G01X223892Y483406D02*
Y484846D01*
G01X223332Y482846D02*
X223892Y483406D01*
G01X220152Y482846D02*
X223332D01*
G01X219592Y482286D02*
X220152Y482846D01*
G01X219592Y480846D02*
Y482286D01*
G01X220152Y480286D02*
X219592Y480846D01*
G01X223332Y480286D02*
X220152D01*
G01X223892Y479726D02*
X223332Y480286D01*
G01X223892Y478286D02*
Y479726D01*
G01X223332Y477726D02*
X223892Y478286D01*
G01X220152Y477726D02*
X223332D01*
G01X219592Y477166D02*
X220152Y477726D01*
G01X219592Y475700D02*
Y477166D01*
G01X220392Y474900D02*
X219592Y475700D01*
G01X224092Y474900D02*
X220392D01*
G01X224592Y474400D02*
X224092Y474900D01*
G01X224592Y468400D02*
Y474400D01*
G01X188844Y519862D02*
X190549Y518157D01*
G01X188844Y530049D02*
Y519862D01*
G01X182151D02*
X183856Y518157D01*
G01X182151Y530049D02*
Y519862D01*
G01X227995Y525788D02*
X229132Y526925D01*
G01X227995Y524712D02*
Y525788D01*
G01X229007Y523700D02*
X227995Y524712D01*
G01X229007Y522500D02*
Y523700D01*
G01X227995Y521488D02*
X229007Y522500D01*
G01X227995Y520412D02*
Y521488D01*
G01X229107Y519300D02*
X227995Y520412D01*
G01X229107Y516667D02*
Y519300D01*
G01X228932Y516492D02*
X229107Y516667D01*
G01X228932Y514800D02*
Y516492D01*
G01X230618Y513114D02*
X228932Y514800D01*
G01X230706Y513114D02*
X230618D01*
G01X230706Y513166D02*
Y513114D01*
G01X232002Y511870D02*
X230706Y513166D01*
G01X230892Y504100D02*
X232002Y505210D01*
G01X230892Y497297D02*
Y504100D01*
G01X230332Y496737D02*
X230892Y497297D01*
G01X227052Y496737D02*
X230332D01*
G01X226492Y496177D02*
X227052Y496737D01*
G01X226492Y494737D02*
Y496177D01*
G01X227052Y494177D02*
X226492Y494737D01*
G01X230332Y494177D02*
X227052D01*
G01X230892Y493617D02*
X230332Y494177D01*
G01X230892Y492177D02*
Y493617D01*
G01X230332Y491617D02*
X230892Y492177D01*
G01X227052Y491617D02*
X230332D01*
G01X226492Y491057D02*
X227052Y491617D01*
G01X226492Y489617D02*
Y491057D01*
G01X227052Y489057D02*
X226492Y489617D01*
G01X230332Y489057D02*
X227052D01*
G01X230892Y488497D02*
X230332Y489057D01*
G01X230892Y487057D02*
Y488497D01*
G01X230332Y486497D02*
X230892Y487057D01*
G01X227052Y486497D02*
X230332D01*
G01X226492Y485937D02*
X227052Y486497D01*
G01X226492Y484497D02*
Y485937D01*
G01X227052Y483937D02*
X226492Y484497D01*
G01X230332Y483937D02*
X227052D01*
G01X230892Y483377D02*
X230332Y483937D01*
G01X230892Y481937D02*
Y483377D01*
G01X230332Y481377D02*
X230892Y481937D01*
G01X227052Y481377D02*
X230332D01*
G01X226492Y480817D02*
X227052Y481377D01*
G01X226492Y479377D02*
Y480817D01*
G01X227052Y478817D02*
X226492Y479377D01*
G01X230332Y478817D02*
X227052D01*
G01X230892Y478257D02*
X230332Y478817D01*
G01X230892Y476817D02*
Y478257D01*
G01X230332Y476257D02*
X230892Y476817D01*
G01X227052Y476257D02*
X230332D01*
G01X226492Y475697D02*
X227052Y476257D01*
G01X226492Y474257D02*
Y475697D01*
G01X227052Y473697D02*
X226492Y474257D01*
G01X230332Y473697D02*
X227052D01*
G01X230892Y473137D02*
X230332Y473697D01*
G01X230892Y471697D02*
Y473137D01*
G01X230332Y471137D02*
X230892Y471697D01*
G01X227052Y471137D02*
X230332D01*
G01X226492Y470577D02*
X227052Y471137D01*
G01X226492Y469137D02*
Y470577D01*
G01X227052Y468577D02*
X226492Y469137D01*
G01X230332Y468577D02*
X227052D01*
G01X230892Y468017D02*
X230332Y468577D01*
G01X171180Y470600D02*
X170380Y471400D01*
G01X218962Y519866D02*
Y530049D01*
G01X220667Y518161D02*
X218962Y519866D01*
G01X219192Y516686D02*
X220667Y518161D01*
G01X219192Y514467D02*
Y516686D01*
G01X222592Y511067D02*
X219192Y514467D01*
G01X222592Y509200D02*
Y511067D01*
G01X223692Y508100D02*
X222592Y509200D01*
G01X223692Y506300D02*
Y508100D01*
G01X222992Y505600D02*
X223692Y506300D01*
G01X220793Y505600D02*
X222992D01*
G01X214492Y499299D02*
X220793Y505600D01*
G01X187114Y513114D02*
X187202D01*
G01X185428Y514800D02*
X187114Y513114D01*
G01X185428Y516492D02*
Y514800D01*
G01X185603Y516667D02*
X185428Y516492D01*
G01X185603Y519300D02*
Y516667D01*
G01X184491Y520412D02*
X185603Y519300D01*
G01X184491Y521488D02*
Y520412D01*
G01X185503Y522500D02*
X184491Y521488D01*
G01X185503Y523700D02*
Y522500D01*
G01X184491Y524712D02*
X185503Y523700D01*
G01X184491Y525788D02*
Y524712D01*
G01X185628Y526925D02*
X184491Y525788D01*
G01X221302D02*
X222439Y526925D01*
G01X221302Y524712D02*
Y525788D01*
G01X222314Y523700D02*
X221302Y524712D01*
G01X222314Y522500D02*
Y523700D01*
G01X221302Y521488D02*
X222314Y522500D01*
G01X221302Y520412D02*
Y521488D01*
G01X222414Y519300D02*
X221302Y520412D01*
G01X222414Y516667D02*
Y519300D01*
G01X222239Y516492D02*
X222414Y516667D01*
G01X222239Y514800D02*
Y516492D01*
G01X223925Y513114D02*
X222239Y514800D01*
G01X224013Y513114D02*
X223925D01*
G01X225359Y511768D02*
X224013Y513114D01*
G01X225402Y511768D02*
X225359D01*
G01X225402Y509390D02*
Y511768D01*
G01X226592Y508200D02*
X225402Y509390D01*
G01X226592Y506500D02*
Y508200D01*
G01X224742Y504650D02*
X226592Y506500D01*
G01X224742Y502750D02*
Y504650D01*
G01X223892Y501900D02*
X224742Y502750D01*
G01X220692Y501900D02*
X223892D01*
G01X216992Y498200D02*
X220692Y501900D01*
G01X216992Y473500D02*
Y498200D01*
G01X217492Y473000D02*
X216992Y473500D01*
G01X222192Y473000D02*
X217492D01*
G01X222692Y472500D02*
X222192Y473000D01*
G01X222692Y467600D02*
Y472500D01*
G01X199214Y534700D02*
X200202D01*
G01X196159Y531645D02*
X199214Y534700D01*
G01X196159Y530457D02*
Y531645D01*
G01X195537Y529835D02*
X196159Y530457D01*
G01X191621Y528899D02*
X190549D01*
G01X192321Y528199D02*
X191621Y528899D01*
G01X192321Y526925D02*
Y528199D01*
G01X198314Y528899D02*
X197242D01*
G01X198914Y528299D02*
X198314Y528899D01*
G01X198914Y527401D02*
Y528299D01*
G01X204915Y528899D02*
X203935D01*
G01X205514Y528300D02*
X204915Y528899D01*
G01X205514Y527100D02*
Y528300D01*
G01X205415Y534700D02*
X206581D01*
G01X202230Y531515D02*
X205415Y534700D01*
G01X225655Y530049D02*
X230706Y535100D01*
G01X193895D02*
X188844Y530049D01*
G01X187202Y535100D02*
X182151Y530049D01*
G01X228432Y528899D02*
X227360D01*
G01X229132Y528199D02*
X228432Y528899D01*
G01X229132Y526925D02*
Y528199D01*
G01X218962Y530049D02*
X224013Y535100D01*
G01X185628Y528199D02*
Y526925D01*
G01X184928Y528899D02*
X185628Y528199D01*
G01X183856Y528899D02*
X184928D01*
G01X221739D02*
X220667D01*
G01X222439Y528199D02*
X221739Y528899D01*
G01X222439Y526925D02*
Y528199D01*
G01X235066Y91074D02*
X238566Y94574D01*
G01X235066Y89575D02*
Y91074D01*
G01X236927Y87714D02*
X235066Y89575D01*
G01X237099Y87714D02*
X236927D01*
G01X238325Y86488D02*
X237099Y87714D01*
G01X238325Y73475D02*
Y86488D01*
G01X239100Y72700D02*
X238325Y73475D01*
G01X239100Y71076D02*
Y72700D01*
G01X237524Y69500D02*
X239100Y71076D01*
G01X236300Y69500D02*
X237524D01*
G01X234053Y67253D02*
X236300Y69500D01*
G01X234053Y65699D02*
Y67253D01*
G01X232095Y73312D02*
Y86325D01*
G01X232707Y72700D02*
X232095Y73312D01*
G01X232707Y71300D02*
Y72700D01*
G01X279966Y92674D02*
Y101338D01*
G01X278166Y90874D02*
X279966Y92674D01*
G01X278166Y89751D02*
Y90874D01*
G01X280203Y87714D02*
X278166Y89751D01*
G01X281676Y86241D02*
X280203Y87714D01*
G01X281676Y73116D02*
Y86241D01*
G01X282292Y72500D02*
X281676Y73116D01*
G01X282292Y71156D02*
Y72500D01*
G01X280836Y69700D02*
X282292Y71156D01*
G01X279436Y69700D02*
X280836D01*
G01X277557Y67821D02*
X279436Y69700D01*
G01X277557Y65699D02*
Y67821D01*
G01X259350Y73374D02*
X260824Y71900D01*
G01X259350Y74468D02*
Y73374D01*
G01X257917Y75901D02*
X259350Y74468D01*
G01X257917Y77124D02*
Y75901D01*
G01X259417Y78624D02*
X257917Y77124D01*
G01X259417Y79976D02*
Y78624D01*
G01X257917Y81476D02*
X259417Y79976D01*
G01X257917Y82599D02*
Y81476D01*
G01X259592Y84274D02*
X257917Y82599D01*
G01X259592Y85659D02*
Y84274D01*
G01X256550Y88701D02*
X259592Y85659D01*
G01X256550Y91829D02*
Y88701D01*
G01X257478Y92757D02*
X256550Y91829D01*
G01X257478Y94286D02*
Y92757D01*
G01X258434Y95242D02*
X257478Y94286D01*
G01X240746Y92757D02*
Y101718D01*
G01X239625Y91636D02*
X240746Y92757D01*
G01X239625Y88700D02*
Y91636D01*
G01X242525Y85800D02*
X239625Y88700D01*
G01X242525Y83832D02*
Y85800D01*
G01X240992Y82299D02*
X242525Y83832D01*
G01X240992Y81100D02*
Y82299D01*
G01X242242Y79850D02*
X240992Y81100D01*
G01X242242Y78950D02*
Y79850D01*
G01X240892Y77600D02*
X242242Y78950D01*
G01X240892Y76301D02*
Y77600D01*
G01X242525Y74668D02*
X240892Y76301D01*
G01X242525Y72367D02*
Y74668D01*
G01X243392Y71500D02*
X242525Y72367D01*
G01X293036Y91504D02*
X294289Y92757D01*
G01X293036Y89750D02*
Y91504D01*
G01X296036Y86750D02*
X293036Y89750D01*
G01X264171Y92757D02*
Y101737D01*
G01X263050Y91636D02*
X264171Y92757D01*
G01X263050Y88700D02*
Y91636D01*
G01X266392Y85358D02*
X263050Y88700D01*
G01X266392Y84300D02*
Y85358D01*
G01X264592Y82500D02*
X266392Y84300D01*
G01X264592Y80925D02*
Y82500D01*
G01X265792Y79725D02*
X264592Y80925D01*
G01X265792Y78599D02*
Y79725D01*
G01X264592Y77399D02*
X265792Y78599D01*
G01X264592Y76026D02*
Y77399D01*
G01X265950Y74668D02*
X264592Y76026D01*
G01X265950Y73467D02*
Y74668D01*
G01X267517Y71900D02*
X265950Y73467D01*
G01X261216Y93624D02*
Y101588D01*
G01X259016Y91424D02*
X261216Y93624D01*
G01X259016Y89522D02*
Y91424D01*
G01X260824Y87714D02*
X259016Y89522D01*
G01X262213Y86325D02*
X260824Y87714D01*
G01X262213Y73312D02*
Y86325D01*
G01X262825Y72700D02*
X262213Y73312D01*
G01X262825Y71300D02*
Y72700D01*
G01X261025Y69500D02*
X262825Y71300D01*
G01X260025Y69500D02*
X261025D01*
G01X258725Y68200D02*
X260025Y69500D01*
G01X258725Y66946D02*
Y68200D01*
G01X257478Y65699D02*
X258725Y66946D01*
G01X271874Y91032D02*
X275466Y94624D01*
G01X271874Y89566D02*
Y91032D01*
G01X273726Y87714D02*
X271874Y89566D01*
G01X273910Y87714D02*
X273726D01*
G01X275136Y86488D02*
X273910Y87714D01*
G01X275136Y73475D02*
Y86488D01*
G01X275911Y72700D02*
X275136Y73475D01*
G01X275911Y71076D02*
Y72700D01*
G01X274335Y69500D02*
X275911Y71076D01*
G01X273111Y69500D02*
X274335D01*
G01X270864Y67253D02*
X273111Y69500D01*
G01X270864Y65699D02*
Y67253D01*
G01X234053Y92757D02*
X236066Y94770D01*
G01X233125Y91829D02*
X234053Y92757D01*
G01X233125Y88701D02*
Y91829D01*
G01X235925Y85901D02*
X233125Y88701D01*
G01X235925Y84032D02*
Y85901D01*
G01X234542Y82649D02*
X235925Y84032D01*
G01X234542Y81250D02*
Y82649D01*
G01X235992Y79800D02*
X234542Y81250D01*
G01X235992Y78600D02*
Y79800D01*
G01X234492Y77100D02*
X235992Y78600D01*
G01X234492Y75901D02*
Y77100D01*
G01X235925Y74468D02*
X234492Y75901D01*
G01X235925Y72588D02*
Y74468D01*
G01X237013Y71500D02*
X235925Y72588D01*
G01X268766Y94474D02*
Y95365D01*
G01X265684Y91392D02*
X268766Y94474D01*
G01X265684Y89547D02*
Y91392D01*
G01X267517Y87714D02*
X265684Y89547D01*
G01X268906Y86325D02*
X267517Y87714D01*
G01X268906Y73312D02*
Y86325D01*
G01X269518Y72700D02*
X268906Y73312D01*
G01X269518Y71300D02*
Y72700D01*
G01X267718Y69500D02*
X269518Y71300D01*
G01X266718Y69500D02*
X267718D01*
G01X265418Y68200D02*
X266718Y69500D01*
G01X265418Y66946D02*
Y68200D01*
G01X264171Y65699D02*
X265418Y66946D01*
G01X279336Y72367D02*
X280203Y71500D01*
G01X279336Y85800D02*
Y72367D01*
G01X276436Y88700D02*
X279336Y85800D01*
G01X276436Y91636D02*
Y88700D01*
G01X277557Y92757D02*
X276436Y91636D01*
G01X277866Y93066D02*
X277557Y92757D01*
G01X277866Y102196D02*
Y93066D01*
G01X243166Y92674D02*
Y100674D01*
G01X241466Y90974D02*
X243166Y92674D01*
G01X241466Y89640D02*
Y90974D01*
G01X243392Y87714D02*
X241466Y89640D01*
G01X244865Y86241D02*
X243392Y87714D01*
G01X244865Y73116D02*
Y86241D01*
G01X245481Y72500D02*
X244865Y73116D01*
G01X245481Y71156D02*
Y72500D01*
G01X244025Y69700D02*
X245481Y71156D01*
G01X242625Y69700D02*
X244025D01*
G01X240746Y67821D02*
X242625Y69700D01*
G01X240746Y65699D02*
Y67821D01*
G01X269936Y91829D02*
X270864Y92757D01*
G01X269936Y88701D02*
Y91829D01*
G01X272736Y85901D02*
X269936Y88701D01*
G01X272736Y72588D02*
Y85901D01*
G01X273824Y71500D02*
X272736Y72588D01*
G01X270864Y92757D02*
X273584Y95477D01*
G01X238384Y123481D02*
Y168105D01*
G01X239684Y122181D02*
X238384Y123481D01*
G01X239684Y120956D02*
Y122181D01*
G01X238384Y119656D02*
X239684Y120956D01*
G01X238384Y118731D02*
Y119656D01*
G01X239184Y117931D02*
X238384Y118731D01*
G01X239584Y117931D02*
X239184D01*
G01X240292Y117223D02*
X239584Y117931D01*
G01X240292Y115239D02*
Y117223D01*
G01X239784Y114731D02*
X240292Y115239D01*
G01X239184Y114731D02*
X239784D01*
G01X238384Y113931D02*
X239184Y114731D01*
G01X238384Y111656D02*
Y113931D01*
G01X238966Y111074D02*
X238384Y111656D01*
G01X238966Y106574D02*
Y111074D01*
G01X238566Y106174D02*
X238966Y106574D01*
G01X238566Y94574D02*
Y106174D01*
G01X232592Y153782D02*
X231982Y154392D01*
G01X232592Y152392D02*
Y153782D01*
G01X231982Y151782D02*
X232592Y152392D01*
G01Y148562D02*
X231982Y149172D01*
G01X232592Y147172D02*
Y148562D01*
G01X231982Y146562D02*
X232592Y147172D01*
G01X231445Y98000D02*
Y106440D01*
G01X284284Y115991D02*
Y158710D01*
G01X282116Y113823D02*
X284284Y115991D01*
G01X282116Y103488D02*
Y113823D01*
G01X279966Y101338D02*
X282116Y103488D01*
G01X258434Y102406D02*
Y95242D01*
G01X259466Y103438D02*
X258434Y102406D01*
G01X259466Y105174D02*
Y103438D01*
G01X258666Y105974D02*
X259466Y105174D01*
G01X258666Y110774D02*
Y105974D01*
G01X259566Y111674D02*
X258666Y110774D01*
G01X259566Y113156D02*
Y111674D01*
G01X258884Y113838D02*
X259566Y113156D01*
G01X258884Y135308D02*
Y113838D01*
G01X258066Y136126D02*
X258884Y135308D01*
G01X258066Y153140D02*
Y136126D01*
G01X258676Y153750D02*
X258066Y153140D01*
G01X262532Y153750D02*
X258676D01*
G01X263092Y154310D02*
X262532Y153750D01*
G01X263092Y156352D02*
Y154310D01*
G01X240884Y144317D02*
Y164293D01*
G01X242892Y142309D02*
X240884Y144317D01*
G01X242892Y140277D02*
Y142309D01*
G01X242332Y139717D02*
X242892Y140277D01*
G01X241684Y139717D02*
X242332D01*
G01X240884Y138917D02*
X241684Y139717D01*
G01X240884Y137317D02*
Y138917D01*
G01X241684Y136517D02*
X240884Y137317D01*
G01X243266Y136517D02*
X241684D01*
G01X244066Y135717D02*
X243266Y136517D01*
G01X244066Y134117D02*
Y135717D01*
G01X243266Y133317D02*
X244066Y134117D01*
G01X241684Y133317D02*
X243266D01*
G01X240884Y132517D02*
X241684Y133317D01*
G01X240884Y130917D02*
Y132517D01*
G01X241684Y130117D02*
X240884Y130917D01*
G01X243266Y130117D02*
X241684D01*
G01X244066Y129317D02*
X243266Y130117D01*
G01X244066Y127717D02*
Y129317D01*
G01X243266Y126917D02*
X244066Y127717D01*
G01X241684Y126917D02*
X243266D01*
G01X240884Y126117D02*
X241684Y126917D01*
G01X240884Y124517D02*
Y126117D01*
G01X241684Y123717D02*
X240884Y124517D01*
G01X243266Y123717D02*
X241684D01*
G01X244066Y122917D02*
X243266Y123717D01*
G01X244066Y116274D02*
Y122917D01*
G01X242842Y115050D02*
X244066Y116274D01*
G01X242842Y111850D02*
Y115050D01*
G01X241466Y110474D02*
X242842Y111850D01*
G01X241466Y106174D02*
Y110474D01*
G01X242566Y105074D02*
X241466Y106174D01*
G01X242566Y103538D02*
Y105074D01*
G01X240746Y101718D02*
X242566Y103538D01*
G01X270592Y146535D02*
Y166692D01*
G01X269982Y145925D02*
X270592Y146535D01*
G01X264952Y145925D02*
X269982D01*
G01X264342Y145315D02*
X264952Y145925D01*
G01X264342Y143925D02*
Y145315D01*
G01X264952Y143315D02*
X264342Y143925D01*
G01X269982Y143315D02*
X264952D01*
G01X270592Y142705D02*
X269982Y143315D01*
G01X270592Y141315D02*
Y142705D01*
G01X269982Y140705D02*
X270592Y141315D01*
G01X264952Y140705D02*
X269982D01*
G01X264342Y140095D02*
X264952Y140705D01*
G01X264342Y138705D02*
Y140095D01*
G01X264952Y138095D02*
X264342Y138705D01*
G01X266832Y138095D02*
X264952D01*
G01X267392Y137535D02*
X266832Y138095D01*
G01X267392Y135216D02*
Y137535D01*
G01X266832Y134656D02*
X267392Y135216D01*
G01X264984Y134656D02*
X266832D01*
G01X263884Y133556D02*
X264984Y134656D01*
G01X263884Y116438D02*
Y133556D01*
G01X266166Y114156D02*
X263884Y116438D01*
G01X266166Y111474D02*
Y114156D01*
G01X265566Y110874D02*
X266166Y111474D01*
G01X265566Y105974D02*
Y110874D01*
G01X266266Y105274D02*
X265566Y105974D01*
G01X266266Y103832D02*
Y105274D01*
G01X264171Y101737D02*
X266266Y103832D01*
G01X268692Y153000D02*
Y168626D01*
G01X263692Y148000D02*
X268692Y153000D01*
G01X261126Y148000D02*
X263692D01*
G01X260566Y147440D02*
X261126Y148000D01*
G01X260566Y137226D02*
Y147440D01*
G01X261384Y136408D02*
X260566Y137226D01*
G01X261384Y115238D02*
Y136408D01*
G01X262166Y114456D02*
X261384Y115238D01*
G01X262166Y111374D02*
Y114456D01*
G01X262732Y110808D02*
X262166Y111374D01*
G01X262732Y106240D02*
Y110808D01*
G01X261966Y105474D02*
X262732Y106240D01*
G01X261966Y102338D02*
Y105474D01*
G01X261216Y101588D02*
X261966Y102338D01*
G01X278192Y117200D02*
Y161751D01*
G01X275566Y114574D02*
X278192Y117200D01*
G01X275566Y111174D02*
Y114574D01*
G01X275766Y110974D02*
X275566Y111174D01*
G01X275766Y106274D02*
Y110974D01*
G01X275466Y105974D02*
X275766Y106274D01*
G01X275466Y94624D02*
Y105974D01*
G01X235866Y130037D02*
Y169123D01*
G01X235256Y129427D02*
X235866Y130037D01*
G01X234652Y129427D02*
X235256D01*
G01X234092Y128867D02*
X234652Y129427D01*
G01X234092Y127377D02*
Y128867D01*
G01X234652Y126817D02*
X234092Y127377D01*
G01X235256Y126817D02*
X234652D01*
G01X235866Y126207D02*
X235256Y126817D01*
G01X235866Y124817D02*
Y126207D01*
G01X235256Y124207D02*
X235866Y124817D01*
G01X234152Y124207D02*
X235256D01*
G01X233542Y123597D02*
X234152Y124207D01*
G01X233542Y122207D02*
Y123597D01*
G01X234152Y121597D02*
X233542Y122207D01*
G01X235256Y121597D02*
X234152D01*
G01X235866Y120987D02*
X235256Y121597D01*
G01X235866Y119597D02*
Y120987D01*
G01X235256Y118987D02*
X235866Y119597D01*
G01X234152Y118987D02*
X235256D01*
G01X233542Y118377D02*
X234152Y118987D01*
G01X233542Y116987D02*
Y118377D01*
G01X234152Y116377D02*
X233542Y116987D01*
G01X235256Y116377D02*
X234152D01*
G01X235866Y115767D02*
X235256Y116377D01*
G01X235866Y111474D02*
Y115767D01*
G01X235066Y110674D02*
X235866Y111474D01*
G01X235066Y105974D02*
Y110674D01*
G01X236066Y104974D02*
X235066Y105974D01*
G01X236066Y100744D02*
Y104974D01*
G01X235084Y99762D02*
X236066Y100744D01*
G01X235084Y97544D02*
Y99762D01*
G01X236066Y96562D02*
X235084Y97544D01*
G01X236066Y94770D02*
Y96562D01*
G01X272784Y131946D02*
Y165277D01*
G01X272174Y131336D02*
X272784Y131946D01*
G01X267602Y131336D02*
X272174D01*
G01X266992Y130726D02*
X267602Y131336D01*
G01X266992Y129336D02*
Y130726D01*
G01X267602Y128726D02*
X266992Y129336D01*
G01X271232Y128726D02*
X267602D01*
G01X271792Y128166D02*
X271232Y128726D01*
G01X271792Y126260D02*
Y128166D01*
G01X271232Y125700D02*
X271792Y126260D01*
G01X266994Y125700D02*
X271232D01*
G01X266384Y125090D02*
X266994Y125700D01*
G01X266384Y117474D02*
Y125090D01*
G01X268984Y114874D02*
X266384Y117474D01*
G01X268984Y111406D02*
Y114874D01*
G01X269466Y110924D02*
X268984Y111406D01*
G01X269466Y106224D02*
Y110924D01*
G01X268766Y105524D02*
X269466Y106224D01*
G01X268766Y102737D02*
Y105524D01*
G01X266584Y100555D02*
X268766Y102737D01*
G01X266584Y97547D02*
Y100555D01*
G01X268766Y95365D02*
X266584Y97547D01*
G01X279684Y104014D02*
X277866Y102196D01*
G01X279684Y104856D02*
Y104014D01*
G01X278266Y106274D02*
X279684Y104856D01*
G01X278266Y110374D02*
Y106274D01*
G01X279466Y111574D02*
X278266Y110374D01*
G01X279466Y114873D02*
Y111574D01*
G01X280192Y115599D02*
X279466Y114873D01*
G01X280192Y157284D02*
Y115599D01*
G01X243384Y145353D02*
Y162758D01*
G01X246566Y142171D02*
X243384Y145353D01*
G01X246566Y115274D02*
Y142171D01*
G01X245316Y114024D02*
X246566Y115274D01*
G01X245316Y102824D02*
Y114024D01*
G01X243166Y100674D02*
X245316Y102824D01*
G01X275966Y123153D02*
Y162192D01*
G01X275406Y122593D02*
X275966Y123153D01*
G01X271052Y122593D02*
X275406D01*
G01X270492Y122033D02*
X271052Y122593D01*
G01X270492Y119953D02*
Y122033D01*
G01X271052Y119393D02*
X270492Y119953D01*
G01X275086Y119393D02*
X271052D01*
G01X275668Y118811D02*
X275086Y119393D01*
G01X275668Y118277D02*
Y118811D01*
G01X272984Y115593D02*
X275668Y118277D01*
G01X272984Y111892D02*
Y115593D01*
G01X271866Y110774D02*
X272984Y111892D01*
G01X271866Y106574D02*
Y110774D01*
G01X273584Y104856D02*
X271866Y106574D01*
G01X273584Y101564D02*
Y104856D01*
G01X272784Y100764D02*
X273584Y101564D01*
G01X271184Y100764D02*
X272784D01*
G01X270384Y99964D02*
X271184Y100764D01*
G01X270384Y98364D02*
Y99964D01*
G01X271084Y97664D02*
X270384Y98364D01*
G01X272684Y97664D02*
X271084D01*
G01X273584Y96764D02*
X272684Y97664D01*
G01X273584Y95477D02*
Y96764D01*
G01X248292Y186600D02*
X267448Y205756D01*
G01X245092Y186600D02*
X248292D01*
G01X248651Y174300D02*
X271755Y197404D01*
G01X244579Y174300D02*
X248651D01*
G01X238384Y168105D02*
X244579Y174300D01*
G01X247899Y182600D02*
X268612Y203313D01*
G01X244792Y182600D02*
X247899D01*
G01X232592Y164222D02*
X231982Y164832D01*
G01X232592Y162832D02*
Y164222D01*
G01X231982Y162222D02*
X232592Y162832D01*
G01Y159002D02*
X231982Y159612D01*
G01X232592Y157612D02*
Y159002D01*
G01X231982Y157002D02*
X232592Y157612D01*
G01X284284Y158710D02*
X311868Y186294D01*
G01X262532Y156912D02*
X263092Y156352D01*
G01X260202Y156912D02*
X262532D01*
G01X259592Y157522D02*
X260202Y156912D01*
G01X259592Y158912D02*
Y157522D01*
G01X260202Y159522D02*
X259592Y158912D01*
G01X265932Y159522D02*
X260202D01*
G01X266542Y160132D02*
X265932Y159522D01*
G01X266542Y161522D02*
Y160132D01*
G01X265932Y162132D02*
X266542Y161522D01*
G01X262302Y162132D02*
X265932D01*
G01X261692Y162742D02*
X262302Y162132D01*
G01X261692Y164132D02*
Y162742D01*
G01X262302Y164742D02*
X261692Y164132D01*
G01X265932Y164742D02*
X262302D01*
G01X266542Y165352D02*
X265932Y164742D01*
G01X266542Y169857D02*
Y165352D01*
G01X290537Y193852D02*
X266542Y169857D01*
G01X263149Y208243D02*
X264736Y209830D01*
G01X263149Y204357D02*
Y208243D01*
G01X249792Y191000D02*
X263149Y204357D01*
G01X244592Y191000D02*
X249792D01*
G01X248658Y170700D02*
X275061Y197103D01*
G01X247291Y170700D02*
X248658D01*
G01X240884Y164293D02*
X247291Y170700D01*
G01X245622Y196038D02*
X244830D01*
G01X246780Y194880D02*
X245622Y196038D01*
G01X247572Y194880D02*
X246780D01*
G01X248591Y195899D02*
X247572Y194880D01*
G01X248591Y196691D02*
Y195899D01*
G01X247433Y197849D02*
X248591Y196691D01*
G01X247433Y198641D02*
Y197849D01*
G01X250392Y201600D02*
X247433Y198641D01*
G01X252792Y201600D02*
X250392D01*
G01X263572Y212380D02*
X252792Y201600D01*
G01X264608Y212380D02*
X263572D01*
G01X270592Y166692D02*
X293841Y189941D01*
G01X292064Y191998D02*
X292291D01*
G01X268692Y168626D02*
X292064Y191998D01*
G01X278192Y161751D02*
X306768Y190327D01*
G01X248544Y177800D02*
X270723Y199979D01*
G01X244543Y177800D02*
X248544D01*
G01X235866Y169123D02*
X244543Y177800D01*
G01X272784Y165277D02*
X295748Y188241D01*
G01X283944Y161036D02*
X280192Y157284D01*
G01X283944Y161898D02*
Y161036D01*
G01X283048Y162794D02*
X283944Y161898D01*
G01X283048Y163656D02*
Y162794D01*
G01X284449Y165057D02*
X283048Y163656D01*
G01X285311Y165057D02*
X284449D01*
G01X286207Y164161D02*
X285311Y165057D01*
G01X287069Y164161D02*
X286207D01*
G01X288470Y165562D02*
X287069Y164161D01*
G01X288470Y166424D02*
Y165562D01*
G01X287574Y167320D02*
X288470Y166424D01*
G01X287574Y168182D02*
Y167320D01*
G01X288975Y169583D02*
X287574Y168182D01*
G01X289837Y169583D02*
X288975D01*
G01X290733Y168687D02*
X289837Y169583D01*
G01X291595Y168687D02*
X290733D01*
G01X292996Y170088D02*
X291595Y168687D01*
G01X292996Y170950D02*
Y170088D01*
G01X292100Y171846D02*
X292996Y170950D01*
G01X292100Y172708D02*
Y171846D01*
G01X293501Y174109D02*
X292100Y172708D01*
G01X249665Y168100D02*
X278366Y196801D01*
G01X248726Y168100D02*
X249665D01*
G01X243384Y162758D02*
X248726Y168100D01*
G01X275966Y162192D02*
X304218Y190444D01*
G01X247151Y262863D02*
X257892D01*
G01X255295Y232952D02*
X261045D01*
G01X246115Y265363D02*
X257892D01*
G01X257108Y227852D02*
X260840D01*
G01X248187Y260363D02*
X258392D01*
G01X255526Y242659D02*
X258392D01*
G01X254490Y245159D02*
X258392D01*
G01X258094Y225302D02*
X260209D01*
G01X257092Y224300D02*
X258094Y225302D01*
G01X257092Y222000D02*
Y224300D01*
G01X256743Y230402D02*
X260898D01*
G01X249223Y257863D02*
X258392D01*
G01X256562Y240159D02*
X257892D01*
G01X253454Y247659D02*
X258392D01*
G01X259291Y334836D02*
X254482D01*
G01X259124Y330247D02*
X253739D01*
G01X259306Y337336D02*
X254649D01*
G01X259233Y332336D02*
X254316D01*
G01X263236Y357831D02*
X258941D01*
G01X259422Y351460D02*
X256856D01*
G01X263264Y360381D02*
X259057D01*
G01X262499Y365627D02*
X259143D01*
G01X262499Y363076D02*
X259028D01*
G01X254978Y391041D02*
X238354Y407665D01*
G01X256748Y392878D02*
X240874Y408752D01*
G01X259480Y354000D02*
X256983D01*
G01X259334Y349616D02*
X256034D01*
G01X256400Y382405D02*
X233192Y405613D01*
G01X257985Y384308D02*
X235738Y406555D01*
G01X258104Y384308D02*
X257985D01*
G01X259334Y347560D02*
X255424D01*
G01X268813Y457800D02*
Y482621D01*
G01X269313Y457300D02*
X268813Y457800D01*
G01X270992Y457300D02*
X269313D01*
G01X271492Y457800D02*
X270992Y457300D01*
G01X271492Y459400D02*
Y457800D01*
G01X272092Y460000D02*
X271492Y459400D01*
G01X273492Y460000D02*
X272092D01*
G01X274192Y459300D02*
X273492Y460000D01*
G01X274192Y449500D02*
Y459300D01*
G01X274752Y448940D02*
X274192Y449500D01*
G01X276132Y448940D02*
X274752D01*
G01X276692Y448380D02*
X276132Y448940D01*
G01X276692Y446940D02*
Y448380D01*
G01X276132Y446380D02*
X276692Y446940D01*
G01X274752Y446380D02*
X276132D01*
G01X274192Y445820D02*
X274752Y446380D01*
G01X274192Y444380D02*
Y445820D01*
G01X274752Y443820D02*
X274192Y444380D01*
G01X276132Y443820D02*
X274752D01*
G01X276692Y443260D02*
X276132Y443820D01*
G01X276692Y441820D02*
Y443260D01*
G01X276132Y441260D02*
X276692Y441820D01*
G01X274752Y441260D02*
X276132D01*
G01X274192Y440700D02*
X274752Y441260D01*
G01X274192Y439260D02*
Y440700D01*
G01X274752Y438700D02*
X274192Y439260D01*
G01X276132Y438700D02*
X274752D01*
G01X276692Y438140D02*
X276132Y438700D01*
G01X276692Y436700D02*
Y438140D01*
G01X276132Y436140D02*
X276692Y436700D01*
G01X274752Y436140D02*
X276132D01*
G01X274192Y435580D02*
X274752Y436140D01*
G01X274192Y420784D02*
Y435580D01*
G01X280841Y414135D02*
X274192Y420784D01*
G01X238592Y462500D02*
Y477800D01*
G01X236841Y460749D02*
X238592Y462500D01*
G01X236841Y435788D02*
Y460749D01*
G01X247942Y424687D02*
X236841Y435788D01*
G01X247942Y411317D02*
Y424687D01*
G01X255750Y403509D02*
X247942Y411317D01*
G01X241592Y462301D02*
Y480739D01*
G01X238841Y459550D02*
X241592Y462301D01*
G01X238841Y437324D02*
Y459550D01*
G01X250442Y425723D02*
X238841Y437324D01*
G01X250442Y412424D02*
Y425723D01*
G01X257553Y405313D02*
X250442Y412424D01*
G01X243692Y461000D02*
Y488042D01*
G01X240931Y458239D02*
X243692Y461000D01*
G01X240931Y438770D02*
Y458239D01*
G01X252942Y426759D02*
X240931Y438770D01*
G01X252942Y413533D02*
Y426759D01*
G01X259808Y406667D02*
X252942Y413533D01*
G01X262692Y449341D02*
Y494301D01*
G01X263252Y448781D02*
X262692Y449341D01*
G01X268732Y448781D02*
X263252D01*
G01X269292Y448221D02*
X268732Y448781D01*
G01X269292Y446781D02*
Y448221D01*
G01X268732Y446221D02*
X269292Y446781D01*
G01X263252Y446221D02*
X268732D01*
G01X262692Y445661D02*
X263252Y446221D01*
G01X262692Y444221D02*
Y445661D01*
G01X263252Y443661D02*
X262692Y444221D01*
G01X267132Y443661D02*
X263252D01*
G01X267692Y443101D02*
X267132Y443661D01*
G01X267692Y441661D02*
Y443101D01*
G01X267132Y441101D02*
X267692Y441661D01*
G01X263252Y441101D02*
X267132D01*
G01X262692Y440541D02*
X263252Y441101D01*
G01X262692Y438200D02*
Y440541D01*
G01X268492Y432400D02*
X262692Y438200D01*
G01X268492Y419320D02*
Y432400D01*
G01X275722Y412090D02*
X268492Y419320D01*
G01X238354Y407665D02*
Y418875D01*
G01X289192Y436317D02*
Y477195D01*
G01X315668Y409841D02*
X289192Y436317D01*
G01X233408Y428247D02*
X232546D01*
G01X234494Y429334D02*
X233408Y428247D01*
G01X235356Y429334D02*
X234494D01*
G01X236757Y427933D02*
X235356Y429334D01*
G01X236757Y427071D02*
Y427933D01*
G01X235671Y425984D02*
X236757Y427071D01*
G01X235671Y425122D02*
Y425984D01*
G01X237072Y423721D02*
X235671Y425122D01*
G01X237934Y423721D02*
X237072D01*
G01X239020Y424808D02*
X237934Y423721D01*
G01X239882Y424808D02*
X239020D01*
G01X241283Y423407D02*
X239882Y424808D01*
G01X241283Y422545D02*
Y423407D01*
G01X240197Y421458D02*
X241283Y422545D01*
G01X240197Y420596D02*
Y421458D01*
G01X240874Y419919D02*
X240197Y420596D01*
G01X240874Y408752D02*
Y419919D01*
G01X284092Y434274D02*
Y465700D01*
G01X310549Y407817D02*
X284092Y434274D01*
G01X266292Y451500D02*
Y488000D01*
G01X266892Y450900D02*
X266292Y451500D01*
G01X268492Y450900D02*
X266892D01*
G01X269192Y451600D02*
X268492Y450900D01*
G01X269192Y454700D02*
Y451600D01*
G01X269792Y455300D02*
X269192Y454700D01*
G01X270992Y455300D02*
X269792D01*
G01X271592Y454700D02*
X270992Y455300D01*
G01X271592Y419827D02*
Y454700D01*
G01X279063Y412356D02*
X271592Y419827D01*
G01X260192Y437745D02*
Y466700D01*
G01X266392Y431545D02*
X260192Y437745D01*
G01X266392Y417813D02*
Y431545D01*
G01X274044Y410161D02*
X266392Y417813D01*
G01X286592Y435310D02*
Y466600D01*
G01X313099Y408803D02*
X286592Y435310D01*
G01X233192Y405613D02*
Y416736D01*
G01X246392Y457205D02*
Y487900D01*
G01X245782Y456595D02*
X246392Y457205D01*
G01X243602Y456595D02*
X245782D01*
G01X242992Y455985D02*
X243602Y456595D01*
G01X242992Y454005D02*
Y455985D01*
G01X243602Y453395D02*
X242992Y454005D01*
G01X245782Y453395D02*
X243602D01*
G01X246392Y452785D02*
X245782Y453395D01*
G01X246392Y450805D02*
Y452785D01*
G01X245782Y450195D02*
X246392Y450805D01*
G01X243602Y450195D02*
X245782D01*
G01X242992Y449585D02*
X243602Y450195D01*
G01X242992Y447605D02*
Y449585D01*
G01X243602Y446995D02*
X242992Y447605D01*
G01X245782Y446995D02*
X243602D01*
G01X246392Y446385D02*
X245782Y446995D01*
G01X246392Y444405D02*
Y446385D01*
G01X245782Y443795D02*
X246392Y444405D01*
G01X244302Y443795D02*
X245782D01*
G01X243692Y443185D02*
X244302Y443795D01*
G01X243692Y441205D02*
Y443185D01*
G01X244302Y440595D02*
X243692Y441205D01*
G01X245782Y440595D02*
X244302D01*
G01X246392Y439985D02*
X245782Y440595D01*
G01X246392Y436924D02*
Y439985D01*
G01X255498Y427818D02*
X246392Y436924D01*
G01X255498Y414584D02*
Y427818D01*
G01X261660Y408422D02*
X255498Y414584D01*
G01X235738Y406555D02*
Y417791D01*
G01X281492Y433338D02*
Y465400D01*
G01X307971Y406859D02*
X281492Y433338D01*
G01X264806Y525788D02*
X265943Y526925D01*
G01X264806Y524712D02*
Y525788D01*
G01X265818Y523700D02*
X264806Y524712D01*
G01X265818Y522500D02*
Y523700D01*
G01X264806Y521488D02*
X265818Y522500D01*
G01X264806Y520412D02*
Y521488D01*
G01X265918Y519300D02*
X264806Y520412D01*
G01X265918Y516667D02*
Y519300D01*
G01X265743Y516492D02*
X265918Y516667D01*
G01X265743Y514800D02*
Y516492D01*
G01X267429Y513114D02*
X265743Y514800D01*
G01X267517Y513114D02*
X267429D01*
G01X267517Y513166D02*
Y513114D01*
G01X268813Y511870D02*
X267517Y513166D01*
G01X268813Y497752D02*
Y511870D01*
G01X269392Y497173D02*
X268813Y497752D01*
G01X269392Y483200D02*
Y497173D01*
G01X268813Y482621D02*
X269392Y483200D01*
G01X233393Y518157D02*
X234053D01*
G01X232592Y517356D02*
X233393Y518157D01*
G01X232592Y514228D02*
Y517356D01*
G01X235892Y510928D02*
X232592Y514228D01*
G01X235892Y502801D02*
Y510928D01*
G01X235166Y502075D02*
X235892Y502801D01*
G01X235166Y489626D02*
Y502075D01*
G01X235992Y488800D02*
X235166Y489626D01*
G01X235992Y480400D02*
Y488800D01*
G01X238592Y477800D02*
X235992Y480400D01*
G01X232348Y519862D02*
Y529835D01*
G01X234053Y518157D02*
X232348Y519862D01*
G01X234688Y526364D02*
X235725Y527401D01*
G01X234688Y525136D02*
Y526364D01*
G01X235625Y524199D02*
X234688Y525136D01*
G01X235625Y522801D02*
Y524199D01*
G01X234688Y521864D02*
X235625Y522801D01*
G01X234688Y520536D02*
Y521864D01*
G01X235825Y519399D02*
X234688Y520536D01*
G01X235825Y517500D02*
Y519399D01*
G01X235325Y517000D02*
X235825Y517500D01*
G01X235325Y514800D02*
Y517000D01*
G01X237011Y513114D02*
X235325Y514800D01*
G01X237099Y513114D02*
X237011D01*
G01X237979D02*
X237099D01*
G01X238792Y512301D02*
X237979Y513114D01*
G01X238792Y509196D02*
Y512301D01*
G01X237592Y507996D02*
X238792Y509196D01*
G01X237592Y505996D02*
Y507996D01*
G01X238792Y504796D02*
X237592Y505996D01*
G01X238792Y502796D02*
Y504796D01*
G01X237592Y501596D02*
X238792Y502796D01*
G01X237592Y495200D02*
Y501596D01*
G01X238692Y494100D02*
X237592Y495200D01*
G01X238692Y489100D02*
Y494100D01*
G01X241592Y486200D02*
X238692Y489100D01*
G01X241592Y485159D02*
Y486200D01*
G01X240982Y484549D02*
X241592Y485159D01*
G01X238902Y484549D02*
X240982D01*
G01X238292Y483939D02*
X238902Y484549D01*
G01X238292Y481959D02*
Y483939D01*
G01X238902Y481349D02*
X238292Y481959D01*
G01X240982Y481349D02*
X238902D01*
G01X241592Y480739D02*
X240982Y481349D01*
G01X239977Y517388D02*
X240746Y518157D01*
G01X239977Y513543D02*
Y517388D01*
G01X242292Y511228D02*
X239977Y513543D01*
G01X242292Y506600D02*
Y511228D01*
G01X241292Y505600D02*
X242292Y506600D01*
G01X241292Y490442D02*
Y505600D01*
G01X243692Y488042D02*
X241292Y490442D01*
G01X239041Y519862D02*
Y531515D01*
G01X240746Y518157D02*
X239041Y519862D01*
G01X258113Y525788D02*
X259250Y526925D01*
G01X258113Y524712D02*
Y525788D01*
G01X259125Y523700D02*
X258113Y524712D01*
G01X259125Y522500D02*
Y523700D01*
G01X258113Y521488D02*
X259125Y522500D01*
G01X258113Y520412D02*
Y521488D01*
G01X259225Y519300D02*
X258113Y520412D01*
G01X259225Y516667D02*
Y519300D01*
G01X259050Y516492D02*
X259225Y516667D01*
G01X259050Y514800D02*
Y516492D01*
G01X260736Y513114D02*
X259050Y514800D01*
G01X260824Y513114D02*
X260736D01*
G01X262170Y511768D02*
X260824Y513114D01*
G01X262213Y511768D02*
X262170D01*
G01X262213Y507588D02*
Y511768D01*
G01X263013Y506788D02*
X262213Y507588D01*
G01X263292Y506788D02*
X263013D01*
G01X264092Y505988D02*
X263292Y506788D01*
G01X264092Y504388D02*
Y505988D01*
G01X263292Y503588D02*
X264092Y504388D01*
G01X263013Y503588D02*
X263292D01*
G01X262213Y502788D02*
X263013Y503588D01*
G01X262213Y494780D02*
Y502788D01*
G01X262692Y494301D02*
X262213Y494780D01*
G01X282124Y511193D02*
X280203Y513114D01*
G01X282124Y489068D02*
Y511193D01*
G01X282792Y488400D02*
X282124Y489068D01*
G01X282792Y483900D02*
Y488400D01*
G01X283362Y483330D02*
X282792Y483900D01*
G01X285062Y483330D02*
X283362D01*
G01X285892Y482500D02*
X285062Y483330D01*
G01X285892Y481330D02*
Y482500D01*
G01X285282Y480720D02*
X285892Y481330D01*
G01X283412Y480720D02*
X285282D01*
G01X282792Y480100D02*
X283412Y480720D01*
G01X282792Y473199D02*
Y480100D01*
G01X283612Y472379D02*
X282792Y473199D01*
G01X285212Y472379D02*
X283612D01*
G01X286192Y473359D02*
X285212Y472379D01*
G01X286192Y477095D02*
Y473359D01*
G01X286992Y477895D02*
X286192Y477095D01*
G01X288492Y477895D02*
X286992D01*
G01X289192Y477195D02*
X288492Y477895D01*
G01X278192Y526156D02*
X279136Y527100D01*
G01X278192Y524944D02*
Y526156D01*
G01X279036Y524100D02*
X278192Y524944D01*
G01X279036Y522400D02*
Y524100D01*
G01X278192Y521556D02*
X279036Y522400D01*
G01X278192Y520136D02*
Y521556D01*
G01X279336Y518992D02*
X278192Y520136D01*
G01X279336Y517399D02*
Y518992D01*
G01X278429Y516492D02*
X279336Y517399D01*
G01X278429Y514800D02*
Y516492D01*
G01X280115Y513114D02*
X278429Y514800D01*
G01X280203Y513114D02*
X280115D01*
G01X232002Y505210D02*
Y511870D01*
G01X275424Y511600D02*
X273910Y513114D01*
G01X275424Y506732D02*
Y511600D01*
G01X275002Y506310D02*
X275424Y506732D01*
G01X274392Y506310D02*
X275002D01*
G01X273592Y505510D02*
X274392Y506310D01*
G01X273592Y503910D02*
Y505510D01*
G01X274392Y503110D02*
X273592Y503910D01*
G01X274982Y503110D02*
X274392D01*
G01X275792Y502300D02*
X274982Y503110D01*
G01X275792Y495200D02*
Y502300D01*
G01X276492Y494500D02*
X275792Y495200D01*
G01X276492Y483580D02*
Y494500D01*
G01X277092Y482980D02*
X276492Y483580D01*
G01X278133Y482980D02*
X277092D01*
G01X278743Y482370D02*
X278133Y482980D01*
G01X278743Y480980D02*
Y482370D01*
G01X278133Y480370D02*
X278743Y480980D01*
G01X276552Y480370D02*
X278133D01*
G01X275915Y479733D02*
X276552Y480370D01*
G01X275915Y478343D02*
Y479733D01*
G01X276498Y477760D02*
X275915Y478343D01*
G01X278107Y477760D02*
X276498D01*
G01X278770Y477097D02*
X278107Y477760D01*
G01X278770Y475707D02*
Y477097D01*
G01X278213Y475150D02*
X278770Y475707D01*
G01X276524Y475150D02*
X278213D01*
G01X275988Y474614D02*
X276524Y475150D01*
G01X275988Y473804D02*
Y474614D01*
G01X284092Y465700D02*
X275988Y473804D01*
G01X271499Y526364D02*
X272536Y527401D01*
G01X271499Y525136D02*
Y526364D01*
G01X272436Y524199D02*
X271499Y525136D01*
G01X272436Y522801D02*
Y524199D01*
G01X271499Y521864D02*
X272436Y522801D01*
G01X271499Y520536D02*
Y521864D01*
G01X272636Y519399D02*
X271499Y520536D01*
G01X272636Y517500D02*
Y519399D01*
G01X272136Y517000D02*
X272636Y517500D01*
G01X272136Y514800D02*
Y517000D01*
G01X273822Y513114D02*
X272136Y514800D01*
G01X273910Y513114D02*
X273822D01*
G01X262813Y516799D02*
X264171Y518157D01*
G01X262813Y514307D02*
Y516799D01*
G01X266213Y510907D02*
X262813Y514307D01*
G01X266213Y495320D02*
Y510907D01*
G01X265892Y494999D02*
X266213Y495320D01*
G01X265892Y488400D02*
Y494999D01*
G01X266292Y488000D02*
X265892Y488400D01*
G01X262466Y519862D02*
Y530049D01*
G01X264171Y518157D02*
X262466Y519862D01*
G01X256813Y517492D02*
X257478Y518157D01*
G01X256813Y513657D02*
Y517492D01*
G01X259713Y510757D02*
X256813Y513657D01*
G01X259713Y495120D02*
Y510757D01*
G01X257592Y492999D02*
X259713Y495120D01*
G01X257592Y487941D02*
Y492999D01*
G01X258152Y487381D02*
X257592Y487941D01*
G01X259692Y487381D02*
X258152D01*
G01X260192Y486881D02*
X259692Y487381D01*
G01X260192Y485481D02*
Y486881D01*
G01X259532Y484821D02*
X260192Y485481D01*
G01X258152Y484821D02*
X259532D01*
G01X257592Y484261D02*
X258152Y484821D01*
G01X257592Y482821D02*
Y484261D01*
G01X258152Y482261D02*
X257592Y482821D01*
G01X259692Y482261D02*
X258152D01*
G01X260192Y481761D02*
X259692Y482261D01*
G01X260192Y480361D02*
Y481761D01*
G01X259532Y479701D02*
X260192Y480361D01*
G01X258392Y479701D02*
X259532D01*
G01X257592Y478901D02*
X258392Y479701D01*
G01X257592Y469300D02*
Y478901D01*
G01X260192Y466700D02*
X257592Y469300D01*
G01X255773Y519862D02*
Y530049D01*
G01X257478Y518157D02*
X255773Y519862D01*
G01X276124Y516724D02*
X277557Y518157D01*
G01X276124Y514207D02*
Y516724D01*
G01X279474Y510857D02*
X276124Y514207D01*
G01X279474Y507398D02*
Y510857D01*
G01X278674Y506598D02*
X279474Y507398D01*
G01X278392Y506598D02*
X278674D01*
G01X277592Y505798D02*
X278392Y506598D01*
G01X277592Y504198D02*
Y505798D01*
G01X278392Y503398D02*
X277592Y504198D01*
G01X278674Y503398D02*
X278392D01*
G01X279474Y502598D02*
X278674Y503398D01*
G01X279474Y494982D02*
Y502598D01*
G01X278366Y493874D02*
X279474Y494982D01*
G01X278366Y489126D02*
Y493874D01*
G01X280708Y486784D02*
X278366Y489126D01*
G01X280708Y472484D02*
Y486784D01*
G01X286592Y466600D02*
X280708Y472484D01*
G01X275852Y519862D02*
Y531515D01*
G01X277557Y518157D02*
X275852Y519862D01*
G01X241381Y526156D02*
X242325Y527100D01*
G01X241381Y524944D02*
Y526156D01*
G01X242225Y524100D02*
X241381Y524944D01*
G01X242225Y522400D02*
Y524100D01*
G01X241381Y521556D02*
X242225Y522400D01*
G01X241381Y520136D02*
Y521556D01*
G01X242525Y518992D02*
X241381Y520136D01*
G01X242525Y517399D02*
Y518992D01*
G01X241618Y516492D02*
X242525Y517399D01*
G01X241618Y514800D02*
Y516492D01*
G01X243304Y513114D02*
X241618Y514800D01*
G01X243392Y513114D02*
X243304D01*
G01X245366Y511140D02*
X243392Y513114D01*
G01X245366Y488926D02*
Y511140D01*
G01X246392Y487900D02*
X245366Y488926D01*
G01X269624Y516917D02*
X270864Y518157D01*
G01X269624Y514007D02*
Y516917D01*
G01X272774Y510857D02*
X269624Y514007D01*
G01X272774Y508982D02*
Y510857D01*
G01X271692Y507900D02*
X272774Y508982D01*
G01X271692Y503500D02*
Y507900D01*
G01X272792Y502400D02*
X271692Y503500D01*
G01X272792Y495200D02*
Y502400D01*
G01X271966Y494374D02*
X272792Y495200D01*
G01X271966Y490726D02*
Y494374D01*
G01X273992Y488700D02*
X271966Y490726D01*
G01X273992Y465700D02*
Y488700D01*
G01X274592Y465100D02*
X273992Y465700D01*
G01X275992Y465100D02*
X274592D01*
G01X276592Y465700D02*
X275992Y465100D01*
G01X276592Y467100D02*
Y465700D01*
G01X277292Y467800D02*
X276592Y467100D01*
G01X279092Y467800D02*
X277292D01*
G01X281492Y465400D02*
X279092Y467800D01*
G01X269159Y519862D02*
Y529835D01*
G01X270864Y518157D02*
X269159Y519862D01*
G01X292584D02*
Y530049D01*
G01X294289Y518157D02*
X292584Y519862D01*
G01X265243Y528899D02*
X264171D01*
G01X265943Y528199D02*
X265243Y528899D01*
G01X265943Y526925D02*
Y528199D01*
G01X236025Y534700D02*
X237013D01*
G01X232970Y531645D02*
X236025Y534700D01*
G01X232970Y530457D02*
Y531645D01*
G01X232348Y529835D02*
X232970Y530457D01*
G01X235125Y528899D02*
X234053D01*
G01X235725Y528299D02*
X235125Y528899D01*
G01X235725Y527401D02*
Y528299D01*
G01X242226Y534700D02*
X243392D01*
G01X239041Y531515D02*
X242226Y534700D01*
G01X258550Y528899D02*
X257478D01*
G01X259250Y528199D02*
X258550Y528899D01*
G01X259250Y526925D02*
Y528199D01*
G01X278537Y528899D02*
X277557D01*
G01X279136Y528300D02*
X278537Y528899D01*
G01X279136Y527100D02*
Y528300D01*
G01X271936Y528899D02*
X270864D01*
G01X272536Y528299D02*
X271936Y528899D01*
G01X272536Y527401D02*
Y528299D01*
G01X262466Y530049D02*
X267517Y535100D01*
G01X255773Y530049D02*
X260824Y535100D01*
G01X279037Y534700D02*
X280203D01*
G01X275852Y531515D02*
X279037Y534700D01*
G01X241726Y528899D02*
X240746D01*
G01X242325Y528300D02*
X241726Y528899D01*
G01X242325Y527100D02*
Y528300D01*
G01X272836Y534700D02*
X273824D01*
G01X269781Y531645D02*
X272836Y534700D01*
G01X269781Y530457D02*
Y531645D01*
G01X269159Y529835D02*
X269781Y530457D01*
G01X292584Y530049D02*
X297635Y535100D01*
G01X329752Y22402D02*
X324407Y17057D01*
G01X329752Y26259D02*
Y22402D01*
G01X329492Y26519D02*
X329752Y26259D01*
G01X329492Y28725D02*
Y26519D01*
G01X330252Y29485D02*
X329492Y28725D01*
G01X330252Y31159D02*
Y29485D01*
G01X328833Y32578D02*
X330252Y31159D01*
G01X328833Y34240D02*
Y32578D01*
G01X324407Y-7785D02*
Y-9901D01*
G01X329986Y-2206D02*
X324407Y-7785D01*
G01X329986Y4114D02*
Y-2206D01*
G01X329392Y4708D02*
X329986Y4114D01*
G01X329392Y12072D02*
Y4708D01*
G01X324407Y17057D02*
X329392Y12072D01*
G01X322692Y14176D02*
X327754Y9114D01*
G01X322692Y18829D02*
Y14176D01*
G01X326049Y22186D02*
X322692Y18829D01*
G01X326049Y29262D02*
Y22186D01*
G01X325592Y29719D02*
X326049Y29262D01*
G01X325592Y32199D02*
Y29719D01*
G01X326102Y32709D02*
X325592Y32199D01*
G01X326102Y53724D02*
Y32709D01*
G01X327754Y238D02*
Y-1743D01*
G01X327192Y800D02*
X327754Y238D01*
G01X327192Y8552D02*
Y800D01*
G01X327754Y9114D02*
X327192Y8552D01*
G01X321061Y16169D02*
Y17057D01*
G01X319356Y14464D02*
X321061Y16169D01*
G01X319356Y5788D02*
Y14464D01*
G01X319966Y5178D02*
X319356Y5788D01*
G01X321017Y5178D02*
X319966D01*
G01X321627Y4568D02*
X321017Y5178D01*
G01X321627Y2668D02*
Y4568D01*
G01X321017Y2058D02*
X321627Y2668D01*
G01X319966Y2058D02*
X321017D01*
G01X319356Y1448D02*
X319966Y2058D01*
G01X319356Y-2964D02*
Y1448D01*
G01X321061Y-4669D02*
X319356Y-2964D01*
G01X321061Y-7108D02*
Y-4669D01*
G01X323452Y29759D02*
Y34239D01*
G01X322692Y28999D02*
X323452Y29759D01*
G01X322692Y26100D02*
Y28999D01*
G01X321061Y24469D02*
X322692Y26100D01*
G01X321061Y17057D02*
Y24469D01*
G01X314368Y-4724D02*
Y-7108D01*
G01X316105Y-2987D02*
X314368Y-4724D01*
G01X316105Y10940D02*
Y-2987D01*
G01X315992Y11053D02*
X316105Y10940D01*
G01X315992Y17799D02*
Y11053D01*
G01X318400Y20207D02*
X315992Y17799D01*
G01X318400Y25393D02*
Y20207D01*
G01X319446Y26439D02*
X318400Y25393D01*
G01X319446Y29379D02*
Y26439D01*
G01X318866Y29959D02*
X319446Y29379D01*
G01X318866Y34207D02*
Y29959D01*
G01X344486Y19806D02*
Y17057D01*
G01X339535Y24757D02*
X344486Y19806D01*
G01X339535Y31682D02*
Y24757D01*
G01X339398Y31819D02*
X339535Y31682D01*
G01X339398Y43549D02*
Y31819D01*
G01X342666Y-5392D02*
X344486Y-9786D01*
G01X342666Y-3426D02*
Y-5392D01*
G01X342992Y-3100D02*
X342666Y-3426D01*
G01X342992Y-1080D02*
Y-3100D01*
G01X342123Y-211D02*
X342992Y-1080D01*
G01X342123Y7491D02*
Y-211D01*
G01X342863Y8231D02*
X342123Y7491D01*
G01X342863Y13138D02*
Y8231D01*
G01X344486Y17057D02*
X342863Y13138D01*
G01X354679Y8968D02*
X354525Y9122D01*
G01X354679Y-1588D02*
Y8968D01*
G01X354525Y-1742D02*
X354679Y-1588D01*
G01X354525Y9122D02*
X354892Y9489D01*
G01X347833Y-1743D02*
Y9122D01*
G01X346092Y24400D02*
Y34545D01*
G01X349538Y20954D02*
X346092Y24400D01*
G01X349538Y13505D02*
Y20954D01*
G01X347833Y11800D02*
X349538Y13505D01*
G01X347833Y9122D02*
Y11800D01*
G01X344486Y11982D02*
Y9122D01*
G01X346121Y13617D02*
X344486Y11982D01*
G01X346121Y21171D02*
Y13617D01*
G01X342881Y24411D02*
X346121Y21171D01*
G01X342881Y50631D02*
Y24411D01*
G01X345592Y-5642D02*
X344486Y-4536D01*
G01X346425Y-5642D02*
X345592D01*
G01X347249Y-4818D02*
X346425Y-5642D01*
G01X347249Y-3823D02*
Y-4818D01*
G01X346108Y-2682D02*
X347249Y-3823D01*
G01X346108Y-632D02*
Y-2682D01*
G01X345387Y89D02*
X346108Y-632D01*
G01X344400Y89D02*
X345387D01*
G01X343751Y738D02*
X344400Y89D01*
G01X343751Y1728D02*
Y738D01*
G01X344322Y2299D02*
X343751Y1728D01*
G01X345460Y2299D02*
X344322D01*
G01X346070Y2909D02*
X345460Y2299D01*
G01X346070Y3899D02*
Y2909D01*
G01X345460Y4509D02*
X346070Y3899D01*
G01X344335Y4509D02*
X345460D01*
G01X343752Y5092D02*
X344335Y4509D01*
G01X343752Y6082D02*
Y5092D01*
G01X344389Y6719D02*
X343752Y6082D01*
G01X345223Y6719D02*
X344389D01*
G01X345833Y7329D02*
X345223Y6719D01*
G01X345833Y8621D02*
Y7329D01*
G01X345332Y9122D02*
X345833Y8621D01*
G01X344486Y9122D02*
X345332D01*
G01X311021Y2071D02*
Y-4536D01*
G01X309392Y3700D02*
X311021Y2071D01*
G01X309392Y10474D02*
Y3700D01*
G01X309992Y11074D02*
X309392Y10474D01*
G01X309992Y14300D02*
Y11074D01*
G01X309292Y15000D02*
X309992Y14300D01*
G01X309292Y28985D02*
Y15000D01*
G01X310066Y29759D02*
X309292Y28985D01*
G01X310066Y32727D02*
Y29759D01*
G01X309380Y33413D02*
X310066Y32727D01*
G01X341140Y20153D02*
Y17057D01*
G01X336088Y25205D02*
X341140Y20153D01*
G01X336088Y29009D02*
Y25205D01*
G01X336838Y29759D02*
X336088Y29009D01*
G01X336838Y31459D02*
Y29759D01*
G01X336092Y32205D02*
X336838Y31459D01*
G01X336092Y48200D02*
Y32205D01*
G01X339942Y-5910D02*
X341140Y-7108D01*
G01X339942Y-3750D02*
Y-5910D01*
G01X339340Y-3148D02*
X339942Y-3750D01*
G01X339340Y-952D02*
Y-3148D01*
G01X339892Y-400D02*
X339340Y-952D01*
G01X339892Y6100D02*
Y-400D01*
G01X339435Y6557D02*
X339892Y6100D01*
G01X339435Y15352D02*
Y6557D01*
G01X341140Y17057D02*
X339435Y15352D01*
G01X336052Y10855D02*
X337793Y9114D01*
G01X336052Y18640D02*
Y10855D01*
G01X332792Y21900D02*
X336052Y18640D01*
G01X332792Y29419D02*
Y21900D01*
G01X332446Y29765D02*
X332792Y29419D01*
G01X332446Y33461D02*
Y29765D01*
G01X337029Y-5300D02*
X337793Y-4536D01*
G01X336092Y-5300D02*
X337029D01*
G01X335492Y-4700D02*
X336092Y-5300D01*
G01X335492Y-3244D02*
Y-4700D01*
G01X337092Y-1644D02*
X335492Y-3244D01*
G01X337092Y-385D02*
Y-1644D01*
G01X337793Y316D02*
X337092Y-385D01*
G01X337793Y2518D02*
Y316D01*
G01X337183Y3128D02*
X337793Y2518D01*
G01X333511Y3128D02*
X337183D01*
G01X332901Y3738D02*
X333511Y3128D01*
G01X332901Y5638D02*
Y3738D01*
G01X333511Y6248D02*
X332901Y5638D01*
G01X337183Y6248D02*
X333511D01*
G01X337793Y6858D02*
X337183Y6248D01*
G01X337793Y9114D02*
Y6858D01*
G01X312726Y10819D02*
X311021Y9114D01*
G01X312726Y29916D02*
Y10819D01*
G01X312642Y30000D02*
X312726Y29916D01*
G01X312642Y48589D02*
Y30000D01*
G01X354526Y-4734D02*
Y-7108D01*
G01X352692Y-2900D02*
X354526Y-4734D01*
G01X352692Y3200D02*
Y-2900D01*
G01X352920Y3428D02*
X352692Y3200D01*
G01X352920Y15451D02*
Y3428D01*
G01X354526Y17057D02*
X352920Y15451D01*
G01X354526Y25166D02*
Y17057D01*
G01X352892Y26800D02*
X354526Y25166D01*
G01X352892Y48306D02*
Y26800D01*
G01X314373Y17062D02*
X314368Y17057D01*
G01X314373Y18481D02*
Y17062D01*
G01X316009Y20117D02*
X314373Y18481D01*
G01X316009Y29302D02*
Y20117D01*
G01X316366Y29659D02*
X316009Y29302D01*
G01X316366Y31659D02*
Y29659D01*
G01X315766Y32259D02*
X316366Y31659D01*
G01X315766Y34559D02*
Y32259D01*
G01X351164Y-9895D02*
X351179Y-9901D01*
G01X349451Y-5759D02*
X351164Y-9895D01*
G01X349451Y-3552D02*
Y-5759D01*
G01X350392Y-1280D02*
X349451Y-3552D01*
G01X350392Y6400D02*
Y-1280D01*
G01X349464Y7328D02*
X350392Y6400D01*
G01X349464Y10173D02*
Y7328D01*
G01X351179Y11888D02*
X349464Y10173D01*
G01X351179Y17057D02*
Y11888D01*
G01X351692Y17570D02*
X351179Y17057D01*
G01X351692Y22800D02*
Y17570D01*
G01X349574Y24918D02*
X351692Y22800D01*
G01X349574Y30067D02*
Y24918D01*
G01X350297Y30790D02*
X349574Y30067D01*
G01X350297Y34130D02*
Y30790D01*
G01X329372Y34779D02*
X328833Y34240D01*
G01X329372Y48094D02*
Y34779D01*
G01X329987Y48709D02*
X329372Y48094D01*
G01X329987Y50139D02*
Y48709D01*
G01X328774Y51352D02*
X329987Y50139D01*
G01X328774Y52896D02*
Y51352D01*
G01X329492Y53614D02*
X328774Y52896D01*
G01X329492Y66617D02*
Y53614D01*
G01X330095Y67220D02*
X329492Y66617D01*
G01X330095Y69116D02*
Y67220D01*
G01X328821Y70390D02*
X330095Y69116D01*
G01X328821Y72388D02*
Y70390D01*
G01X329382Y72949D02*
X328821Y72388D01*
G01X329382Y75129D02*
Y72949D01*
G01X329152Y75359D02*
X329382Y75129D01*
G01X329152Y85674D02*
Y75359D01*
G01X330035Y86557D02*
X329152Y85674D01*
G01X330035Y88247D02*
Y86557D01*
G01X329052Y89230D02*
X330035Y88247D01*
G01X329052Y90974D02*
Y89230D01*
G01X329752Y91674D02*
X329052Y90974D01*
G01X329752Y97560D02*
Y91674D01*
G01X326022Y53804D02*
X326102Y53724D01*
G01X326022Y67089D02*
Y53804D01*
G01X325752Y67359D02*
X326022Y67089D01*
G01X325752Y69359D02*
Y67359D01*
G01X326352Y69959D02*
X325752Y69359D01*
G01X326352Y72459D02*
Y69959D01*
G01X326106Y72705D02*
X326352Y72459D01*
G01X326106Y81384D02*
Y72705D01*
G01X326352Y81630D02*
X326106Y81384D01*
G01X326352Y85874D02*
Y81630D01*
G01X325852Y86374D02*
X326352Y85874D01*
G01X325852Y88274D02*
Y86374D01*
G01X326552Y88974D02*
X325852Y88274D01*
G01X326552Y91074D02*
Y88974D01*
G01X325821Y91805D02*
X326552Y91074D01*
G01X325821Y96129D02*
Y91805D01*
G01X322892Y91714D02*
Y95800D01*
G01X322607Y91429D02*
X322892Y91714D01*
G01X322607Y89069D02*
Y91429D01*
G01X322861Y88815D02*
X322607Y89069D01*
G01X322861Y85883D02*
Y88815D01*
G01X322452Y85474D02*
X322861Y85883D01*
G01X322452Y75859D02*
Y85474D01*
G01X322788Y75523D02*
X322452Y75859D01*
G01X322788Y72695D02*
Y75523D01*
G01X323092Y72391D02*
X322788Y72695D01*
G01X323092Y67199D02*
Y72391D01*
G01X322772Y66879D02*
X323092Y67199D01*
G01X322772Y51820D02*
Y66879D01*
G01X323452Y51140D02*
X322772Y51820D01*
G01X323452Y48674D02*
Y51140D01*
G01X322792Y48014D02*
X323452Y48674D01*
G01X322792Y34899D02*
Y48014D01*
G01X323452Y34239D02*
X322792Y34899D01*
G01X303784Y93756D02*
Y97092D01*
G01X306266Y91274D02*
X303784Y93756D01*
G01X306266Y89652D02*
Y91274D01*
G01X304328Y87714D02*
X306266Y89652D01*
G01X305717Y86325D02*
X304328Y87714D01*
G01X305717Y72976D02*
Y86325D01*
G01X306329Y72364D02*
X305717Y72976D01*
G01X306329Y71300D02*
Y72364D01*
G01X304529Y69500D02*
X306329Y71300D01*
G01X303529Y69500D02*
X304529D01*
G01X302229Y68200D02*
X303529Y69500D01*
G01X302229Y66946D02*
Y68200D01*
G01X300982Y65699D02*
X302229Y66946D01*
G01X319342Y34683D02*
X318866Y34207D01*
G01X319342Y52910D02*
Y34683D01*
G01X319456Y53024D02*
X319342Y52910D01*
G01X319456Y67169D02*
Y53024D01*
G01X319092Y67533D02*
X319456Y67169D01*
G01X319092Y69385D02*
Y67533D01*
G01X319331Y69624D02*
X319092Y69385D01*
G01X319331Y83439D02*
Y69624D01*
G01X319666Y83774D02*
X319331Y83439D01*
G01X319666Y85574D02*
Y83774D01*
G01X319066Y86174D02*
X319666Y85574D01*
G01X319066Y88374D02*
Y86174D01*
G01X319666Y88974D02*
X319066Y88374D01*
G01X319666Y90974D02*
Y88974D01*
G01X318492Y92148D02*
X319666Y90974D01*
G01X318492Y97100D02*
Y92148D01*
G01X339402Y43553D02*
X339398Y43549D01*
G01X339402Y50638D02*
Y43553D01*
G01X339512Y50748D02*
X339402Y50638D01*
G01X339512Y69852D02*
Y50748D01*
G01X339405Y69959D02*
X339512Y69852D01*
G01X339405Y81297D02*
Y69959D01*
G01X339738Y81630D02*
X339405Y81297D01*
G01X339738Y85874D02*
Y81630D01*
G01X339238Y86374D02*
X339738Y85874D01*
G01X339238Y88274D02*
Y86374D01*
G01X339938Y88974D02*
X339238Y88274D01*
G01X339938Y91074D02*
Y88974D01*
G01X339207Y91805D02*
X339938Y91074D01*
G01X339207Y97827D02*
Y91805D01*
G01X300982Y92757D02*
Y100290D01*
G01X299736Y91511D02*
X300982Y92757D01*
G01X299736Y89299D02*
Y91511D01*
G01X302729Y86306D02*
X299736Y89299D01*
G01X302729Y73499D02*
Y86306D01*
G01X304328Y71900D02*
X302729Y73499D01*
G01X345652Y91760D02*
Y96092D01*
G01X346438Y90974D02*
X345652Y91760D01*
G01X346438Y88974D02*
Y90974D01*
G01X345838Y88374D02*
X346438Y88974D01*
G01X345838Y86174D02*
Y88374D01*
G01X346438Y85574D02*
X345838Y86174D01*
G01X346438Y83774D02*
Y85574D01*
G01X346190Y83526D02*
X346438Y83774D01*
G01X346190Y72407D02*
Y83526D01*
G01X346438Y72159D02*
X346190Y72407D01*
G01X346438Y69959D02*
Y72159D01*
G01X345638Y69159D02*
X346438Y69959D01*
G01X345638Y67759D02*
Y69159D01*
G01X346102Y67295D02*
X345638Y67759D01*
G01X346102Y63749D02*
Y67295D01*
G01X347093Y62758D02*
X346102Y63749D01*
G01X347093Y60629D02*
Y62758D01*
G01X346102Y59638D02*
X347093Y60629D01*
G01X346102Y48110D02*
Y59638D01*
G01X346172Y48040D02*
X346102Y48110D01*
G01X346172Y34625D02*
Y48040D01*
G01X346092Y34545D02*
X346172Y34625D01*
G01X298584Y94092D02*
Y103192D01*
G01X295792Y91300D02*
X298584Y94092D01*
G01X295792Y89557D02*
Y91300D01*
G01X297635Y87714D02*
X295792Y89557D01*
G01X299024Y86325D02*
X297635Y87714D01*
G01X299024Y73312D02*
Y86325D01*
G01X299636Y72700D02*
X299024Y73312D01*
G01X299636Y71300D02*
Y72700D01*
G01X297836Y69500D02*
X299636Y71300D01*
G01X296836Y69500D02*
X297836D01*
G01X295536Y68200D02*
X296836Y69500D01*
G01X295536Y66946D02*
Y68200D01*
G01X294289Y65699D02*
X295536Y66946D01*
G01X294289Y92761D02*
X296184Y94656D01*
G01X294289Y92757D02*
Y92761D01*
G01X296036Y73499D02*
Y86750D01*
G01X297635Y71900D02*
X296036Y73499D01*
G01X342822Y50690D02*
X342881Y50631D01*
G01X342822Y72643D02*
Y50690D01*
G01X342862Y72683D02*
X342822Y72643D01*
G01X342862Y75035D02*
Y72683D01*
G01X342538Y75359D02*
X342862Y75035D01*
G01X342538Y85674D02*
Y75359D01*
G01X343138Y86274D02*
X342538Y85674D01*
G01X343138Y88174D02*
Y86274D01*
G01X342438Y88874D02*
X343138Y88174D01*
G01X342438Y90974D02*
Y88874D01*
G01X343138Y91674D02*
X342438Y90974D01*
G01X343138Y98929D02*
Y91674D01*
G01X309380Y48960D02*
Y33413D01*
G01X309992Y49572D02*
X309380Y48960D01*
G01X309992Y51531D02*
Y49572D01*
G01X309316Y52207D02*
X309992Y51531D01*
G01X309316Y66809D02*
Y52207D01*
G01X310066Y67559D02*
X309316Y66809D01*
G01X310066Y78859D02*
Y67559D01*
G01X309066Y79859D02*
X310066Y78859D01*
G01X309066Y85474D02*
Y79859D01*
G01X310066Y86474D02*
X309066Y85474D01*
G01X310066Y88224D02*
Y86474D01*
G01X309066Y89224D02*
X310066Y88224D01*
G01X309066Y91274D02*
Y89224D01*
G01X310066Y92274D02*
X309066Y91274D01*
G01X310066Y97674D02*
Y92274D01*
G01X336072Y48220D02*
X336092Y48200D01*
G01X336072Y66793D02*
Y48220D01*
G01X336130Y66851D02*
X336072Y66793D01*
G01X336130Y75567D02*
Y66851D01*
G01X335838Y75859D02*
X336130Y75567D01*
G01X335838Y85156D02*
Y75859D01*
G01X336563Y85881D02*
X335838Y85156D01*
G01X336563Y88531D02*
Y85881D01*
G01X335838Y89256D02*
X336563Y88531D01*
G01X335838Y91274D02*
Y89256D01*
G01X336366Y91802D02*
X335838Y91274D01*
G01X336366Y97815D02*
Y91802D01*
G01X332842Y33857D02*
X332446Y33461D01*
G01X332842Y37949D02*
Y33857D01*
G01X332452Y38339D02*
X332842Y37949D01*
G01X332452Y45374D02*
Y38339D01*
G01X332812Y45734D02*
X332452Y45374D01*
G01X332812Y49100D02*
Y45734D01*
G01X332310Y49602D02*
X332812Y49100D01*
G01X332310Y52298D02*
Y49602D01*
G01X332812Y52800D02*
X332310Y52298D01*
G01X332812Y67199D02*
Y52800D01*
G01X332485Y67526D02*
X332812Y67199D01*
G01X332485Y72084D02*
Y67526D01*
G01X332806Y72405D02*
X332485Y72084D01*
G01X332806Y83528D02*
Y72405D01*
G01X333052Y83774D02*
X332806Y83528D01*
G01X333052Y85574D02*
Y83774D01*
G01X332452Y86174D02*
X333052Y85574D01*
G01X332452Y88374D02*
Y86174D01*
G01X333052Y88974D02*
X332452Y88374D01*
G01X333052Y90974D02*
Y88974D01*
G01X332452Y91574D02*
X333052Y90974D01*
G01X332452Y97461D02*
Y91574D01*
G01X312763Y48710D02*
X312642Y48589D01*
G01X312763Y66962D02*
Y48710D01*
G01X312366Y67359D02*
X312763Y66962D01*
G01X312366Y69359D02*
Y67359D01*
G01X312966Y69959D02*
X312366Y69359D01*
G01X312966Y72459D02*
Y69959D01*
G01X312688Y72737D02*
X312966Y72459D01*
G01X312688Y76117D02*
Y72737D01*
G01X312966Y76395D02*
X312688Y76117D01*
G01X312966Y85874D02*
Y76395D01*
G01X312466Y86374D02*
X312966Y85874D01*
G01X312466Y88274D02*
Y86374D01*
G01X313166Y88974D02*
X312466Y88274D01*
G01X313166Y91074D02*
Y88974D01*
G01X312435Y91805D02*
X313166Y91074D01*
G01X312435Y97043D02*
Y91805D01*
G01X352822Y48376D02*
X352892Y48306D01*
G01X352822Y69657D02*
Y48376D01*
G01X352911Y69746D02*
X352822Y69657D01*
G01X352911Y86087D02*
Y69746D01*
G01X352624Y86374D02*
X352911Y86087D01*
G01X352624Y88274D02*
Y86374D01*
G01X353324Y88974D02*
X352624Y88274D01*
G01X353324Y91074D02*
Y88974D01*
G01X352593Y91805D02*
X353324Y91074D01*
G01X352593Y95731D02*
Y91805D01*
G01X316092Y34885D02*
X315766Y34559D01*
G01X316092Y48860D02*
Y34885D01*
G01X315992Y48960D02*
X316092Y48860D01*
G01X315992Y67085D02*
Y48960D01*
G01X316366Y67459D02*
X315992Y67085D01*
G01X316366Y69459D02*
Y67459D01*
G01X315766Y70059D02*
X316366Y69459D01*
G01X315766Y72359D02*
Y70059D01*
G01X316091Y72684D02*
X315766Y72359D01*
G01X316091Y75034D02*
Y72684D01*
G01X315766Y75359D02*
X316091Y75034D01*
G01X315766Y85674D02*
Y75359D01*
G01X316366Y86274D02*
X315766Y85674D01*
G01X316366Y88174D02*
Y86274D01*
G01X315666Y88874D02*
X316366Y88174D01*
G01X315666Y90974D02*
Y88874D01*
G01X316366Y91674D02*
X315666Y90974D01*
G01X316366Y97974D02*
Y91674D01*
G01X349452Y34975D02*
X350297Y34130D01*
G01X349452Y41424D02*
Y34975D01*
G01X350497Y42469D02*
X349452Y41424D01*
G01X350497Y44619D02*
Y42469D01*
G01X349452Y45664D02*
X350497Y44619D01*
G01X349452Y47902D02*
Y45664D01*
G01X350073Y48523D02*
X349452Y47902D01*
G01X350073Y50575D02*
Y48523D01*
G01X349101Y51547D02*
X350073Y50575D01*
G01X349101Y53351D02*
Y51547D01*
G01X349542Y53792D02*
X349101Y53351D01*
G01X349542Y59776D02*
Y53792D01*
G01X350647Y60881D02*
X349542Y59776D01*
G01X350647Y63528D02*
Y60881D01*
G01X349542Y64633D02*
X350647Y63528D01*
G01X349542Y66877D02*
Y64633D01*
G01X350224Y67559D02*
X349542Y66877D01*
G01X350224Y69259D02*
Y67559D01*
G01X349224Y70259D02*
X350224Y69259D01*
G01X349224Y72359D02*
Y70259D01*
G01X349443Y72578D02*
X349224Y72359D01*
G01X349443Y75640D02*
Y72578D01*
G01X349224Y75859D02*
X349443Y75640D01*
G01X349224Y79256D02*
Y75859D01*
G01X350241Y80273D02*
X349224Y79256D01*
G01X350241Y82376D02*
Y80273D01*
G01X349224Y83393D02*
X350241Y82376D01*
G01X349224Y85474D02*
Y83393D01*
G01X350224Y86474D02*
X349224Y85474D01*
G01X350224Y88224D02*
Y86474D01*
G01X349224Y89224D02*
X350224Y88224D01*
G01X349224Y91274D02*
Y89224D01*
G01X349766Y91816D02*
X349224Y91274D01*
G01X349766Y95733D02*
Y91816D01*
G01X333592Y101400D02*
X329752Y97560D01*
G01X333592Y106015D02*
Y101400D01*
G01X349298Y121721D02*
X333592Y106015D01*
G01X349298Y200994D02*
Y121721D01*
G01X331792Y102100D02*
X325821Y96129D01*
G01X331792Y107044D02*
Y102100D01*
G01X347298Y122550D02*
X331792Y107044D01*
G01X347298Y201105D02*
Y122550D01*
G01X345298Y125303D02*
Y200336D01*
G01X329592Y109597D02*
X345298Y125303D01*
G01X329592Y102500D02*
Y109597D01*
G01X322892Y95800D02*
X329592Y102500D01*
G01X309384Y155856D02*
X314792Y161264D01*
G01X309384Y110336D02*
Y155856D01*
G01X308418Y109370D02*
X309384Y110336D01*
G01X307384Y109370D02*
X308418D01*
G01X306584Y108570D02*
X307384Y109370D01*
G01X306584Y106970D02*
Y108570D01*
G01X307792Y105762D02*
X306584Y106970D01*
G01X307792Y101100D02*
Y105762D01*
G01X303784Y97092D02*
X307792Y101100D01*
G01X322592Y101200D02*
X318492Y97100D01*
G01X322592Y106331D02*
Y101200D01*
G01X343273Y127012D02*
X322592Y106331D01*
G01X343273Y200681D02*
Y127012D01*
G01X349707Y108327D02*
X339207Y97827D01*
G01X349707Y113643D02*
Y108327D01*
G01X355298Y119234D02*
X349707Y113643D01*
G01X306884Y120600D02*
Y162958D01*
G01X306084Y119800D02*
X306884Y120600D01*
G01X302052Y119800D02*
X306084D01*
G01X301492Y119240D02*
X302052Y119800D01*
G01X301492Y116972D02*
Y119240D01*
G01X302052Y116412D02*
X301492Y116972D01*
G01X306084Y116412D02*
X302052D01*
G01X306884Y115612D02*
X306084Y116412D01*
G01X306884Y113656D02*
Y115612D01*
G01X305984Y112756D02*
X306884Y113656D01*
G01X304148Y112756D02*
X305984D01*
G01X302892Y111500D02*
X304148Y112756D01*
G01X302892Y109000D02*
Y111500D01*
G01X302266Y108374D02*
X302892Y109000D01*
G01X302266Y104226D02*
Y108374D01*
G01X303992Y102500D02*
X302266Y104226D01*
G01X303992Y101699D02*
Y102500D01*
G01X303293Y101000D02*
X303992Y101699D01*
G01X301692Y101000D02*
X303293D01*
G01X300982Y100290D02*
X301692Y101000D01*
G01X348143Y101105D02*
X355630Y108592D01*
G01X348143Y100082D02*
Y101105D01*
G01X349316Y98909D02*
X348143Y100082D01*
G01X349316Y98047D02*
Y98909D01*
G01X347971Y96702D02*
X349316Y98047D01*
G01X346262Y96702D02*
X347971D01*
G01X345652Y96092D02*
X346262Y96702D01*
G01X304384Y124760D02*
Y163124D01*
G01X303824Y124200D02*
X304384Y124760D01*
G01X298244Y124200D02*
X303824D01*
G01X297684Y123640D02*
X298244Y124200D01*
G01X297684Y115456D02*
Y123640D01*
G01X299084Y114056D02*
X297684Y115456D01*
G01X299084Y108908D02*
Y114056D01*
G01X299566Y108426D02*
X299084Y108908D01*
G01X299566Y104174D02*
Y108426D01*
G01X298584Y103192D02*
X299566Y104174D01*
G01X298584Y155293D02*
Y158093D01*
G01X299384Y154493D02*
X298584Y155293D01*
G01X301592Y154493D02*
X299384D01*
G01X302392Y153693D02*
X301592Y154493D01*
G01X302392Y152093D02*
Y153693D01*
G01X301592Y151293D02*
X302392Y152093D01*
G01X299384Y151293D02*
X301592D01*
G01X298584Y150493D02*
X299384Y151293D01*
G01X298584Y148893D02*
Y150493D01*
G01X299384Y148093D02*
X298584Y148893D01*
G01X301492Y148093D02*
X299384D01*
G01X302292Y147293D02*
X301492Y148093D01*
G01X302292Y145693D02*
Y147293D01*
G01X301492Y144893D02*
X302292Y145693D01*
G01X299384Y144893D02*
X301492D01*
G01X298584Y144093D02*
X299384Y144893D01*
G01X298584Y142493D02*
Y144093D01*
G01X299384Y141693D02*
X298584Y142493D01*
G01X301092Y141693D02*
X299384D01*
G01X301892Y140893D02*
X301092Y141693D01*
G01X301892Y139293D02*
Y140893D01*
G01X301092Y138493D02*
X301892Y139293D01*
G01X299384Y138493D02*
X301092D01*
G01X298584Y137693D02*
X299384Y138493D01*
G01X298584Y136093D02*
Y137693D01*
G01X298892Y135785D02*
X298584Y136093D01*
G01X298892Y132565D02*
Y135785D01*
G01X295184Y128857D02*
X298892Y132565D01*
G01X295184Y114256D02*
Y128857D01*
G01X296766Y112674D02*
X295184Y114256D01*
G01X296766Y109674D02*
Y112674D01*
G01X295666Y108574D02*
X296766Y109674D01*
G01X295666Y104026D02*
Y108574D01*
G01X296184Y103508D02*
X295666Y104026D01*
G01X296184Y94656D02*
Y103508D01*
G01X352278Y108069D02*
X343138Y98929D01*
G01X352278Y112117D02*
Y108069D01*
G01X353202Y113041D02*
X352278Y112117D01*
G01X356144Y113041D02*
X353202D01*
G01X316592Y104200D02*
X310066Y97674D01*
G01X316592Y109261D02*
Y104200D01*
G01X337273Y129942D02*
X316592Y109261D01*
G01X337273Y190678D02*
Y129942D01*
G01X338785Y100234D02*
X336366Y97815D01*
G01X338785Y101364D02*
Y100234D01*
G01X337568Y102581D02*
X338785Y101364D01*
G01X337568Y103747D02*
Y102581D01*
G01X338599Y104778D02*
X337568Y103747D01*
G01X339898Y104778D02*
X338599D01*
G01X341049Y103627D02*
X339898Y104778D01*
G01X342178Y103627D02*
X341049D01*
G01X343311Y104760D02*
X342178Y103627D01*
G01X343311Y105917D02*
Y104760D01*
G01X341569Y107659D02*
X343311Y105917D01*
G01X341569Y108656D02*
Y107659D01*
G01X342745Y109832D02*
X341569Y108656D01*
G01X343923Y109832D02*
X342745D01*
G01X345602Y108153D02*
X343923Y109832D01*
G01X346704Y108153D02*
X345602D01*
G01X347707Y109156D02*
X346704Y108153D01*
G01X347707Y114472D02*
Y109156D01*
G01X353298Y120063D02*
X347707Y114472D01*
G01X353298Y200493D02*
Y120063D01*
G01X335792Y100801D02*
X332452Y97461D01*
G01X335792Y105386D02*
Y100801D01*
G01X351298Y120892D02*
X335792Y105386D01*
G01X351298Y200173D02*
Y120892D01*
G01X318892Y103500D02*
X312435Y97043D01*
G01X318892Y108198D02*
Y103500D01*
G01X339273Y128579D02*
X318892Y108198D01*
G01X339273Y191212D02*
Y128579D01*
G01X363298Y106436D02*
X352593Y95731D01*
G01X320892Y102500D02*
X316366Y97974D01*
G01X320892Y107569D02*
Y102500D01*
G01X341273Y127950D02*
X320892Y107569D01*
G01X341273Y200481D02*
Y127950D01*
G01X351728Y97695D02*
X349766Y95733D01*
G01X351728Y98827D02*
Y97695D01*
G01X350840Y99715D02*
X351728Y98827D01*
G01X350840Y100847D02*
Y99715D01*
G01X351971Y101978D02*
X350840Y100847D01*
G01X353103Y101978D02*
X351971D01*
G01X353991Y101090D02*
X353103Y101978D01*
G01X355123Y101090D02*
X353991D01*
G01X311868Y186294D02*
Y193991D01*
G01X331789Y180597D02*
Y194186D01*
G01X324992Y173800D02*
X331789Y180597D01*
G01X320393Y173800D02*
X324992D01*
G01X314792Y168199D02*
X320393Y173800D01*
G01X314792Y161264D02*
Y168199D01*
G01X329220Y181428D02*
Y194186D01*
G01X323477Y175685D02*
X329220Y181428D01*
G01X319611Y175685D02*
X323477D01*
G01X310833Y166907D02*
X319611Y175685D01*
G01X310833Y166115D02*
Y166907D01*
G01X312474Y164474D02*
X310833Y166115D01*
G01X312474Y163682D02*
Y164474D01*
G01X311455Y162663D02*
X312474Y163682D01*
G01X310663Y162663D02*
X311455D01*
G01X309022Y164304D02*
X310663Y162663D01*
G01X308230Y164304D02*
X309022D01*
G01X306884Y162958D02*
X308230Y164304D01*
G01X326578Y182186D02*
Y192141D01*
G01X321962Y177570D02*
X326578Y182186D01*
G01X318830Y177570D02*
X321962D01*
G01X304384Y163124D02*
X318830Y177570D01*
G01X324028Y182736D02*
Y192131D01*
G01X320747Y179455D02*
X324028Y182736D01*
G01X318048Y179455D02*
X320747D01*
G01X301884Y163291D02*
X318048Y179455D01*
G01X301884Y159681D02*
Y163291D01*
G01X300948Y158745D02*
X301884Y159681D01*
G01X299236Y158745D02*
X300948D01*
G01X298584Y158093D02*
X299236Y158745D01*
G01X306768Y190327D02*
Y193511D01*
G01X294363Y174109D02*
X293501D01*
G01X295259Y173213D02*
X294363Y174109D01*
G01X296121Y173213D02*
X295259D01*
G01X297522Y174614D02*
X296121Y173213D01*
G01X297522Y175476D02*
Y174614D01*
G01X296626Y176372D02*
X297522Y175476D01*
G01X296626Y177234D02*
Y176372D01*
G01X298027Y178635D02*
X296626Y177234D01*
G01X298889Y178635D02*
X298027D01*
G01X299785Y177739D02*
X298889Y178635D01*
G01X300647Y177739D02*
X299785D01*
G01X302048Y179140D02*
X300647Y177739D01*
G01X302048Y180002D02*
Y179140D01*
G01X301152Y180898D02*
X302048Y180002D01*
G01X301152Y181760D02*
Y180898D01*
G01X302553Y183161D02*
X301152Y181760D01*
G01X303415Y183161D02*
X302553D01*
G01X304311Y182265D02*
X303415Y183161D01*
G01X305173Y182265D02*
X304311D01*
G01X309592Y186684D02*
X305173Y182265D01*
G01X309592Y194265D02*
Y186684D01*
G01X304218Y190444D02*
Y193611D01*
G01X343792Y399647D02*
Y479629D01*
G01X347792Y395781D02*
Y481400D01*
G01X315668Y401814D02*
Y409841D01*
G01X345792Y398948D02*
Y480458D01*
G01X310549Y400397D02*
Y407817D01*
G01X337792Y399687D02*
Y476800D01*
G01X341792Y399889D02*
Y478800D01*
G01X313099Y401938D02*
Y408803D01*
G01X307971Y399557D02*
Y406859D01*
G01X339792Y477900D02*
Y399607D01*
G01X351792Y406100D02*
Y486828D01*
G01X312045Y434947D02*
Y466131D01*
G01X331150Y415842D02*
X312045Y434947D01*
G01X331150Y406691D02*
Y415842D01*
G01X303092Y463500D02*
Y465466D01*
G01X303592Y463000D02*
X303092Y463500D01*
G01X308974Y463000D02*
X303592D01*
G01X309748Y462226D02*
X308974Y463000D01*
G01X309748Y460925D02*
Y462226D01*
G01X309090Y460267D02*
X309748Y460925D01*
G01X303692Y460267D02*
X309090D01*
G01X302892Y459467D02*
X303692Y460267D01*
G01X302892Y458367D02*
Y459467D01*
G01X303692Y457567D02*
X302892Y458367D01*
G01X308096Y457567D02*
X303692D01*
G01X309492Y456171D02*
X308096Y457567D01*
G01X309492Y434101D02*
Y456171D01*
G01X328600Y414993D02*
X309492Y434101D01*
G01X328600Y406691D02*
Y414993D01*
G01X349792Y405706D02*
Y485999D01*
G01X314699Y435593D02*
Y478038D01*
G01X333700Y416592D02*
X314699Y435593D01*
G01X333700Y406691D02*
Y416592D01*
G01X353792Y405714D02*
Y491628D01*
G01X300492Y455800D02*
Y483200D01*
G01X301292Y455000D02*
X300492Y455800D01*
G01X302444Y455000D02*
X301292D01*
G01X303440Y454004D02*
X302444Y455000D01*
G01X303440Y452501D02*
Y454004D01*
G01X302640Y451701D02*
X303440Y452501D01*
G01X301592Y451701D02*
X302640D01*
G01X300792Y450901D02*
X301592Y451701D01*
G01X300792Y449301D02*
Y450901D01*
G01X301592Y448501D02*
X300792Y449301D01*
G01X306088Y448501D02*
X301592D01*
G01X306988Y447601D02*
X306088Y448501D01*
G01X306988Y432996D02*
Y447601D01*
G01X326050Y413934D02*
X306988Y432996D01*
G01X326050Y406691D02*
Y413934D01*
G01X342768Y522024D02*
Y535676D01*
G01X342992Y521800D02*
X342768Y522024D01*
G01X342992Y517000D02*
Y521800D01*
G01X342492Y516500D02*
X342992Y517000D01*
G01X342492Y514400D02*
Y516500D01*
G01X343092Y513800D02*
X342492Y514400D01*
G01X343092Y511700D02*
Y513800D01*
G01X342292Y510900D02*
X343092Y511700D01*
G01X342292Y505792D02*
Y510900D01*
G01X355792Y492292D02*
X342292Y505792D01*
G01X349555Y524937D02*
Y532837D01*
G01X350292Y524200D02*
X349555Y524937D01*
G01X350292Y517300D02*
Y524200D01*
G01X349292Y516300D02*
X350292Y517300D01*
G01X349292Y514600D02*
Y516300D01*
G01X349698Y514194D02*
X349292Y514600D01*
G01X349698Y511706D02*
Y514194D01*
G01X348598Y510606D02*
X349698Y511706D01*
G01X348598Y506122D02*
Y510606D01*
G01X359792Y494928D02*
X348598Y506122D01*
G01X322743Y526449D02*
Y530351D01*
G01X323092Y526100D02*
X322743Y526449D01*
G01X323092Y517000D02*
Y526100D01*
G01X322492Y516400D02*
X323092Y517000D01*
G01X322492Y514300D02*
Y516400D01*
G01X322992Y513800D02*
X322492Y514300D01*
G01X322992Y511500D02*
Y513800D01*
G01X322492Y511000D02*
X322992Y511500D01*
G01X322492Y509200D02*
Y511000D01*
G01X329092Y502600D02*
X322492Y509200D01*
G01X329092Y494329D02*
Y502600D01*
G01X343792Y479629D02*
X329092Y494329D01*
G01X352892Y520400D02*
Y577000D01*
G01X352392Y519900D02*
X352892Y520400D01*
G01X352392Y517400D02*
Y519900D01*
G01X353192Y516600D02*
X352392Y517400D01*
G01X353192Y514500D02*
Y516600D01*
G01X352492Y513800D02*
X353192Y514500D01*
G01X352492Y511600D02*
Y513800D01*
G01X353056Y511036D02*
X352492Y511600D01*
G01X353056Y509330D02*
Y511036D01*
G01X351825Y508099D02*
X353056Y509330D01*
G01X351825Y506908D02*
Y508099D01*
G01X353115Y505618D02*
X351825Y506908D01*
G01X354164Y505618D02*
X353115D01*
G01X355398Y506852D02*
X354164Y505618D01*
G01X329472Y516780D02*
Y531596D01*
G01X329192Y516500D02*
X329472Y516780D01*
G01X329192Y514400D02*
Y516500D01*
G01X329792Y513800D02*
X329192Y514400D01*
G01X329792Y511700D02*
Y513800D01*
G01X329300Y511208D02*
X329792Y511700D01*
G01X329300Y509492D02*
Y511208D01*
G01X333092Y505700D02*
X329300Y509492D01*
G01X333092Y496100D02*
Y505700D01*
G01X347792Y481400D02*
X333092Y496100D01*
G01X336084Y525408D02*
Y549292D01*
G01X336692Y524800D02*
X336084Y525408D01*
G01X336692Y517200D02*
Y524800D01*
G01X335792Y516300D02*
X336692Y517200D01*
G01X335792Y514400D02*
Y516300D01*
G01X336292Y513900D02*
X335792Y514400D01*
G01X336292Y511500D02*
Y513900D01*
G01X335892Y511100D02*
X336292Y511500D01*
G01X335892Y509354D02*
Y511100D01*
G01X337092Y508154D02*
X335892Y509354D01*
G01X337092Y501528D02*
Y508154D01*
G01X351792Y486828D02*
X337092Y501528D01*
G01X299277Y519862D02*
Y530049D01*
G01X300982Y518157D02*
X299277Y519862D01*
G01X299624Y516799D02*
X300982Y518157D01*
G01X299624Y514307D02*
Y516799D01*
G01X303024Y510907D02*
X299624Y514307D01*
G01X303024Y499700D02*
Y510907D01*
G01X302692Y499368D02*
X303024Y499700D01*
G01X302692Y494000D02*
Y499368D01*
G01X304292Y492400D02*
X302692Y494000D01*
G01X304292Y487800D02*
Y492400D01*
G01X305792Y486300D02*
X304292Y487800D01*
G01X305792Y478564D02*
Y486300D01*
G01X306712Y477644D02*
X305792Y478564D01*
G01X308304Y477644D02*
X306712D01*
G01X308881Y477067D02*
X308304Y477644D01*
G01X308881Y475067D02*
Y477067D01*
G01X308258Y474444D02*
X308881Y475067D01*
G01X306990Y474444D02*
X308258D01*
G01X306190Y473644D02*
X306990Y474444D01*
G01X306190Y471986D02*
Y473644D01*
G01X312045Y466131D02*
X306190Y471986D01*
G01X346119Y521227D02*
Y533027D01*
G01X345692Y520800D02*
X346119Y521227D01*
G01X345692Y517200D02*
Y520800D01*
G01X346292Y516600D02*
X345692Y517200D01*
G01X346292Y514100D02*
Y516600D01*
G01X346060Y513868D02*
X346292Y514100D01*
G01X346060Y511732D02*
Y513868D01*
G01X346392Y511400D02*
X346060Y511732D01*
G01X346392Y509400D02*
Y511400D01*
G01X345739Y508747D02*
X346392Y509400D01*
G01X345739Y506151D02*
Y508747D01*
G01X349064Y502826D02*
X345739Y506151D01*
G01X349064Y501526D02*
Y502826D01*
G01X350947Y499643D02*
X349064Y501526D01*
G01X351795Y499643D02*
X350947D01*
G01X353590Y497848D02*
X351795Y499643D01*
G01X353590Y496880D02*
Y497848D01*
G01X357792Y492678D02*
X353590Y496880D01*
G01X326034Y516658D02*
Y537707D01*
G01X326197Y516495D02*
X326034Y516658D01*
G01X326197Y514205D02*
Y516495D01*
G01X325973Y513981D02*
X326197Y514205D01*
G01X325973Y512019D02*
Y513981D01*
G01X326392Y511600D02*
X325973Y512019D01*
G01X326392Y509299D02*
Y511600D01*
G01X331092Y504599D02*
X326392Y509299D01*
G01X331092Y495158D02*
Y504599D01*
G01X345792Y480458D02*
X331092Y495158D01*
G01X294924Y525788D02*
X296061Y526925D01*
G01X294924Y524712D02*
Y525788D01*
G01X295936Y523700D02*
X294924Y524712D01*
G01X295936Y522500D02*
Y523700D01*
G01X294924Y521488D02*
X295936Y522500D01*
G01X294924Y520412D02*
Y521488D01*
G01X296036Y519300D02*
X294924Y520412D01*
G01X296036Y516667D02*
Y519300D01*
G01X295861Y516492D02*
X296036Y516667D01*
G01X295861Y514800D02*
Y516492D01*
G01X297547Y513114D02*
X295861Y514800D01*
G01X297635Y513114D02*
X297547D01*
G01X298981Y511768D02*
X297635Y513114D01*
G01X299024Y511768D02*
X298981D01*
G01X299024Y499368D02*
Y511768D01*
G01X300192Y498200D02*
X299024Y499368D01*
G01X300192Y494900D02*
Y498200D01*
G01X299024Y493732D02*
X300192Y494900D01*
G01X299024Y488368D02*
Y493732D01*
G01X303092Y484300D02*
X299024Y488368D01*
G01X303092Y469396D02*
Y484300D01*
G01X303702Y468786D02*
X303092Y469396D01*
G01X306556Y468786D02*
X303702D01*
G01X307219Y468123D02*
X306556Y468786D01*
G01X307219Y466633D02*
Y468123D01*
G01X306662Y466076D02*
X307219Y466633D01*
G01X303702Y466076D02*
X306662D01*
G01X303092Y465466D02*
X303702Y466076D01*
G01X312752Y519860D02*
Y533060D01*
G01X312392Y519500D02*
X312752Y519860D01*
G01X312392Y517100D02*
Y519500D01*
G01X313092Y516400D02*
X312392Y517100D01*
G01X313092Y514300D02*
Y516400D01*
G01X312292Y513500D02*
X313092Y514300D01*
G01X312292Y512000D02*
Y513500D01*
G01X312892Y511400D02*
X312292Y512000D01*
G01X312892Y501700D02*
Y511400D01*
G01X337792Y476800D02*
X312892Y501700D01*
G01X332792Y526200D02*
Y530300D01*
G01X332392Y525800D02*
X332792Y526200D01*
G01X332392Y516900D02*
Y525800D01*
G01X332992Y516300D02*
X332392Y516900D01*
G01X332992Y514400D02*
Y516300D01*
G01X332592Y514000D02*
X332992Y514400D01*
G01X332592Y511700D02*
Y514000D01*
G01X333092Y511200D02*
X332592Y511700D01*
G01X333092Y509324D02*
Y511200D01*
G01X335092Y507324D02*
X333092Y509324D01*
G01X335092Y500699D02*
Y507324D01*
G01X340322Y495469D02*
X335092Y500699D01*
G01X340322Y494337D02*
Y495469D01*
G01X339686Y493701D02*
X340322Y494337D01*
G01X339686Y492556D02*
Y493701D01*
G01X340817Y491425D02*
X339686Y492556D01*
G01X341936Y491425D02*
X340817D01*
G01X342585Y492074D02*
X341936Y491425D01*
G01X343717Y492074D02*
X342585D01*
G01X344848Y490943D02*
X343717Y492074D01*
G01X344848Y489811D02*
Y490943D01*
G01X344095Y489058D02*
X344848Y489811D01*
G01X344095Y487926D02*
Y489058D01*
G01X345226Y486795D02*
X344095Y487926D01*
G01X346358Y486795D02*
X345226D01*
G01X347111Y487548D02*
X346358Y486795D01*
G01X348243Y487548D02*
X347111D01*
G01X349792Y485999D02*
X348243Y487548D01*
G01X319422Y519830D02*
Y530570D01*
G01X319092Y519500D02*
X319422Y519830D01*
G01X319092Y516900D02*
Y519500D01*
G01X319692Y516300D02*
X319092Y516900D01*
G01X319692Y514400D02*
Y516300D01*
G01X319192Y513900D02*
X319692Y514400D01*
G01X319192Y511900D02*
Y513900D01*
G01X319592Y511500D02*
X319192Y511900D01*
G01X319592Y501000D02*
Y511500D01*
G01X341792Y478800D02*
X319592Y501000D01*
G01X301617Y525788D02*
X302754Y526925D01*
G01X301617Y524712D02*
Y525788D01*
G01X302629Y523700D02*
X301617Y524712D01*
G01X302629Y522500D02*
Y523700D01*
G01X301617Y521488D02*
X302629Y522500D01*
G01X301617Y520412D02*
Y521488D01*
G01X302729Y519300D02*
X301617Y520412D01*
G01X302729Y516667D02*
Y519300D01*
G01X302554Y516492D02*
X302729Y516667D01*
G01X302554Y514800D02*
Y516492D01*
G01X304240Y513114D02*
X302554Y514800D01*
G01X304328Y513114D02*
X304240D01*
G01X304328Y513166D02*
Y513114D01*
G01X306166Y511328D02*
X304328Y513166D01*
G01X306166Y500000D02*
Y511328D01*
G01X306692Y499474D02*
X306166Y500000D01*
G01X306692Y492484D02*
Y499474D01*
G01X307719Y491457D02*
X306692Y492484D01*
G01X312059Y491457D02*
X307719D01*
G01X312710Y490806D02*
X312059Y491457D01*
G01X312710Y489416D02*
Y490806D01*
G01X312141Y488847D02*
X312710Y489416D01*
G01X308909Y488847D02*
X312141D01*
G01X308299Y488237D02*
X308909Y488847D01*
G01X308299Y486847D02*
Y488237D01*
G01X308909Y486237D02*
X308299Y486847D01*
G01X312813Y486237D02*
X308909D01*
G01X313449Y485601D02*
X312813Y486237D01*
G01X313449Y484211D02*
Y485601D01*
G01X312865Y483627D02*
X313449Y484211D01*
G01X308909Y483627D02*
X312865D01*
G01X308299Y483017D02*
X308909Y483627D01*
G01X308299Y480900D02*
Y483017D01*
G01X309099Y480100D02*
X308299Y480900D01*
G01X312637Y480100D02*
X309099D01*
G01X314699Y478038D02*
X312637Y480100D01*
G01X339506Y521714D02*
Y535686D01*
G01X338592Y520800D02*
X339506Y521714D01*
G01X338592Y517700D02*
Y520800D01*
G01X339792Y516500D02*
X338592Y517700D01*
G01X339792Y514300D02*
Y516500D01*
G01X339192Y513700D02*
X339792Y514300D01*
G01X339192Y511700D02*
Y513700D01*
G01X339692Y511200D02*
X339192Y511700D01*
G01X339692Y502302D02*
Y511200D01*
G01X341220Y500774D02*
X339692Y502302D01*
G01X342596Y500774D02*
X341220D01*
G01X344392Y498978D02*
X342596Y500774D01*
G01X344392Y497058D02*
Y498978D01*
G01X345202Y496248D02*
X344392Y497058D01*
G01X346334Y496248D02*
X345202D01*
G01X346988Y496902D02*
X346334Y496248D01*
G01X348134Y496902D02*
X346988D01*
G01X349265Y495771D02*
X348134Y496902D01*
G01X349265Y494653D02*
Y495771D01*
G01X348587Y493975D02*
X349265Y494653D01*
G01X348587Y493043D02*
Y493975D01*
G01X349897Y491733D02*
X348587Y493043D01*
G01X350871Y491733D02*
X349897D01*
G01X351721Y492583D02*
X350871Y491733D01*
G01X352837Y492583D02*
X351721D01*
G01X353792Y491628D02*
X352837Y492583D01*
G01X315892Y501800D02*
X339792Y477900D01*
G01X315892Y511200D02*
Y501800D01*
G01X316192Y511500D02*
X315892Y511200D01*
G01X316192Y513800D02*
Y511500D01*
G01X315592Y514400D02*
X316192Y513800D01*
G01X315592Y516200D02*
Y514400D01*
G01X316392Y517000D02*
X315592Y516200D01*
G01X316392Y519100D02*
Y517000D01*
G01X315999Y519493D02*
X316392Y519100D01*
G01X315999Y530307D02*
Y519493D01*
G01X293624Y517492D02*
X294289Y518157D01*
G01X293624Y513657D02*
Y517492D01*
G01X296524Y510757D02*
X293624Y513657D01*
G01X296524Y500032D02*
Y510757D01*
G01X295992Y499500D02*
X296524Y500032D01*
G01X295992Y494400D02*
Y499500D01*
G01X296992Y493400D02*
X295992Y494400D01*
G01X296992Y486700D02*
Y493400D01*
G01X300492Y483200D02*
X296992Y486700D01*
G01X339419Y580473D02*
Y589527D01*
G01X342871Y577021D02*
X339419Y580473D01*
G01X342871Y535779D02*
Y577021D01*
G01X342768Y535676D02*
X342871Y535779D01*
G01X344486Y587894D02*
X346492Y589900D01*
G01X344486Y585722D02*
Y587894D01*
G01Y582106D02*
Y585722D01*
G01X349439Y577153D02*
X344486Y582106D01*
G01X349439Y573447D02*
Y577153D01*
G01X349542Y573344D02*
X349439Y573447D01*
G01X349542Y554650D02*
Y573344D01*
G01X349468Y554576D02*
X349542Y554650D01*
G01X349468Y532924D02*
Y554576D01*
G01X349555Y532837D02*
X349468Y532924D01*
G01X316087Y583305D02*
Y589805D01*
G01X322787Y576605D02*
X316087Y583305D01*
G01X322787Y572089D02*
Y576605D01*
G01X323092Y571784D02*
X322787Y572089D01*
G01X323092Y568500D02*
Y571784D01*
G01X322787Y568195D02*
X323092Y568500D01*
G01X322787Y564905D02*
Y568195D01*
G01X322698Y564816D02*
X322787Y564905D01*
G01X322698Y553886D02*
Y564816D01*
G01X322831Y553753D02*
X322698Y553886D01*
G01X322831Y549439D02*
Y553753D01*
G01X322787Y549395D02*
X322831Y549439D01*
G01X322787Y545405D02*
Y549395D01*
G01X322802Y545390D02*
X322787Y545405D01*
G01X322802Y534329D02*
Y545390D01*
G01X323286Y533845D02*
X322802Y534329D01*
G01X323286Y530894D02*
Y533845D01*
G01X322743Y530351D02*
X323286Y530894D01*
G01X349453Y580439D02*
Y591931D01*
G01X352892Y577000D02*
X349453Y580439D01*
G01X322787Y583905D02*
Y588948D01*
G01X329383Y577309D02*
X322787Y583905D01*
G01X329383Y571009D02*
Y577309D01*
G01X329486Y570906D02*
X329383Y571009D01*
G01X329486Y554694D02*
Y570906D01*
G01X329384Y554592D02*
X329486Y554694D01*
G01X329384Y538430D02*
Y554592D01*
G01X329369Y538415D02*
X329384Y538430D01*
G01X329369Y531699D02*
Y538415D01*
G01X329472Y531596D02*
X329369Y531699D01*
G01X332307Y587853D02*
Y591761D01*
G01X334446Y585714D02*
X332307Y587853D01*
G01X334446Y577546D02*
Y585714D01*
G01X336157Y575835D02*
X334446Y577546D01*
G01X336157Y572383D02*
Y575835D01*
G01X336492Y572048D02*
X336157Y572383D01*
G01X336492Y568600D02*
Y572048D01*
G01X336068Y568176D02*
X336492Y568600D01*
G01X336068Y552800D02*
Y568176D01*
G01X336492Y552376D02*
X336068Y552800D01*
G01X336492Y549700D02*
Y552376D01*
G01X336084Y549292D02*
X336492Y549700D01*
G01X299277Y530049D02*
X304328Y535100D01*
G01X342871Y580221D02*
Y592042D01*
G01X346191Y576901D02*
X342871Y580221D01*
G01X346191Y570999D02*
Y576901D01*
G01X346117Y570925D02*
X346191Y570999D01*
G01X346117Y551925D02*
Y570925D01*
G01X346207Y551835D02*
X346117Y551925D01*
G01X346207Y535685D02*
Y551835D01*
G01X346492Y535400D02*
X346207Y535685D01*
G01X346492Y533400D02*
Y535400D01*
G01X346119Y533027D02*
X346492Y533400D01*
G01X352592Y587500D02*
Y591723D01*
G01X352891Y587201D02*
X352592Y587500D01*
G01X352891Y580601D02*
Y587201D01*
G01X356156Y577336D02*
X352891Y580601D01*
G01X319320Y583572D02*
Y591012D01*
G01X326049Y576843D02*
X319320Y583572D01*
G01X326049Y570957D02*
Y576843D01*
G01X326034Y570942D02*
X326049Y570957D01*
G01X326034Y546844D02*
Y570942D01*
G01X324814Y545624D02*
X326034Y546844D01*
G01X324814Y544444D02*
Y545624D01*
G01X325452Y543806D02*
X324814Y544444D01*
G01X326479Y543806D02*
X325452D01*
G01X327145Y543140D02*
X326479Y543806D01*
G01X327145Y541605D02*
Y543140D01*
G01X326591Y541051D02*
X327145Y541605D01*
G01X325382Y541051D02*
X326591D01*
G01X324772Y540441D02*
X325382Y541051D01*
G01X324772Y538969D02*
Y540441D01*
G01X326034Y537707D02*
X324772Y538969D01*
G01X295361Y528899D02*
X294289D01*
G01X296061Y528199D02*
X295361Y528899D01*
G01X296061Y526925D02*
Y528199D01*
G01X309992Y587400D02*
Y591392D01*
G01X309402Y586810D02*
X309992Y587400D01*
G01X309402Y580390D02*
Y586810D01*
G01X312634Y577158D02*
X309402Y580390D01*
G01X312634Y568358D02*
Y577158D01*
G01X312738Y568254D02*
X312634Y568358D01*
G01X312738Y552146D02*
Y568254D01*
G01X312649Y552057D02*
X312738Y552146D01*
G01X312649Y535343D02*
Y552057D01*
G01X313092Y534900D02*
X312649Y535343D01*
G01X313092Y533400D02*
Y534900D01*
G01X312752Y533060D02*
X313092Y533400D01*
G01X332821Y577300D02*
X324407Y585714D01*
G01X332821Y573371D02*
Y577300D01*
G01X332192Y572742D02*
X332821Y573371D01*
G01X332192Y568700D02*
Y572742D01*
G01X332734Y568158D02*
X332192Y568700D01*
G01X332734Y564942D02*
Y568158D01*
G01X332192Y564400D02*
X332734Y564942D01*
G01X332192Y558600D02*
Y564400D01*
G01X332777Y558015D02*
X332192Y558600D01*
G01X332777Y553107D02*
Y558015D01*
G01X332292Y552622D02*
X332777Y553107D01*
G01X332292Y549700D02*
Y552622D01*
G01X332807Y549185D02*
X332292Y549700D01*
G01X332807Y534712D02*
Y549185D01*
G01X332492Y534397D02*
X332807Y534712D01*
G01X332492Y530600D02*
Y534397D01*
G01X332792Y530300D02*
X332492Y530600D01*
G01X324407Y587677D02*
X326551Y589821D01*
G01X324407Y585714D02*
Y587677D01*
G01X312649Y583743D02*
Y590070D01*
G01X319319Y577073D02*
X312649Y583743D01*
G01X319319Y573727D02*
Y577073D01*
G01X319192Y573600D02*
X319319Y573727D01*
G01X319192Y568400D02*
Y573600D01*
G01X319423Y568169D02*
X319192Y568400D01*
G01X319423Y554135D02*
Y568169D01*
G01X319092Y553804D02*
X319423Y554135D01*
G01X319092Y549500D02*
Y553804D01*
G01X319319Y549273D02*
X319092Y549500D01*
G01X319319Y530673D02*
Y549273D01*
G01X319422Y530570D02*
X319319Y530673D01*
G01X302054Y528899D02*
X300982D01*
G01X302754Y528199D02*
X302054Y528899D01*
G01X302754Y526925D02*
Y528199D01*
G01X336992Y586515D02*
Y591572D01*
G01X337793Y585714D02*
X336992Y586515D01*
G01X337793Y577899D02*
Y585714D01*
G01X339404Y576288D02*
X337793Y577899D01*
G01X339404Y568188D02*
Y576288D01*
G01X339528Y568064D02*
X339404Y568188D01*
G01X339528Y551160D02*
Y568064D01*
G01X339411Y551043D02*
X339528Y551160D01*
G01X339411Y535781D02*
Y551043D01*
G01X339506Y535686D02*
X339411Y535781D01*
G01X316392Y530700D02*
X315999Y530307D01*
G01X316392Y532800D02*
Y530700D01*
G01X316087Y533105D02*
X316392Y532800D01*
G01X316087Y552005D02*
Y533105D01*
G01X315999Y552093D02*
X316087Y552005D01*
G01X315999Y568307D02*
Y552093D01*
G01X316087Y568395D02*
X315999Y568307D01*
G01X316087Y576922D02*
Y568395D01*
G01X311021Y581988D02*
X316087Y576922D01*
G01X311021Y585714D02*
Y581988D01*
G01X341992Y608144D02*
X341140Y607292D01*
G01X341992Y610062D02*
Y608144D01*
G01X341492Y610562D02*
X341992Y610062D01*
G01X340192Y610562D02*
X341492D01*
G01X339692Y610062D02*
X340192Y610562D01*
G01X339692Y609240D02*
Y610062D01*
G01X338423Y607971D02*
X339692Y609240D01*
G01X338423Y606415D02*
Y607971D01*
G01X339593Y605245D02*
X338423Y606415D01*
G01X339593Y603753D02*
Y605245D01*
G01X337993Y602153D02*
X339593Y603753D01*
G01X337993Y595994D02*
Y602153D01*
G01X340330Y593657D02*
X337993Y595994D01*
G01X341140Y593657D02*
X340330D01*
G01X341140Y591248D02*
Y593657D01*
G01X339419Y589527D02*
X341140Y591248D01*
G01X345911Y606425D02*
X344486Y609864D01*
G01X348155Y604181D02*
X345911Y606425D01*
G01X348155Y596597D02*
Y604181D01*
G01X346117Y594559D02*
X348155Y596597D01*
G01X346117Y592675D02*
Y594559D01*
G01X346492Y592300D02*
X346117Y592675D01*
G01X346492Y589900D02*
Y592300D01*
G01X314368Y599606D02*
Y607292D01*
G01X315999Y597975D02*
X314368Y599606D01*
G01X315999Y589893D02*
Y597975D01*
G01X316087Y589805D02*
X315999Y589893D01*
G01X352753Y602925D02*
X351179Y604499D01*
G01X352753Y600662D02*
Y602925D01*
G01X352143Y600052D02*
X352753Y600662D01*
G01X350518Y600052D02*
X352143D01*
G01X349908Y599442D02*
X350518Y600052D01*
G01X349908Y598052D02*
Y599442D01*
G01X350518Y597442D02*
X349908Y598052D01*
G01X352143Y597442D02*
X350518D01*
G01X352753Y596832D02*
X352143Y597442D01*
G01X352753Y595231D02*
Y596832D01*
G01X351179Y593657D02*
X352753Y595231D01*
G01X349453Y591931D02*
X351179Y593657D01*
G01X324407Y603046D02*
Y604499D01*
G01X323797Y602436D02*
X324407Y603046D01*
G01X322454Y602436D02*
X323797D01*
G01X321844Y601826D02*
X322454Y602436D01*
G01X321844Y600836D02*
Y601826D01*
G01X322454Y600226D02*
X321844Y600836D01*
G01X323797Y600226D02*
X322454D01*
G01X324407Y599616D02*
X323797Y600226D01*
G01X324407Y598626D02*
Y599616D01*
G01X323797Y598016D02*
X324407Y598626D01*
G01X322872Y598016D02*
X323797D01*
G01X322262Y597406D02*
X322872Y598016D01*
G01X322262Y596416D02*
Y597406D01*
G01X322872Y595806D02*
X322262Y596416D01*
G01X323797Y595806D02*
X322872D01*
G01X324407Y595196D02*
X323797Y595806D01*
G01X324407Y593657D02*
Y595196D01*
G01Y590568D02*
Y593657D01*
G01X322787Y588948D02*
X324407Y590568D01*
G01X334447Y610355D02*
Y612457D01*
G01X332592Y608500D02*
X334447Y610355D01*
G01X332592Y606100D02*
Y608500D01*
G01X333092Y605600D02*
X332592Y606100D01*
G01X333092Y599700D02*
Y605600D01*
G01X332718Y599326D02*
X333092Y599700D01*
G01X332718Y592172D02*
Y599326D01*
G01X332307Y591761D02*
X332718Y592172D01*
G01X343300Y605800D02*
X344486Y604614D01*
G01X342380Y605800D02*
X343300D01*
G01X341377Y604797D02*
X342380Y605800D01*
G01X341377Y602316D02*
Y604797D01*
G01X341984Y601709D02*
X341377Y602316D01*
G01X345846Y601709D02*
X341984D01*
G01X346400Y601155D02*
X345846Y601709D01*
G01X346400Y599613D02*
Y601155D01*
G01X345886Y599099D02*
X346400Y599613D01*
G01X340228Y599099D02*
X345886D01*
G01X339631Y598502D02*
X340228Y599099D01*
G01X339631Y596865D02*
Y598502D01*
G01X340149Y596347D02*
X339631Y596865D01*
G01X343754Y596347D02*
X340149D01*
G01X344486Y595615D02*
X343754Y596347D01*
G01X344486Y593657D02*
Y595615D01*
G01X342871Y592042D02*
X344486Y593657D01*
G01X354526D02*
Y607292D01*
G01X352592Y591723D02*
X354526Y593657D01*
G01X319931Y606162D02*
X321061Y607292D01*
G01X319931Y594787D02*
Y606162D01*
G01X321061Y593657D02*
X319931Y594787D01*
G01X321061Y592753D02*
Y593657D01*
G01X319320Y591012D02*
X321061Y592753D01*
G01X311021Y607429D02*
Y609864D01*
G01X308892Y605300D02*
X311021Y607429D01*
G01X308892Y597200D02*
Y605300D01*
G01X309285Y596807D02*
X308892Y597200D01*
G01X309285Y592099D02*
Y596807D01*
G01X309992Y591392D02*
X309285Y592099D01*
G01X324407Y607685D02*
Y609864D01*
G01X326539Y605553D02*
X324407Y607685D01*
G01X326539Y595291D02*
Y605553D01*
G01X326049Y594801D02*
X326539Y595291D01*
G01X326049Y592743D02*
Y594801D01*
G01X326551Y592241D02*
X326049Y592743D01*
G01X326551Y589821D02*
Y592241D01*
G01X314368Y591789D02*
Y593657D01*
G01X312649Y590070D02*
X314368Y591789D01*
G01X336247Y608318D02*
X337793Y609864D01*
G01X336247Y605853D02*
Y608318D01*
G01X335993Y605599D02*
X336247Y605853D01*
G01X335993Y594679D02*
Y605599D01*
G01X336068Y594604D02*
X335993Y594679D01*
G01X336068Y592496D02*
Y594604D01*
G01X336992Y591572D02*
X336068Y592496D01*
G01X414761Y9124D02*
X414763Y9122D01*
G01X414761Y14169D02*
Y9124D01*
G01X416386Y15794D02*
X414761Y14169D01*
G01X416386Y20858D02*
Y15794D01*
G01X413138Y24106D02*
X416386Y20858D01*
G01X413138Y29284D02*
Y24106D01*
G01X412763Y29659D02*
X413138Y29284D01*
G01X412763Y31659D02*
Y29659D01*
G01X413363Y32259D02*
X412763Y31659D01*
G01X413363Y34559D02*
Y32259D01*
G01X414761Y4249D02*
Y-1743D01*
G01X415371Y4859D02*
X414761Y4249D01*
G01X416361Y4859D02*
X415371D01*
G01X416971Y4249D02*
X416361Y4859D01*
G01X415371Y7189D02*
X418571D01*
G01X414761Y7799D02*
X415371Y7189D01*
G01X414761Y9120D02*
Y7799D01*
G01X414763Y9122D02*
X414761Y9120D01*
G01X409798Y22022D02*
X414762Y17058D01*
G01X409798Y29494D02*
Y22022D01*
G01X410263Y29959D02*
X409798Y29494D01*
G01X410263Y33213D02*
Y29959D01*
G01X394682Y-1140D02*
Y11792D01*
G01X394683Y-1141D02*
X394682Y-1140D01*
G01X394683Y-2200D02*
Y-1141D01*
G01X392692Y15400D02*
Y97932D01*
G01X394682Y13410D02*
X392692Y15400D01*
G01X394682Y11792D02*
Y13410D01*
G01X355292Y29600D02*
Y34200D01*
G01X356136Y28756D02*
X355292Y29600D01*
G01X356136Y16145D02*
Y28756D01*
G01X354892Y14901D02*
X356136Y16145D01*
G01X354892Y9489D02*
Y14901D01*
G01X397392Y17679D02*
X398029Y17042D01*
G01X397392Y25900D02*
Y17679D01*
G01X396084Y27208D02*
X397392Y25900D01*
G01X396084Y28959D02*
Y27208D01*
G01X396303Y29178D02*
X396084Y28959D01*
G01X396303Y37804D02*
Y29178D01*
G01X398029Y-7583D02*
Y-9901D01*
G01X400057Y-5555D02*
X398029Y-7583D01*
G01X400057Y-3365D02*
Y-5555D01*
G01X399425Y-2733D02*
X400057Y-3365D01*
G01X399425Y333D02*
Y-2733D01*
G01X399741Y649D02*
X399425Y333D01*
G01X399741Y10051D02*
Y649D01*
G01X398029Y11763D02*
X399741Y10051D01*
G01X398029Y17042D02*
Y11763D01*
G01X403592Y15926D02*
X404723Y17057D01*
G01X403592Y10900D02*
Y15926D01*
G01X403065Y10373D02*
X403592Y10900D01*
G01X403065Y927D02*
Y10373D01*
G01X403392Y600D02*
X403065Y927D01*
G01X403392Y-2800D02*
Y600D01*
G01X402792Y-3400D02*
X403392Y-2800D01*
G01X402792Y-5500D02*
Y-3400D01*
G01X404722Y-7430D02*
X402792Y-5500D01*
G01X404722Y-9901D02*
Y-7430D01*
G01X399738Y22042D02*
X404723Y17057D01*
G01X399738Y53513D02*
Y22042D01*
G01X416370Y23704D02*
X419815Y20259D01*
G01X416370Y31930D02*
Y23704D01*
G01X416381Y31941D02*
X416370Y31930D01*
G01X416381Y75711D02*
Y31941D01*
G01X403056Y22055D02*
X408069Y17042D01*
G01X403056Y29238D02*
Y22055D01*
G01X403377Y29559D02*
X403056Y29238D01*
G01X403377Y31559D02*
Y29559D01*
G01X402275Y32661D02*
X403377Y31559D01*
G01X402275Y34157D02*
Y32661D01*
G01X406842Y-5882D02*
X408068Y-7108D01*
G01X406842Y-3650D02*
Y-5882D01*
G01X406192Y-3000D02*
X406842Y-3650D01*
G01X406192Y-1072D02*
Y-3000D01*
G01X406363Y-901D02*
X406192Y-1072D01*
G01X406363Y10029D02*
Y-901D01*
G01X406192Y10200D02*
X406363Y10029D01*
G01X406192Y15165D02*
Y10200D01*
G01X408069Y17042D02*
X406192Y15165D01*
G01X410898Y-7108D02*
X414761D01*
G01X409492Y-5702D02*
X410898Y-7108D01*
G01X409492Y-3400D02*
Y-5702D01*
G01X409868Y-3024D02*
X409492Y-3400D01*
G01X409868Y1817D02*
Y-3024D01*
G01X410668Y2617D02*
X409868Y1817D01*
G01X411782Y2617D02*
X410668D01*
G01X412568Y3403D02*
X411782Y2617D01*
G01X412568Y5003D02*
Y3403D01*
G01X411754Y5817D02*
X412568Y5003D01*
G01X410411Y5817D02*
X411754D01*
G01X409801Y6427D02*
X410411Y5817D01*
G01X409801Y10124D02*
Y6427D01*
G01X410767Y11090D02*
X409801Y10124D01*
G01X410767Y14066D02*
Y11090D01*
G01X409687Y15146D02*
X410767Y14066D01*
G01X409687Y18605D02*
Y15146D01*
G01X406331Y21961D02*
X409687Y18605D01*
G01X406331Y29105D02*
Y21961D01*
G01X405677Y29759D02*
X406331Y29105D01*
G01X405677Y31459D02*
Y29759D01*
G01X406352Y32134D02*
X405677Y31459D01*
G01X406352Y37734D02*
Y32134D01*
G01X413158Y34764D02*
X413363Y34559D01*
G01X413158Y48079D02*
Y34764D01*
G01X412763Y48474D02*
X413158Y48079D01*
G01X412763Y50374D02*
Y48474D01*
G01X413463Y51074D02*
X412763Y50374D01*
G01X413463Y53174D02*
Y51074D01*
G01X413122Y53515D02*
X413463Y53174D01*
G01X413122Y67100D02*
Y53515D01*
G01X413363Y67341D02*
X413122Y67100D01*
G01X413363Y72359D02*
Y67341D01*
G01X413029Y72693D02*
X413363Y72359D01*
G01X413029Y75025D02*
Y72693D01*
G01X413363Y75359D02*
X413029Y75025D01*
G01X413363Y85674D02*
Y75359D01*
G01X412763Y86274D02*
X413363Y85674D01*
G01X412763Y88174D02*
Y86274D01*
G01X413463Y88874D02*
X412763Y88174D01*
G01X413463Y90974D02*
Y88874D01*
G01X412266Y92171D02*
X413463Y90974D01*
G01X412266Y95898D02*
Y92171D01*
G01X409776Y33700D02*
X410263Y33213D01*
G01X409776Y48087D02*
Y33700D01*
G01X410063Y48374D02*
X409776Y48087D01*
G01X410063Y52746D02*
Y48374D01*
G01X409707Y53102D02*
X410063Y52746D01*
G01X409707Y62352D02*
Y53102D01*
G01X409775Y62420D02*
X409707Y62352D01*
G01X409775Y67271D02*
Y62420D01*
G01X410263Y67759D02*
X409775Y67271D01*
G01X410263Y71787D02*
Y67759D01*
G01X409791Y72259D02*
X410263Y71787D01*
G01X409791Y83446D02*
Y72259D01*
G01X409463Y83774D02*
X409791Y83446D01*
G01X409463Y85574D02*
Y83774D01*
G01X410063Y86174D02*
X409463Y85574D01*
G01X410063Y88374D02*
Y86174D01*
G01X409463Y88974D02*
X410063Y88374D01*
G01X409463Y90974D02*
Y88974D01*
G01X410166Y91677D02*
X409463Y90974D01*
G01X410166Y95168D02*
Y91677D01*
G01X356120Y85870D02*
Y96429D01*
G01X355924Y85674D02*
X356120Y85870D01*
G01X355924Y75359D02*
Y85674D01*
G01X356206Y75077D02*
X355924Y75359D01*
G01X356206Y73085D02*
Y75077D01*
G01X355660Y72539D02*
X356206Y73085D01*
G01X355660Y67123D02*
Y72539D01*
G01X356153Y66630D02*
X355660Y67123D01*
G01X356153Y54129D02*
Y66630D01*
G01X355924Y53900D02*
X356153Y54129D01*
G01X355924Y48275D02*
Y53900D01*
G01X356167Y48032D02*
X355924Y48275D01*
G01X356167Y45525D02*
Y48032D01*
G01X356592Y45100D02*
X356167Y45525D01*
G01X356592Y35500D02*
Y45100D01*
G01X355292Y34200D02*
X356592Y35500D01*
G01X396650Y38151D02*
X396303Y37804D01*
G01X396650Y43323D02*
Y38151D01*
G01X396084Y43889D02*
X396650Y43323D01*
G01X396084Y48074D02*
Y43889D01*
G01X396584Y48574D02*
X396084Y48074D01*
G01X396584Y50474D02*
Y48574D01*
G01X396245Y50813D02*
X396584Y50474D01*
G01X396245Y63247D02*
Y50813D01*
G01X396084Y63408D02*
X396245Y63247D01*
G01X396084Y66759D02*
Y63408D01*
G01X396684Y67359D02*
X396084Y66759D01*
G01X396684Y69359D02*
Y67359D01*
G01X396084Y69959D02*
X396684Y69359D01*
G01X396084Y85874D02*
Y69959D01*
G01X396584Y86374D02*
X396084Y85874D01*
G01X396584Y88274D02*
Y86374D01*
G01X395884Y88974D02*
X396584Y88274D01*
G01X395884Y91074D02*
Y88974D01*
G01X396615Y91805D02*
X395884Y91074D01*
G01X396615Y96839D02*
Y91805D01*
G01X399658Y53593D02*
X399738Y53513D01*
G01X399658Y57358D02*
Y53593D01*
G01X399762Y57462D02*
X399658Y57358D01*
G01X399762Y67074D02*
Y57462D01*
G01X399377Y67459D02*
X399762Y67074D01*
G01X399377Y69459D02*
Y67459D01*
G01X399977Y70059D02*
X399377Y69459D01*
G01X399977Y72359D02*
Y70059D01*
G01X399739Y72597D02*
X399977Y72359D01*
G01X399739Y75121D02*
Y72597D01*
G01X400141Y75523D02*
X399739Y75121D01*
G01X400141Y77625D02*
Y75523D01*
G01X399641Y78125D02*
X400141Y77625D01*
G01X398847Y78125D02*
X399641D01*
G01X398213Y78759D02*
X398847Y78125D01*
G01X398213Y80659D02*
Y78759D01*
G01X398799Y81245D02*
X398213Y80659D01*
G01X399629Y81245D02*
X398799D01*
G01X400433Y82049D02*
X399629Y81245D01*
G01X400433Y85218D02*
Y82049D01*
G01X399487Y86164D02*
X400433Y85218D01*
G01X399487Y88284D02*
Y86164D01*
G01X399851Y88648D02*
X399487Y88284D01*
G01X399851Y91200D02*
Y88648D01*
G01X399377Y91674D02*
X399851Y91200D01*
G01X399377Y96907D02*
Y91674D01*
G01X416163Y75929D02*
X416381Y75711D01*
G01X416163Y85874D02*
Y75929D01*
G01X416663Y86374D02*
X416163Y85874D01*
G01X416245Y88692D02*
X416663Y88274D01*
G01X416245Y91356D02*
Y88692D01*
G01X416694Y91805D02*
X416245Y91356D01*
G01X403098Y34980D02*
X402275Y34157D01*
G01X403098Y48395D02*
Y34980D01*
G01X403277Y48574D02*
X403098Y48395D01*
G01X403277Y50474D02*
Y48574D01*
G01X402348Y51403D02*
X403277Y50474D01*
G01X402348Y53045D02*
Y51403D01*
G01X403109Y53806D02*
X402348Y53045D01*
G01X403109Y67091D02*
Y53806D01*
G01X403377Y67359D02*
X403109Y67091D01*
G01X403377Y69359D02*
Y67359D01*
G01X402493Y70243D02*
X403377Y69359D01*
G01X402493Y72175D02*
Y70243D01*
G01X403014Y72696D02*
X402493Y72175D01*
G01X403014Y76878D02*
Y72696D01*
G01X402777Y77115D02*
X403014Y76878D01*
G01X402777Y85874D02*
Y77115D01*
G01X403277Y86374D02*
X402777Y85874D01*
G01X403277Y88274D02*
Y86374D01*
G01X402471Y89080D02*
X403277Y88274D01*
G01X402471Y90968D02*
Y89080D01*
G01X403308Y91805D02*
X402471Y90968D01*
G01X403308Y95806D02*
Y91805D01*
G01X407081Y38463D02*
X406352Y37734D01*
G01X407081Y42749D02*
Y38463D01*
G01X406344Y43486D02*
X407081Y42749D01*
G01X406344Y48007D02*
Y43486D01*
G01X405677Y48674D02*
X406344Y48007D01*
G01X405677Y53162D02*
Y48674D01*
G01X406333Y53818D02*
X405677Y53162D01*
G01X406333Y66903D02*
Y53818D01*
G01X405677Y67559D02*
X406333Y66903D01*
G01X405677Y69259D02*
Y67559D01*
G01X406332Y69914D02*
X405677Y69259D01*
G01X406332Y75514D02*
Y69914D01*
G01X406677Y75859D02*
X406332Y75514D01*
G01X406677Y85474D02*
Y75859D01*
G01X405677Y86474D02*
X406677Y85474D01*
G01X405677Y88224D02*
Y86474D01*
G01X406982Y89529D02*
X405677Y88224D01*
G01X406982Y90969D02*
Y89529D01*
G01X405677Y92274D02*
X406982Y90969D01*
G01X405677Y96267D02*
Y92274D01*
G01X406292Y101872D02*
X412266Y95898D01*
G01X406292Y109992D02*
Y101872D01*
G01X392632Y123652D02*
X406292Y109992D01*
G01X392632Y190218D02*
Y123652D01*
G01X408632Y130290D02*
X432292Y106630D01*
G01X408632Y189343D02*
Y130290D01*
G01X412740Y131840D02*
X446835Y97745D01*
G01X412740Y188712D02*
Y131840D01*
G01X404292Y101042D02*
X410166Y95168D01*
G01X404292Y109162D02*
Y101042D01*
G01X390632Y122822D02*
X404292Y109162D01*
G01X390632Y190240D02*
Y122822D01*
G01X380632Y114870D02*
Y190271D01*
G01X390992Y104510D02*
X380632Y114870D01*
G01X390992Y99632D02*
Y104510D01*
G01X392692Y97932D02*
X390992Y99632D01*
G01X355298Y190725D02*
Y119234D01*
G01X406632Y129461D02*
X430192Y105901D01*
G01X406632Y189743D02*
Y129461D01*
G01X400632Y126971D02*
Y190799D01*
G01X419598Y108005D02*
X400632Y126971D01*
G01X365298Y105607D02*
Y196325D01*
G01X356120Y96429D02*
X365298Y105607D01*
G01X359298Y110299D02*
Y191225D01*
G01X357591Y108592D02*
X359298Y110299D01*
G01X355630Y108592D02*
X357591D01*
G01X404632Y128631D02*
Y190277D01*
G01X425592Y107671D02*
X404632Y128631D01*
G01X398632Y126141D02*
Y191296D01*
G01X417392Y107381D02*
X398632Y126141D01*
G01X357298Y114195D02*
X356144Y113041D01*
G01X357298Y191175D02*
Y114195D01*
G01X392992Y100462D02*
X396615Y96839D01*
G01X392992Y105340D02*
Y100462D01*
G01X382632Y115700D02*
X392992Y105340D01*
G01X382632Y190375D02*
Y115700D01*
G01X394992Y101292D02*
X399377Y96907D01*
G01X394992Y106170D02*
Y101292D01*
G01X388956Y112206D02*
X394992Y106170D01*
G01X388956Y113338D02*
Y112206D01*
G01X389639Y114021D02*
X388956Y113338D01*
G01X389639Y115153D02*
Y114021D01*
G01X388508Y116284D02*
X389639Y115153D01*
G01X387376Y116284D02*
X388508D01*
G01X386693Y115601D02*
X387376Y116284D01*
G01X385561Y115601D02*
X386693D01*
G01X384632Y116530D02*
X385561Y115601D01*
G01X384632Y190071D02*
Y116530D01*
G01X402632Y127801D02*
Y190520D01*
G01X423492Y106941D02*
X402632Y127801D01*
G01X411019Y99974D02*
X416694Y94299D01*
G01X411019Y108094D02*
Y99974D01*
G01X395752Y123360D02*
X411019Y108094D01*
G01X394632Y124481D02*
X395752Y123360D01*
G01X394632Y190266D02*
Y124481D01*
G01X413019Y100873D02*
X419063Y94829D01*
G01X413019Y108924D02*
Y100873D01*
G01X396632Y125311D02*
X413019Y108924D01*
G01X396632Y191585D02*
Y125311D01*
G01X410632Y131119D02*
X436050Y105701D01*
G01X410632Y188943D02*
Y131119D01*
G01X363298Y196375D02*
Y106436D01*
G01X396992Y102122D02*
X403308Y95806D01*
G01X396992Y110802D02*
Y102122D01*
G01X396152Y111642D02*
X396992Y110802D01*
G01X395020Y111642D02*
X396152D01*
G01X394251Y110873D02*
X395020Y111642D01*
G01X393119Y110873D02*
X394251D01*
G01X391988Y112004D02*
X393119Y110873D01*
G01X391988Y113136D02*
Y112004D01*
G01X392757Y113905D02*
X391988Y113136D01*
G01X392757Y115037D02*
Y113905D01*
G01X386632Y121162D02*
X392757Y115037D01*
G01X386632Y190168D02*
Y121162D01*
G01X398992Y102952D02*
X405677Y96267D01*
G01X398992Y111632D02*
Y102952D01*
G01X388632Y121992D02*
X398992Y111632D01*
G01X388632Y190084D02*
Y121992D01*
G01X356254Y102221D02*
X355123Y101090D01*
G01X356254Y103353D02*
Y102221D01*
G01X355816Y103791D02*
X356254Y103353D01*
G01X355816Y104923D02*
Y103791D01*
G01X356947Y106054D02*
X355816Y104923D01*
G01X358079Y106054D02*
X356947D01*
G01X358517Y105616D02*
X358079Y106054D01*
G01X359649Y105616D02*
X358517D01*
G01X361298Y107265D02*
X359649Y105616D01*
G01X361298Y191275D02*
Y107265D01*
G01X380632Y190271D02*
X380630Y190273D01*
G01X404992Y374845D02*
X403056Y372909D01*
G01X404992Y382300D02*
Y374845D01*
G01X406992Y384300D02*
X404992Y382300D01*
G01X406992Y395600D02*
Y384300D01*
G01X408492Y397100D02*
X406992Y395600D01*
G01X408492Y404200D02*
Y397100D01*
G01X383192Y402828D02*
Y491912D01*
G01X362532Y401713D02*
Y408908D01*
G01X404392Y403000D02*
X405392Y404000D01*
G01X404392Y401600D02*
Y403000D01*
G01X404992Y401000D02*
X404392Y401600D01*
G01X404992Y385200D02*
Y401000D01*
G01X401192Y381400D02*
X404992Y385200D01*
G01X401192Y380000D02*
Y381400D01*
G01X401592Y379600D02*
X401192Y380000D01*
G01X401592Y378000D02*
Y379600D01*
G01X401192Y377600D02*
X401592Y378000D01*
G01X401192Y376100D02*
Y377600D01*
G01X401692Y375600D02*
X401192Y376100D01*
G01X401692Y374100D02*
Y375600D01*
G01X401192Y373600D02*
X401692Y374100D01*
G01X401192Y372200D02*
Y373600D01*
G01X401792Y371600D02*
X401192Y372200D01*
G01X401792Y370300D02*
Y371600D01*
G01X401192Y369700D02*
X401792Y370300D01*
G01X401192Y368576D02*
Y369700D01*
G01X399676Y367060D02*
X401192Y368576D01*
G01X396296Y362504D02*
Y361209D01*
G01X398192Y364400D02*
X396296Y362504D01*
G01X398192Y366000D02*
Y364400D01*
G01X397658Y366534D02*
X398192Y366000D01*
G01X397658Y367666D02*
Y366534D01*
G01X398192Y368200D02*
X397658Y367666D01*
G01X398192Y369800D02*
Y368200D01*
G01X397792Y370200D02*
X398192Y369800D01*
G01X397792Y371700D02*
Y370200D01*
G01X398192Y372100D02*
X397792Y371700D01*
G01X398192Y373700D02*
Y372100D01*
G01X397792Y374100D02*
X398192Y373700D01*
G01X397792Y375700D02*
Y374100D01*
G01X398192Y376100D02*
X397792Y375700D01*
G01X398192Y377600D02*
Y376100D01*
G01X397692Y378100D02*
X398192Y377600D01*
G01X397692Y379500D02*
Y378100D01*
G01X398192Y380000D02*
X397692Y379500D01*
G01X398192Y381400D02*
Y380000D01*
G01X397692Y381900D02*
X398192Y381400D01*
G01X397692Y383300D02*
Y381900D01*
G01X398892Y384500D02*
X397692Y383300D01*
G01X400292Y384500D02*
X398892D01*
G01X401592Y385800D02*
X400292Y384500D01*
G01X401592Y387400D02*
Y385800D01*
G01X401026Y387966D02*
X401592Y387400D01*
G01X401026Y389034D02*
Y387966D01*
G01X401692Y389700D02*
X401026Y389034D01*
G01X401692Y391200D02*
Y389700D01*
G01X401092Y391800D02*
X401692Y391200D01*
G01X401092Y401200D02*
Y391800D01*
G01X402192Y402300D02*
X401092Y401200D01*
G01X402192Y404200D02*
Y402300D01*
G01X410492Y396310D02*
Y405016D01*
G01X409092Y394910D02*
X410492Y396310D01*
G01X409092Y383300D02*
Y394910D01*
G01X406892Y381100D02*
X409092Y383300D01*
G01X406892Y372846D02*
Y381100D01*
G01X403056Y369010D02*
X406892Y372846D01*
G01X412885Y381693D02*
Y405453D01*
G01X411792Y380600D02*
X412885Y381693D01*
G01X410292Y380600D02*
X411792D01*
G01X408892Y379200D02*
X410292Y380600D01*
G01X408892Y371800D02*
Y379200D01*
G01X404192Y367100D02*
X408892Y371800D01*
G01X402392Y367100D02*
X404192D01*
G01X400842Y365550D02*
X402392Y367100D01*
G01X400842Y364326D02*
Y365550D01*
G01X399676Y363160D02*
X400842Y364326D01*
G01X387192Y405200D02*
Y485434D01*
G01X355792Y413600D02*
Y492292D01*
G01X391258Y405606D02*
Y483842D01*
G01X359792Y411826D02*
Y494928D01*
G01X358501Y410535D02*
X359792Y411826D01*
G01X358501Y405305D02*
Y410535D01*
G01X379192Y405271D02*
Y493570D01*
G01X407392Y405300D02*
X408492Y404200D01*
G01X407392Y473258D02*
Y405300D01*
G01X361792Y410997D02*
Y495758D01*
G01X360532Y409737D02*
X361792Y410997D01*
G01X360532Y404760D02*
Y409737D01*
G01X401292Y475645D02*
Y407111D01*
G01X397292Y406829D02*
Y481389D01*
G01X389192Y405821D02*
Y484605D01*
G01X399292Y476474D02*
Y407111D01*
G01X395292Y406265D02*
Y482218D01*
G01X385192Y405100D02*
Y486263D01*
G01X381192Y405204D02*
Y492741D01*
G01X357792Y413816D02*
Y492678D01*
G01X363792Y410168D02*
Y502438D01*
G01X362532Y408908D02*
X363792Y410168D01*
G01X405392Y404000D02*
Y474087D01*
G01X403292Y405300D02*
X402192Y404200D01*
G01X403292Y474816D02*
Y405300D01*
G01X393292Y405741D02*
Y483047D01*
G01X409392Y406116D02*
Y472429D01*
G01X410492Y405016D02*
X409392Y406116D01*
G01X411392Y406946D02*
Y471600D01*
G01X412885Y405453D02*
X411392Y406946D01*
G01X406341Y526349D02*
Y533049D01*
G01X405792Y525800D02*
X406341Y526349D01*
G01X405792Y517400D02*
Y525800D01*
G01X406487Y516705D02*
X405792Y517400D01*
G01X406487Y514195D02*
Y516705D01*
G01X406153Y513861D02*
X406487Y514195D01*
G01X406153Y512139D02*
Y513861D01*
G01X406514Y511778D02*
X406153Y512139D01*
G01X406514Y509222D02*
Y511778D01*
G01X397692Y500400D02*
X406514Y509222D01*
G01X397692Y495960D02*
Y500400D01*
G01X396873Y495141D02*
X397692Y495960D01*
G01X395769Y495141D02*
X396873D01*
G01X394532Y496378D02*
X395769Y495141D01*
G01X393610Y496378D02*
X394532D01*
G01X392380Y495148D02*
X393610Y496378D01*
G01X392380Y494004D02*
Y495148D01*
G01X393505Y492879D02*
X392380Y494004D01*
G01X393505Y491747D02*
Y492879D01*
G01X387192Y485434D02*
X393505Y491747D01*
G01X414126Y526266D02*
X413041Y527351D01*
G01X414126Y520534D02*
Y526266D01*
G01X412977Y519385D02*
X414126Y520534D01*
G01X412977Y516615D02*
Y519385D01*
G01X413273Y516319D02*
X412977Y516615D01*
G01X413273Y514281D02*
Y516319D01*
G01X412914Y513922D02*
X413273Y514281D01*
G01X412914Y511578D02*
Y513922D01*
G01X413153Y511339D02*
X412914Y511578D01*
G01X413153Y509305D02*
Y511339D01*
G01X407092Y503244D02*
X413153Y509305D01*
G01X407092Y499717D02*
Y503244D01*
G01X406319Y498944D02*
X407092Y499717D01*
G01X405174Y498944D02*
X406319D01*
G01X404322Y499796D02*
X405174Y498944D01*
G01X403216Y499796D02*
X404322D01*
G01X402085Y498665D02*
X403216Y499796D01*
G01X402085Y497507D02*
Y498665D01*
G01X402938Y496654D02*
X402085Y497507D01*
G01X402938Y495522D02*
Y496654D01*
G01X391258Y483842D02*
X402938Y495522D01*
G01X392792Y507170D02*
Y586502D01*
G01X379192Y493570D02*
X392792Y507170D01*
G01X421781Y487647D02*
X407392Y473258D01*
G01X356433Y506852D02*
X355398D01*
G01X357701Y505584D02*
X356433Y506852D01*
G01X357701Y504629D02*
Y505584D01*
G01X356207Y503135D02*
X357701Y504629D01*
G01X356207Y501838D02*
Y503135D01*
G01X357338Y500707D02*
X356207Y501838D01*
G01X358305Y500707D02*
X357338D01*
G01X359364Y501766D02*
X358305Y500707D01*
G01X360537Y501766D02*
X359364D01*
G01X361668Y500635D02*
X360537Y501766D01*
G01X361668Y499544D02*
Y500635D01*
G01X360403Y498279D02*
X361668Y499544D01*
G01X360403Y497147D02*
Y498279D01*
G01X361792Y495758D02*
X360403Y497147D01*
G01X415781Y490134D02*
X401292Y475645D01*
G01X415781Y494219D02*
Y490134D01*
G01X429392Y507830D02*
X415781Y494219D01*
G01X397292Y481389D02*
X422792Y506889D01*
G01X409808Y516516D02*
Y530616D01*
G01X409492Y516200D02*
X409808Y516516D01*
G01X409492Y514400D02*
Y516200D01*
G01X410292Y513600D02*
X409492Y514400D01*
G01X410292Y512000D02*
Y513600D01*
G01X409292Y511000D02*
X410292Y512000D01*
G01X409292Y509171D02*
Y511000D01*
G01X399692Y499571D02*
X409292Y509171D01*
G01X399692Y495105D02*
Y499571D01*
G01X389192Y484605D02*
X399692Y495105D01*
G01X399293Y476475D02*
X399292Y476474D01*
G01X399293Y480541D02*
Y476475D01*
G01X400436Y481684D02*
X399293Y480541D01*
G01X401588Y481684D02*
X400436D01*
G01X402531Y480741D02*
X401588Y481684D01*
G01X403587Y480741D02*
X402531D01*
G01X404776Y481930D02*
X403587Y480741D01*
G01X404776Y483022D02*
Y481930D01*
G01X403461Y484337D02*
X404776Y483022D01*
G01X403461Y485247D02*
Y484337D01*
G01X404741Y486527D02*
X403461Y485247D01*
G01X405797Y486527D02*
X404741D01*
G01X407061Y485263D02*
X405797Y486527D01*
G01X408055Y485263D02*
X407061D01*
G01X409255Y486463D02*
X408055Y485263D01*
G01X409255Y487595D02*
Y486463D01*
G01X408024Y488826D02*
X409255Y487595D01*
G01X408024Y489707D02*
Y488826D01*
G01X409412Y491095D02*
X408024Y489707D01*
G01X410281Y491095D02*
X409412D01*
G01X411635Y489741D02*
X410281Y491095D01*
G01X412533Y489741D02*
X411635D01*
G01X413781Y490989D02*
X412533Y489741D01*
G01X413781Y492121D02*
Y490989D01*
G01X412810Y493092D02*
X413781Y492121D01*
G01X412810Y494078D02*
Y493092D01*
G01X426692Y507960D02*
X412810Y494078D01*
G01X416000Y506108D02*
X417131Y507239D01*
G01X416000Y504976D02*
Y506108D01*
G01X416459Y504517D02*
X416000Y504976D01*
G01X415328Y502254D02*
X416459Y503385D01*
G01X414196Y502254D02*
X415328D01*
G01X413737Y502713D02*
X414196Y502254D01*
G01X412605Y502713D02*
X413737D01*
G01X411474Y501582D02*
X412605Y502713D01*
G01X411474Y500450D02*
Y501582D01*
G01X411933Y499991D02*
X411474Y500450D01*
G01X411933Y498859D02*
Y499991D01*
G01X395292Y482218D02*
X411933Y498859D01*
G01X403050Y520542D02*
Y530158D01*
G01X403192Y520400D02*
X403050Y520542D01*
G01X403192Y517000D02*
Y520400D01*
G01X402792Y516600D02*
X403192Y517000D01*
G01X402792Y514500D02*
Y516600D01*
G01X403592Y513700D02*
X402792Y514500D01*
G01X403592Y511900D02*
Y513700D01*
G01X402792Y511100D02*
X403592Y511900D01*
G01X402792Y508683D02*
Y511100D01*
G01X390760Y496651D02*
X402792Y508683D01*
G01X390760Y491831D02*
Y496651D01*
G01X385192Y486263D02*
X390760Y491831D01*
G01X396307Y516515D02*
Y529791D01*
G01X396140Y516348D02*
X396307Y516515D01*
G01X396140Y514352D02*
Y516348D01*
G01X396543Y513949D02*
X396140Y514352D01*
G01X396543Y511363D02*
Y513949D01*
G01X396092Y510912D02*
X396543Y511363D01*
G01X396092Y507641D02*
Y510912D01*
G01X381192Y492741D02*
X396092Y507641D01*
G01X399492Y517100D02*
Y526700D01*
G01X399886Y516706D02*
X399492Y517100D01*
G01X399886Y514186D02*
Y516706D01*
G01X399402Y513702D02*
X399886Y514186D01*
G01X399402Y511590D02*
Y513702D01*
G01X399858Y511134D02*
X399402Y511590D01*
G01X399858Y508578D02*
Y511134D01*
G01X387587Y496307D02*
X399858Y508578D01*
G01X387587Y495175D02*
Y496307D01*
G01X388710Y494052D02*
X387587Y495175D01*
G01X388710Y492920D02*
Y494052D01*
G01X387579Y491789D02*
X388710Y492920D01*
G01X386447Y491789D02*
X387579D01*
G01X385324Y492912D02*
X386447Y491789D01*
G01X384192Y492912D02*
X385324D01*
G01X383192Y491912D02*
X384192Y492912D01*
G01X356792Y524824D02*
X359615Y527647D01*
G01X356792Y509438D02*
Y524824D01*
G01X363792Y502438D02*
X356792Y509438D01*
G01X405392Y474087D02*
X419781Y488476D01*
G01X417781Y489305D02*
X403292Y474816D01*
G01X416092Y516300D02*
X417392Y517600D01*
G01X416092Y514400D02*
Y516300D01*
G01X416651Y513841D02*
X416092Y514400D01*
G01X415342Y510686D02*
X416651Y511995D01*
G01X415342Y508665D02*
Y510686D01*
G01X409092Y502415D02*
X415342Y508665D01*
G01X409092Y498847D02*
Y502415D01*
G01X393292Y483047D02*
X409092Y498847D01*
G01X409392Y472429D02*
X423781Y486818D01*
G01X411392Y471600D02*
X446743Y506951D01*
G01X409793Y582977D02*
Y588867D01*
G01X406356Y579540D02*
X409793Y582977D01*
G01X406356Y570664D02*
Y579540D01*
G01X406345Y570653D02*
X406356Y570664D01*
G01X406345Y558105D02*
Y570653D01*
G01X406371Y558079D02*
X406345Y558105D01*
G01X406371Y551879D02*
Y558079D01*
G01X406355Y551863D02*
X406371Y551879D01*
G01X406355Y533063D02*
Y551863D01*
G01X406341Y533049D02*
X406355Y533063D01*
G01X416398Y587357D02*
Y597094D01*
G01X414763Y585722D02*
X416398Y587357D01*
G01X414763Y584116D02*
Y585722D01*
G01X415373Y583506D02*
X414763Y584116D01*
G01X416645Y583506D02*
X415373D01*
G01X414500Y580896D02*
X416697D01*
G01X413070Y579466D02*
X414500Y580896D01*
G01X413070Y570478D02*
Y579466D01*
G01X413100Y570448D02*
X413070Y570478D01*
G01X413100Y562471D02*
Y570448D01*
G01X413861Y561710D02*
X413100Y562471D01*
G01X414865Y561710D02*
X413861D01*
G01X415517Y561058D02*
X414865Y561710D01*
G01X415517Y559144D02*
Y561058D01*
G01X414883Y558510D02*
X415517Y559144D01*
G01X413949Y558510D02*
X414883D01*
G01X413143Y557704D02*
X413949Y558510D01*
G01X413143Y551651D02*
Y557704D01*
G01X413129Y551637D02*
X413143Y551651D01*
G01X413129Y539537D02*
Y551637D01*
G01X413041Y539449D02*
X413129Y539537D01*
G01X413041Y527351D02*
Y539449D01*
G01X392792Y586502D02*
X394682Y588392D01*
G01X413099Y583009D02*
Y588857D01*
G01X409780Y579690D02*
X413099Y583009D01*
G01X409780Y573992D02*
Y579690D01*
G01X410045Y573727D02*
X409780Y573992D01*
G01X410045Y568753D02*
Y573727D01*
G01X409808Y568516D02*
X410045Y568753D01*
G01X409808Y563984D02*
Y568516D01*
G01X409706Y563882D02*
X409808Y563984D01*
G01X409706Y553385D02*
Y563882D01*
G01X409892Y553199D02*
X409706Y553385D01*
G01X409892Y549400D02*
Y553199D01*
G01X409793Y549301D02*
X409892Y549400D01*
G01X409793Y545699D02*
Y549301D01*
G01X410192Y545300D02*
X409793Y545699D01*
G01X410192Y539358D02*
Y545300D01*
G01X409793Y538959D02*
X410192Y539358D01*
G01X409793Y534375D02*
Y538959D01*
G01X409992Y534176D02*
X409793Y534375D01*
G01X409992Y530800D02*
Y534176D01*
G01X409808Y530616D02*
X409992Y530800D01*
G01X406341Y582881D02*
Y591914D01*
G01X403035Y579575D02*
X406341Y582881D01*
G01X403035Y570657D02*
Y579575D01*
G01X403079Y570613D02*
X403035Y570657D01*
G01X403079Y563813D02*
Y570613D01*
G01X403392Y563500D02*
X403079Y563813D01*
G01X403392Y558048D02*
Y563500D01*
G01X403109Y557765D02*
X403392Y558048D01*
G01X403109Y549317D02*
Y557765D01*
G01X403021Y549229D02*
X403109Y549317D01*
G01X403021Y532871D02*
Y549229D01*
G01X403192Y532700D02*
X403021Y532871D01*
G01X403192Y530300D02*
Y532700D01*
G01X403050Y530158D02*
X403192Y530300D01*
G01X396306Y587014D02*
X398029Y588737D01*
G01X396306Y571086D02*
Y587014D01*
G01X396497Y570895D02*
X396306Y571086D01*
G01X396497Y568305D02*
Y570895D01*
G01X396194Y568002D02*
X396497Y568305D01*
G01X396194Y563978D02*
Y568002D01*
G01X396409Y563763D02*
X396194Y563978D01*
G01X396409Y549517D02*
Y563763D01*
G01X396192Y549300D02*
X396409Y549517D01*
G01X396192Y546200D02*
Y549300D01*
G01X396321Y546071D02*
X396192Y546200D01*
G01X396321Y529805D02*
Y546071D01*
G01X396307Y529791D02*
X396321Y529805D01*
G01X402999Y587207D02*
X404723Y588931D01*
G01X402999Y583079D02*
Y587207D01*
G01X399744Y579824D02*
X402999Y583079D01*
G01X399744Y563408D02*
Y579824D01*
G01X400341Y562811D02*
X399744Y563408D01*
G01X400341Y557649D02*
Y562811D01*
G01X399656Y556964D02*
X400341Y557649D01*
G01X399656Y554436D02*
Y556964D01*
G01X399747Y554345D02*
X399656Y554436D01*
G01X399747Y533055D02*
Y554345D01*
G01X399744Y533052D02*
X399747Y533055D01*
G01X399744Y526952D02*
Y533052D01*
G01X399492Y526700D02*
X399744Y526952D01*
G01X356156Y574016D02*
Y577336D01*
G01X355757Y573617D02*
X356156Y574016D01*
G01X355757Y568357D02*
Y573617D01*
G01X356153Y567961D02*
X355757Y568357D01*
G01X356153Y560365D02*
Y567961D01*
G01X359615Y556903D02*
X356153Y560365D01*
G01X359615Y527647D02*
Y556903D01*
G01X416391Y577999D02*
X419792Y581400D01*
G01X416391Y564801D02*
Y577999D01*
G01X417492Y563700D02*
X416391Y564801D01*
G01X416376Y556598D02*
X417492Y557714D01*
G01X416376Y549214D02*
Y556598D01*
G01X416391Y549199D02*
X416376Y549214D01*
G01X416391Y527201D02*
Y549199D01*
G01X417392Y526200D02*
X416391Y527201D01*
G01X413892Y606423D02*
X414761Y607292D01*
G01X413892Y596166D02*
Y606423D01*
G01X413143Y595417D02*
X413892Y596166D01*
G01X413143Y592217D02*
Y595417D01*
G01X409793Y588867D02*
X413143Y592217D01*
G01X414761Y610061D02*
Y612657D01*
G01X416561Y608261D02*
X414761Y610061D01*
G01X416308Y605516D02*
X416561Y605769D01*
G01X416308Y597184D02*
Y605516D01*
G01X416398Y597094D02*
X416308Y597184D01*
G01X394682Y610010D02*
Y612657D01*
G01X396409Y608283D02*
X394682Y610010D01*
G01X396409Y606417D02*
Y608283D01*
G01X396057Y606065D02*
X396409Y606417D01*
G01X396057Y597097D02*
Y606065D01*
G01X394682Y595722D02*
X396057Y597097D01*
G01X394682Y588392D02*
Y595722D01*
G01X414763Y590521D02*
Y593657D01*
G01X413099Y588857D02*
X414763Y590521D01*
G01X406774Y605998D02*
X408068Y607292D01*
G01X406774Y603487D02*
Y605998D01*
G01X407666Y602595D02*
X406774Y603487D01*
G01X411471Y602595D02*
X407666D01*
G01X412116Y601950D02*
X411471Y602595D01*
G01X412116Y600462D02*
Y601950D01*
G01X411361Y599707D02*
X412116Y600462D01*
G01X406554Y599707D02*
X411361D01*
G01X405818Y598971D02*
X406554Y599707D01*
G01X405818Y597065D02*
Y598971D01*
G01X406535Y596348D02*
X405818Y597065D01*
G01X407569Y596348D02*
X406535D01*
G01X408069Y595848D02*
X407569Y596348D01*
G01X408069Y593642D02*
Y595848D01*
G01X406341Y591914D02*
X408069Y593642D01*
G01X398531Y603997D02*
X398029Y604499D01*
G01X398531Y594144D02*
Y603997D01*
G01X398029Y593642D02*
X398531Y594144D01*
G01X398029Y588737D02*
Y593642D01*
G01X404143Y603920D02*
X404722Y604499D01*
G01X404143Y594237D02*
Y603920D01*
G01X404723Y593657D02*
X404143Y594237D01*
G01X404723Y588931D02*
Y593657D01*
G01X443146Y-42355D02*
G02Y-45915I0J-1780D01*
G01X416971Y59D02*
Y4249D01*
G01X417553Y-523D02*
X416971Y59D01*
G01X418543Y-523D02*
X417553D01*
G01X419181Y115D02*
X418543Y-523D01*
G01X419181Y6579D02*
Y115D01*
G01X418571Y7189D02*
X419181Y6579D01*
G01X444880Y5612D02*
Y-4536D01*
G01X443256Y7236D02*
X444880Y5612D01*
G01X443256Y18636D02*
Y7236D01*
G01X439819Y22073D02*
X443256Y18636D01*
G01X439819Y29375D02*
Y22073D01*
G01X439535Y29659D02*
X439819Y29375D01*
G01X439535Y31659D02*
Y29659D01*
G01X440135Y32259D02*
X439535Y31659D01*
G01X440135Y34559D02*
Y32259D01*
G01X445819Y10061D02*
X444880Y9122D01*
G01X445819Y14911D02*
Y10061D01*
G01X446992Y16084D02*
X445819Y14911D01*
G01X446992Y26258D02*
Y16084D01*
G01X446489Y26761D02*
X446992Y26258D01*
G01X446489Y51894D02*
Y26761D01*
G01X444880Y-8032D02*
Y-9786D01*
G01X439592Y-2744D02*
X444880Y-8032D01*
G01X439592Y-600D02*
Y-2744D01*
G01X439819Y-373D02*
X439592Y-600D01*
G01X439819Y18672D02*
Y-373D01*
G01X436584Y21907D02*
X439819Y18672D01*
G01X436584Y29508D02*
Y21907D01*
G01X437035Y29959D02*
X436584Y29508D01*
G01X437035Y31359D02*
Y29959D01*
G01X436501Y31893D02*
X437035Y31359D01*
G01X436501Y38176D02*
Y31893D01*
G01X426516Y22046D02*
Y36846D01*
G01X430392Y18170D02*
X426516Y22046D01*
G01X430392Y18144D02*
Y18170D01*
G01X431494Y17042D02*
X430392Y18144D01*
G01X431773Y30435D02*
Y33325D01*
G01X433235Y28973D02*
X431773Y30435D01*
G01X433235Y22011D02*
Y28973D01*
G01X438187Y17059D02*
X433235Y22011D01*
G01X423791Y30101D02*
Y33457D01*
G01X423070Y29380D02*
X423791Y30101D01*
G01X423070Y22663D02*
Y29380D01*
G01X426408Y19325D02*
X423070Y22663D01*
G01X426408Y15784D02*
Y19325D01*
G01X429757Y12435D02*
X426408Y15784D01*
G01X429757Y235D02*
Y12435D01*
G01X430092Y-100D02*
X429757Y235D01*
G01X430092Y-3000D02*
Y-100D01*
G01X429692Y-3400D02*
X430092Y-3000D01*
G01X429692Y-5400D02*
Y-3400D01*
G01X431494Y-7202D02*
X429692Y-5400D01*
G01X431494Y-9901D02*
Y-7202D01*
G01X429764Y21628D02*
Y53689D01*
G01X433107Y18285D02*
X429764Y21628D01*
G01X433107Y16285D02*
Y18285D01*
G01X431633Y14811D02*
X433107Y16285D01*
G01X431633Y11652D02*
Y14811D01*
G01X433233Y10052D02*
X431633Y11652D01*
G01X433233Y541D02*
Y10052D01*
G01X433008Y316D02*
X433233Y541D01*
G01X433008Y-2516D02*
Y316D01*
G01X438187Y-7695D02*
X433008Y-2516D01*
G01X438187Y-9786D02*
Y-7695D01*
G01X424801Y-7711D02*
Y-9786D01*
G01X423074Y-5984D02*
X424801Y-7711D01*
G01X423074Y-3338D02*
Y-5984D01*
G01X423491Y-2921D02*
X423074Y-3338D01*
G01X423491Y1294D02*
Y-2921D01*
G01X423074Y1711D02*
X423491Y1294D01*
G01X423074Y9918D02*
Y1711D01*
G01X422042Y10950D02*
X423074Y9918D01*
G01X420820Y10950D02*
X422042D01*
G01X419302Y12468D02*
X420820Y10950D01*
G01X419302Y14431D02*
Y12468D01*
G01X419815Y14944D02*
X419302Y14431D01*
G01X419815Y20259D02*
Y14944D01*
G01X424020Y17823D02*
X424801Y17042D01*
G01X424020Y18883D02*
Y17823D01*
G01X419816Y23087D02*
X424020Y18883D01*
G01X419816Y29006D02*
Y23087D01*
G01X418754Y30068D02*
X419816Y29006D01*
G01X418754Y33520D02*
Y30068D01*
G01X444880Y21012D02*
Y17059D01*
G01X443244Y22648D02*
X444880Y21012D01*
G01X443244Y31824D02*
Y22648D01*
G01X443257Y31837D02*
X443244Y31824D01*
G01X443257Y38491D02*
Y31837D01*
G01X453445Y72588D02*
X454533Y71500D01*
G01X453445Y74468D02*
Y72588D01*
G01X452012Y75901D02*
X453445Y74468D01*
G01X452012Y77100D02*
Y75901D01*
G01X453512Y78600D02*
X452012Y77100D01*
G01X453512Y79800D02*
Y78600D01*
G01X452062Y81250D02*
X453512Y79800D01*
G01X452062Y82649D02*
Y81250D01*
G01X453445Y84032D02*
X452062Y82649D01*
G01X453445Y85901D02*
Y84032D01*
G01X450645Y88701D02*
X453445Y85901D01*
G01X450645Y91829D02*
Y88701D01*
G01X451573Y92757D02*
X450645Y91829D01*
G01X439825Y34869D02*
X440135Y34559D01*
G01X439825Y37249D02*
Y34869D01*
G01X440135Y37559D02*
X439825Y37249D01*
G01X440135Y43644D02*
Y37559D01*
G01X439813Y43966D02*
X440135Y43644D01*
G01X439813Y50418D02*
Y43966D01*
G01X440235Y50840D02*
X439813Y50418D01*
G01X440235Y53174D02*
Y50840D01*
G01X439814Y53595D02*
X440235Y53174D01*
G01X439814Y67180D02*
Y53595D01*
G01X439535Y67459D02*
X439814Y67180D01*
G01X439535Y69459D02*
Y67459D01*
G01X440135Y70059D02*
X439535Y69459D01*
G01X440135Y72359D02*
Y70059D01*
G01X439803Y72691D02*
X440135Y72359D01*
G01X439803Y75027D02*
Y72691D01*
G01X440135Y75359D02*
X439803Y75027D01*
G01X440135Y85674D02*
Y75359D01*
G01X439535Y86274D02*
X440135Y85674D01*
G01X439535Y88174D02*
Y86274D01*
G01X440235Y88874D02*
X439535Y88174D01*
G01X440235Y90974D02*
Y88874D01*
G01X439535Y91674D02*
X440235Y90974D01*
G01X439535Y95956D02*
Y91674D01*
G01X446835Y52240D02*
X446489Y51894D01*
G01X446835Y97745D02*
Y52240D01*
G01X474998Y66953D02*
Y65699D01*
G01X477545Y69500D02*
X474998Y66953D01*
G01X478545Y69500D02*
X477545D01*
G01X436835Y38983D02*
X436501Y38176D01*
G01X436835Y45374D02*
Y38983D01*
G01X436565Y45644D02*
X436835Y45374D01*
G01X436565Y48104D02*
Y45644D01*
G01X436835Y48374D02*
X436565Y48104D01*
G01X436835Y50574D02*
Y48374D01*
G01X436235Y51174D02*
X436835Y50574D01*
G01X436235Y53174D02*
Y51174D01*
G01X436582Y53521D02*
X436235Y53174D01*
G01X436582Y67306D02*
Y53521D01*
G01X437035Y67759D02*
X436582Y67306D01*
G01X437035Y69159D02*
Y67759D01*
G01X436235Y69959D02*
X437035Y69159D01*
G01X436235Y72159D02*
Y69959D01*
G01X436549Y72473D02*
X436235Y72159D01*
G01X436549Y83460D02*
Y72473D01*
G01X436235Y83774D02*
X436549Y83460D01*
G01X436235Y85574D02*
Y83774D01*
G01X436835Y86174D02*
X436235Y85574D01*
G01X436835Y88374D02*
Y86174D01*
G01X436235Y88974D02*
X436835Y88374D01*
G01X436235Y90974D02*
Y88974D01*
G01X436835Y91574D02*
X436235Y90974D01*
G01X436835Y95656D02*
Y91574D01*
G01X460045Y72367D02*
X460912Y71500D01*
G01X460045Y74668D02*
Y72367D01*
G01X458412Y76301D02*
X460045Y74668D01*
G01X458412Y77600D02*
Y76301D01*
G01X459762Y78950D02*
X458412Y77600D01*
G01X459762Y79850D02*
Y78950D01*
G01X458512Y81100D02*
X459762Y79850D01*
G01X458512Y82299D02*
Y81100D01*
G01X460045Y83832D02*
X458512Y82299D01*
G01X460045Y85800D02*
Y83832D01*
G01X457145Y88700D02*
X460045Y85800D01*
G01X457145Y91636D02*
Y88700D01*
G01X458266Y92757D02*
X457145Y91636D01*
G01X426292Y91531D02*
Y95700D01*
G01X426849Y90974D02*
X426292Y91531D01*
G01X426849Y88874D02*
Y90974D01*
G01X426149Y88174D02*
X426849Y88874D01*
G01X426149Y86274D02*
Y88174D01*
G01X427320Y85103D02*
X426149Y86274D01*
G01X427320Y82398D02*
Y85103D01*
G01X426710Y81788D02*
X427320Y82398D01*
G01X425505Y81788D02*
X426710D01*
G01X424858Y81141D02*
X425505Y81788D01*
G01X424858Y79751D02*
Y81141D01*
G01X425431Y79178D02*
X424858Y79751D01*
G01X426710Y79178D02*
X425431D01*
G01X427320Y78568D02*
X426710Y79178D01*
G01X427320Y75434D02*
Y78568D01*
G01X426511Y74625D02*
X427320Y75434D01*
G01X426511Y72597D02*
Y74625D01*
G01X426749Y72359D02*
X426511Y72597D01*
G01X426749Y70059D02*
Y72359D01*
G01X426149Y69459D02*
X426749Y70059D01*
G01X426149Y67459D02*
Y69459D01*
G01X426521Y67087D02*
X426149Y67459D01*
G01X426521Y57449D02*
Y67087D01*
G01X426429Y57357D02*
X426521Y57449D01*
G01X426429Y53594D02*
Y57357D01*
G01X426849Y53174D02*
X426429Y53594D01*
G01X426849Y51074D02*
Y53174D01*
G01X426149Y50374D02*
X426849Y51074D01*
G01X426149Y48474D02*
Y50374D01*
G01X426541Y48082D02*
X426149Y48474D01*
G01X426541Y46001D02*
Y48082D01*
G01X427466Y45076D02*
X426541Y46001D01*
G01X427466Y43402D02*
Y45076D01*
G01X426856Y42792D02*
X427466Y43402D01*
G01X425637Y42792D02*
X426856D01*
G01X425027Y42182D02*
X425637Y42792D01*
G01X425027Y40792D02*
Y42182D01*
G01X425637Y40182D02*
X425027Y40792D01*
G01X426856Y40182D02*
X425637D01*
G01X427466Y39572D02*
X426856Y40182D01*
G01X427466Y37796D02*
Y39572D01*
G01X426516Y36846D02*
X427466Y37796D01*
G01X432492Y92231D02*
Y95599D01*
G01X433449Y91274D02*
X432492Y92231D01*
G01X433449Y89224D02*
Y91274D01*
G01X432449Y88224D02*
X433449Y89224D01*
G01X432449Y86474D02*
Y88224D01*
G01X433210Y85713D02*
X432449Y86474D01*
G01X433210Y72472D02*
Y85713D01*
G01X431723Y70985D02*
X433210Y72472D01*
G01X431723Y68285D02*
Y70985D01*
G01X433222Y66786D02*
X431723Y68285D01*
G01X433222Y57850D02*
Y66786D01*
G01X433103Y57731D02*
X433222Y57850D01*
G01X433103Y53820D02*
Y57731D01*
G01X431748Y52465D02*
X433103Y53820D01*
G01X431748Y49375D02*
Y52465D01*
G01X433228Y47895D02*
X431748Y49375D01*
G01X433228Y34780D02*
Y47895D01*
G01X431773Y33325D02*
X433228Y34780D01*
G01X476870Y73374D02*
X478344Y71900D01*
G01X476870Y74468D02*
Y73374D01*
G01X475437Y75901D02*
X476870Y74468D01*
G01X475437Y77124D02*
Y75901D01*
G01X476937Y78624D02*
X475437Y77124D01*
G01X476937Y79976D02*
Y78624D01*
G01X475437Y81476D02*
X476937Y79976D01*
G01X475437Y82599D02*
Y81476D01*
G01X477112Y84274D02*
X475437Y82599D01*
G01X477112Y85659D02*
Y84274D01*
G01X474070Y88701D02*
X477112Y85659D01*
G01X474070Y91829D02*
Y88701D01*
G01X474998Y92757D02*
X474070Y91829D01*
G01X423449Y93342D02*
X417392Y99399D01*
G01X423449Y91574D02*
Y93342D01*
G01X422849Y90974D02*
X423449Y91574D01*
G01X422849Y88974D02*
Y90974D01*
G01X423449Y88374D02*
X422849Y88974D01*
G01X423449Y86174D02*
Y88374D01*
G01X422849Y85574D02*
X423449Y86174D01*
G01X422849Y75242D02*
Y85574D01*
G01X423076Y75015D02*
X422849Y75242D01*
G01X423076Y71608D02*
Y75015D01*
G01X423649Y71035D02*
X423076Y71608D01*
G01X423649Y67759D02*
Y71035D01*
G01X423075Y67185D02*
X423649Y67759D01*
G01X423075Y57451D02*
Y67185D01*
G01X423168Y57358D02*
X423075Y57451D01*
G01X423168Y48093D02*
Y57358D01*
G01X423065Y47990D02*
X423168Y48093D01*
G01X423065Y34183D02*
Y47990D01*
G01X423791Y33457D02*
X423065Y34183D01*
G01X451573Y67253D02*
Y65699D01*
G01X453820Y69500D02*
X451573Y67253D01*
G01X455044Y69500D02*
X453820D01*
G01X456620Y71076D02*
X455044Y69500D01*
G01X456620Y72700D02*
Y71076D01*
G01X455845Y73475D02*
X456620Y72700D01*
G01X455845Y86488D02*
Y73475D01*
G01X454619Y87714D02*
X455845Y86488D01*
G01X430080Y91805D02*
Y95012D01*
G01X429349Y91074D02*
X430080Y91805D01*
G01X429349Y88974D02*
Y91074D01*
G01X430049Y88274D02*
X429349Y88974D01*
G01X430049Y86374D02*
Y88274D01*
G01X429549Y85874D02*
X430049Y86374D01*
G01X429549Y83942D02*
Y85874D01*
G01X429764Y83727D02*
X429549Y83942D01*
G01X429764Y72674D02*
Y83727D01*
G01X429549Y72459D02*
X429764Y72674D01*
G01X429549Y69959D02*
Y72459D01*
G01X429776Y69732D02*
X429549Y69959D01*
G01X429776Y57381D02*
Y69732D01*
G01X429881Y57276D02*
X429776Y57381D01*
G01X429881Y53806D02*
Y57276D01*
G01X429764Y53689D02*
X429881Y53806D01*
G01X416663Y88274D02*
Y86374D01*
G01X416694Y94299D02*
Y91805D01*
G01X419838Y34604D02*
X418754Y33520D01*
G01X419838Y41454D02*
Y34604D01*
G01X418996Y42296D02*
X419838Y41454D01*
G01X418996Y44064D02*
Y42296D01*
G01X419838Y44906D02*
X418996Y44064D01*
G01X419838Y47899D02*
Y44906D01*
G01X418802Y48935D02*
X419838Y47899D01*
G01X418802Y52699D02*
Y48935D01*
G01X419820Y53717D02*
X418802Y52699D01*
G01X419820Y56336D02*
Y53717D01*
G01X420647Y57163D02*
X419820Y56336D01*
G01X420647Y58724D02*
Y57163D01*
G01X419821Y59550D02*
X420647Y58724D01*
G01X419821Y61334D02*
Y59550D01*
G01X420379Y61892D02*
X419821Y61334D01*
G01X420379Y64174D02*
Y61892D01*
G01X419820Y64733D02*
X420379Y64174D01*
G01X419820Y66802D02*
Y64733D01*
G01X419063Y67559D02*
X419820Y66802D01*
G01X419063Y70959D02*
Y67559D01*
G01X419831Y71727D02*
X419063Y70959D01*
G01X419831Y75627D02*
Y71727D01*
G01X420866Y76662D02*
X419831Y75627D01*
G01X420866Y79103D02*
Y76662D01*
G01X420256Y79713D02*
X420866Y79103D01*
G01X419000Y79713D02*
X420256D01*
G01X418390Y80323D02*
X419000Y79713D01*
G01X418390Y81713D02*
Y80323D01*
G01X419000Y82323D02*
X418390Y81713D01*
G01X420256Y82323D02*
X419000D01*
G01X420866Y82933D02*
X420256Y82323D01*
G01X420866Y84671D02*
Y82933D01*
G01X419063Y86474D02*
X420866Y84671D01*
G01X419063Y88224D02*
Y86474D01*
G01X420063Y89224D02*
X419063Y88224D01*
G01X420063Y91274D02*
Y89224D01*
G01X419063Y92274D02*
X420063Y91274D01*
G01X419063Y94829D02*
Y92274D01*
G01X443501Y38735D02*
X443257Y38491D01*
G01X443501Y43323D02*
Y38735D01*
G01X443238Y43586D02*
X443501Y43323D01*
G01X443238Y50433D02*
Y43586D01*
G01X442735Y50936D02*
X443238Y50433D01*
G01X442735Y52742D02*
Y50936D01*
G01X443249Y53256D02*
X442735Y52742D01*
G01X443249Y55822D02*
Y53256D01*
G01X442114Y56957D02*
X443249Y55822D01*
G01X442114Y58435D02*
Y56957D01*
G01X442830Y59151D02*
X442114Y58435D01*
G01X444415Y59151D02*
X442830D01*
G01X445025Y59761D02*
X444415Y59151D01*
G01X445025Y61151D02*
Y59761D01*
G01X444415Y61761D02*
X445025Y61151D01*
G01X442928Y61761D02*
X444415D01*
G01X442229Y62460D02*
X442928Y61761D01*
G01X442229Y63896D02*
Y62460D01*
G01X443249Y64916D02*
X442229Y63896D01*
G01X443249Y67860D02*
Y64916D01*
G01X442357Y68752D02*
X443249Y67860D01*
G01X442357Y71227D02*
Y68752D01*
G01X443249Y72119D02*
X442357Y71227D01*
G01X443249Y75443D02*
Y72119D01*
G01X442935Y75757D02*
X443249Y75443D01*
G01X442935Y85874D02*
Y75757D01*
G01X443435Y86374D02*
X442935Y85874D01*
G01X443435Y88274D02*
Y86374D01*
G01X442735Y88974D02*
X443435Y88274D01*
G01X442735Y91074D02*
Y88974D01*
G01X444923Y93262D02*
X442735Y91074D01*
G01X444923Y96828D02*
Y93262D01*
G01X458266Y67821D02*
Y65699D01*
G01X460145Y69700D02*
X458266Y67821D01*
G01X461545Y69700D02*
X460145D01*
G01X463001Y71156D02*
X461545Y69700D01*
G01X463001Y72500D02*
Y71156D01*
G01X462385Y73116D02*
X463001Y72500D01*
G01X462385Y86241D02*
Y73116D01*
G01X460912Y87714D02*
X462385Y86241D01*
G01X454868Y168824D02*
X485792Y137900D01*
G01X432292Y103199D02*
X439535Y95956D01*
G01X432292Y106630D02*
Y103199D01*
G01X462492Y104900D02*
X479865D01*
G01X461148Y106244D02*
X462492Y104900D01*
G01X460286Y106244D02*
X461148D01*
G01X458898Y104856D02*
X460286Y106244D01*
G01X458036Y104856D02*
X458898D01*
G01X457052Y105840D02*
X458036Y104856D01*
G01X457052Y106702D02*
Y105840D01*
G01X458440Y108090D02*
X457052Y106702D01*
G01X458440Y108952D02*
Y108090D01*
G01X453764Y113628D02*
X458440Y108952D01*
G01X452564Y113628D02*
X453764D01*
G01X451056Y115136D02*
X452564Y113628D01*
G01X451056Y116336D02*
Y115136D01*
G01X426592Y140800D02*
X451056Y116336D01*
G01X426592Y184999D02*
Y140800D01*
G01X447592Y162301D02*
X480793Y129100D01*
G01X430192Y102299D02*
X436835Y95656D01*
G01X430192Y105901D02*
Y102299D01*
G01X419598Y100630D02*
Y108005D01*
G01X421716Y98512D02*
X419598Y100630D01*
G01X423480Y98512D02*
X421716D01*
G01X426292Y95700D02*
X423480Y98512D01*
G01X472942Y143551D02*
X483993Y132500D01*
G01X469342Y143551D02*
X472942D01*
G01X449592Y163301D02*
X469342Y143551D01*
G01X425592Y102499D02*
Y107671D01*
G01X432492Y95599D02*
X425592Y102499D01*
G01X417392Y99399D02*
Y107381D01*
G01X476193Y98100D02*
X479592D01*
G01X474593Y99700D02*
X476193Y98100D01*
G01X472791Y99700D02*
X474593D01*
G01X471191Y98100D02*
X472791Y99700D01*
G01X469793Y98100D02*
X471191D01*
G01X468193Y99700D02*
X469793Y98100D01*
G01X466791Y99700D02*
X468193D01*
G01X465191Y98100D02*
X466791Y99700D01*
G01X463501Y98100D02*
X465191D01*
G01X462601Y99000D02*
X463501Y98100D01*
G01X460191Y99000D02*
X462601D01*
G01X459291Y98100D02*
X460191Y99000D01*
G01X455292Y98100D02*
X459291D01*
G01X421692Y131700D02*
X455292Y98100D01*
G01X421692Y184700D02*
Y131700D01*
G01X454691Y95800D02*
X478356D01*
G01X417192Y133299D02*
X454691Y95800D01*
G01X417192Y155406D02*
Y133299D01*
G01X417802Y156016D02*
X417192Y155406D01*
G01X418982Y156016D02*
X417802D01*
G01X419592Y156626D02*
X418982Y156016D01*
G01X423492Y101600D02*
Y106941D01*
G01X430080Y95012D02*
X423492Y101600D01*
G01X474392Y123200D02*
X507329D01*
G01X440092Y157500D02*
X474392Y123200D01*
G01X443969Y97782D02*
X444923Y96828D01*
G01X442839Y97782D02*
X443969D01*
G01X442291Y97234D02*
X442839Y97782D01*
G01X441160Y97234D02*
X442291D01*
G01X440027Y98367D02*
X441160Y97234D01*
G01X440027Y99497D02*
Y98367D01*
G01X440576Y100045D02*
X440027Y99497D01*
G01X440576Y101175D02*
Y100045D01*
G01X439443Y102308D02*
X440576Y101175D01*
G01X438313Y102308D02*
X439443D01*
G01X437765Y101760D02*
X438313Y102308D01*
G01X436634Y101760D02*
X437765D01*
G01X435501Y102893D02*
X436634Y101760D01*
G01X435501Y104023D02*
Y102893D01*
G01X436050Y104571D02*
X435501Y104023D01*
G01X436050Y105701D02*
Y104571D01*
G01X475792Y126000D02*
X508066D01*
G01X441992Y159800D02*
X475792Y126000D01*
G01X471206Y148284D02*
X484890Y134600D01*
G01X470344Y148284D02*
X471206D01*
G01X469423Y147363D02*
X470344Y148284D01*
G01X468630Y147363D02*
X469423D01*
G01X467577Y148416D02*
X468630Y147363D01*
G01X467577Y149209D02*
Y148416D01*
G01X468498Y150130D02*
X467577Y149209D01*
G01X468498Y150992D02*
Y150130D01*
G01X467514Y151976D02*
X468498Y150992D01*
G01X466652Y151976D02*
X467514D01*
G01X465716Y151039D02*
X466652Y151976D01*
G01X464854Y151039D02*
X465716D01*
G01X463870Y152023D02*
X464854Y151039D01*
G01X463870Y152885D02*
Y152023D01*
G01X464806Y153822D02*
X463870Y152885D01*
G01X464806Y154684D02*
Y153822D01*
G01X463822Y155668D02*
X464806Y154684D01*
G01X462960Y155668D02*
X463822D01*
G01X462024Y154731D02*
X462960Y155668D01*
G01X461162Y154731D02*
X462024D01*
G01X460178Y155715D02*
X461162Y154731D01*
G01X460178Y156577D02*
Y155715D01*
G01X467391Y118300D02*
X505156D01*
G01X442492Y143199D02*
X467391Y118300D01*
G01X442492Y145000D02*
Y143199D01*
G01X439582Y147910D02*
X442492Y145000D01*
G01X437781Y147910D02*
X439582D01*
G01X436292Y149399D02*
X437781Y147910D01*
G01X436292Y185900D02*
Y149399D01*
G01X472792Y120700D02*
X506292D01*
G01X438192Y155300D02*
X472792Y120700D01*
G01X438192Y186200D02*
Y155300D01*
G01X454792Y101700D02*
X479528D01*
G01X440297Y116195D02*
X454792Y101700D01*
G01X440297Y117057D02*
Y116195D01*
G01X441735Y118495D02*
X440297Y117057D01*
G01X441735Y119357D02*
Y118495D01*
G01X440751Y120341D02*
X441735Y119357D01*
G01X439889Y120341D02*
X440751D01*
G01X438451Y118903D02*
X439889Y120341D01*
G01X437589Y118903D02*
X438451D01*
G01X436605Y119887D02*
X437589Y118903D01*
G01X436605Y120749D02*
Y119887D01*
G01X438043Y122187D02*
X436605Y120749D01*
G01X438043Y123049D02*
Y122187D01*
G01X437059Y124033D02*
X438043Y123049D01*
G01X436197Y124033D02*
X437059D01*
G01X434759Y122595D02*
X436197Y124033D01*
G01X433897Y122595D02*
X434759D01*
G01X432913Y123579D02*
X433897Y122595D01*
G01X432913Y124441D02*
Y123579D01*
G01X434351Y125879D02*
X432913Y124441D01*
G01X434351Y126741D02*
Y125879D01*
G01X433367Y127725D02*
X434351Y126741D01*
G01X432505Y127725D02*
X433367D01*
G01X431067Y126287D02*
X432505Y127725D01*
G01X430205Y126287D02*
X431067D01*
G01X424692Y131800D02*
X430205Y126287D01*
G01X424692Y185300D02*
Y131800D01*
G01X454868Y188936D02*
Y168824D01*
G01X471108Y174283D02*
X493391Y152000D01*
G01X471108Y193596D02*
Y174283D01*
G01X447592Y169966D02*
Y162301D01*
G01X447032Y170526D02*
X447592Y169966D01*
G01X445552Y170526D02*
X447032D01*
G01X444992Y171086D02*
X445552Y170526D01*
G01X444992Y172526D02*
Y171086D01*
G01X445552Y173086D02*
X444992Y172526D01*
G01X447032Y173086D02*
X445552D01*
G01X447592Y173646D02*
X447032Y173086D01*
G01X447592Y176251D02*
Y173646D01*
G01X446982Y176861D02*
X447592Y176251D01*
G01X445702Y176861D02*
X446982D01*
G01X445092Y177471D02*
X445702Y176861D01*
G01X445092Y178861D02*
Y177471D01*
G01X445702Y179471D02*
X445092Y178861D01*
G01X446982Y179471D02*
X445702D01*
G01X447592Y180081D02*
X446982Y179471D01*
G01X447592Y181471D02*
Y180081D01*
G01X446982Y182081D02*
X447592Y181471D01*
G01X445702Y182081D02*
X446982D01*
G01X445092Y182691D02*
X445702Y182081D01*
G01X445092Y184081D02*
Y182691D01*
G01X445702Y184691D02*
X445092Y184081D01*
G01X446982Y184691D02*
X445702D01*
G01X447592Y185301D02*
X446982Y184691D01*
G01X447592Y186691D02*
Y185301D01*
G01X446982Y187301D02*
X447592Y186691D01*
G01X445702Y187301D02*
X446982D01*
G01X445092Y187911D02*
X445702Y187301D01*
G01X445092Y191310D02*
Y187911D01*
G01X447218Y193436D02*
X445092Y191310D01*
G01X466008Y173484D02*
X491592Y147900D01*
G01X466008Y190596D02*
Y173484D01*
G01X468558Y173634D02*
X492292Y149900D01*
G01X468558Y190596D02*
Y173634D01*
G01X449592Y193260D02*
Y163301D01*
G01X449768Y193436D02*
X449592Y193260D01*
G01X477902Y185327D02*
X483082D01*
G01X477292Y185937D02*
X477902Y185327D01*
G01X477292Y187327D02*
Y185937D01*
G01X477902Y187937D02*
X477292Y187327D01*
G01X483282Y187937D02*
X477902D01*
G01X419592Y158016D02*
Y156626D01*
G01X418982Y158626D02*
X419592Y158016D01*
G01X417802Y158626D02*
X418982D01*
G01X417192Y159236D02*
X417802Y158626D01*
G01X417192Y160626D02*
Y159236D01*
G01X417802Y161236D02*
X417192Y160626D01*
G01X418982Y161236D02*
X417802D01*
G01X419592Y161846D02*
X418982Y161236D01*
G01X419592Y163236D02*
Y161846D01*
G01X418982Y163846D02*
X419592Y163236D01*
G01X417802Y163846D02*
X418982D01*
G01X417192Y164456D02*
X417802Y163846D01*
G01X417192Y165846D02*
Y164456D01*
G01X417802Y166456D02*
X417192Y165846D01*
G01X418982Y166456D02*
X417802D01*
G01X419592Y167066D02*
X418982Y166456D01*
G01X419592Y168456D02*
Y167066D01*
G01X418982Y169066D02*
X419592Y168456D01*
G01X417802Y169066D02*
X418982D01*
G01X417192Y169676D02*
X417802Y169066D01*
G01X417192Y171066D02*
Y169676D01*
G01X417802Y171676D02*
X417192Y171066D01*
G01X418982Y171676D02*
X417802D01*
G01X419592Y172286D02*
X418982Y171676D01*
G01X419592Y173676D02*
Y172286D01*
G01X418982Y174286D02*
X419592Y173676D01*
G01X417802Y174286D02*
X418982D01*
G01X417192Y174896D02*
X417802Y174286D01*
G01X417192Y176286D02*
Y174896D01*
G01X417802Y176896D02*
X417192Y176286D01*
G01X418982Y176896D02*
X417802D01*
G01X419592Y177506D02*
X418982Y176896D01*
G01X419592Y185535D02*
Y177506D01*
G01X473658Y175133D02*
X494591Y154200D01*
G01X473658Y193596D02*
Y175133D01*
G01X440092Y186600D02*
Y157500D01*
G01X441992Y187097D02*
Y159800D01*
G01X461114Y157514D02*
X460178Y156577D01*
G01X461114Y158376D02*
Y157514D01*
G01X460130Y159360D02*
X461114Y158376D01*
G01X459268Y159360D02*
X460130D01*
G01X458332Y158423D02*
X459268Y159360D01*
G01X457470Y158423D02*
X458332D01*
G01X456486Y159407D02*
X457470Y158423D01*
G01X456486Y160269D02*
Y159407D01*
G01X457422Y161206D02*
X456486Y160269D01*
G01X457422Y162068D02*
Y161206D01*
G01X456438Y163052D02*
X457422Y162068D01*
G01X455576Y163052D02*
X456438D01*
G01X454640Y162115D02*
X455576Y163052D01*
G01X453778Y162115D02*
X454640D01*
G01X452318Y163575D02*
X453778Y162115D01*
G01X452318Y188936D02*
Y163575D01*
G01X442498Y455006D02*
X472336Y484844D01*
G01X442498Y417467D02*
Y455006D01*
G01X473280Y464619D02*
X472411Y465487D01*
G01X473280Y463489D02*
Y464619D01*
G01X472147Y462356D02*
X473280Y463489D01*
G01X471017Y462356D02*
X472147D01*
G01X470148Y463224D02*
X471017Y462356D01*
G01X469018Y463224D02*
X470148D01*
G01X467885Y462091D02*
X469018Y463224D01*
G01X467885Y460961D02*
Y462091D01*
G01X468754Y460093D02*
X467885Y460961D01*
G01X468754Y458963D02*
Y460093D01*
G01X454068Y444277D02*
X468754Y458963D01*
G01X454068Y414736D02*
Y444277D01*
G01X470392Y449100D02*
X487136Y465844D01*
G01X470392Y444800D02*
Y449100D01*
G01X461718Y436126D02*
X470392Y444800D01*
G01X461718Y415485D02*
Y436126D01*
G01X423948Y458156D02*
X431608Y465816D01*
G01X423948Y417187D02*
Y458156D01*
G01X448092Y451899D02*
X476037Y479844D01*
G01X448092Y417141D02*
Y451899D01*
G01X457074Y463581D02*
X458475Y464982D01*
G01X456212Y463581D02*
X457074D01*
G01X455624Y464169D02*
X456212Y463581D01*
G01X454762Y464169D02*
X455624D01*
G01X453361Y462768D02*
X454762Y464169D01*
G01X453361Y461906D02*
Y462768D01*
G01X453949Y461318D02*
X453361Y461906D01*
G01X453949Y460446D02*
Y461318D01*
G01X445428Y451925D02*
X453949Y460446D01*
G01X445428Y417407D02*
Y451925D01*
G01X421049Y463457D02*
X449914Y492322D01*
G01X421049Y417187D02*
Y463457D01*
G01X464329Y450937D02*
X484236Y470844D01*
G01X464329Y449687D02*
Y450937D01*
G01X466141Y447875D02*
X464329Y449687D01*
G01X466141Y447013D02*
Y447875D01*
G01X464740Y445612D02*
X466141Y447013D01*
G01X463878Y445612D02*
X464740D01*
G01X461542Y447948D02*
X463878Y445612D01*
G01X460636Y447948D02*
X461542D01*
G01X458900Y446212D02*
X460636Y447948D01*
G01X458900Y445439D02*
Y446212D01*
G01X460892Y443447D02*
X458900Y445439D01*
G01X460892Y442194D02*
Y443447D01*
G01X456618Y437920D02*
X460892Y442194D01*
G01X456618Y414706D02*
Y437920D01*
G01X477514Y429422D02*
X483792Y435700D01*
G01X477514Y420136D02*
Y429422D01*
G01X474218Y430426D02*
Y419224D01*
G01X481392Y437600D02*
X474218Y430426D01*
G01X468242Y450649D02*
X485937Y468344D01*
G01X468242Y445851D02*
Y450649D01*
G01X459168Y436777D02*
X468242Y445851D01*
G01X459168Y415450D02*
Y436777D01*
G01X426498Y457106D02*
X444385Y474993D01*
G01X426498Y417287D02*
Y457106D01*
G01X429048Y456056D02*
X457451Y484459D01*
G01X429048Y417287D02*
Y456056D01*
G01X471668Y432476D02*
X479292Y440100D01*
G01X471668Y418391D02*
Y432476D01*
G01X463890Y464134D02*
Y464996D01*
G01X464277Y463746D02*
X463890Y464134D01*
G01X464277Y462884D02*
Y463746D01*
G01X462876Y461483D02*
X464277Y462884D01*
G01X462015Y461483D02*
X462876D01*
G01X461627Y461871D02*
X462015Y461483D01*
G01X460765Y461871D02*
X461627D01*
G01X459364Y460470D02*
X460765Y461871D01*
G01X459364Y459608D02*
Y460470D01*
G01X459751Y459220D02*
X459364Y459608D01*
G01X459751Y458358D02*
Y459220D01*
G01X458350Y456957D02*
X459751Y458358D01*
G01X457489Y456957D02*
X458350D01*
G01X457101Y457345D02*
X457489Y456957D01*
G01X456239Y457345D02*
X457101D01*
G01X454085Y455191D02*
X456239Y457345D01*
G01X454085Y454329D02*
Y455191D01*
G01X455383Y453031D02*
X454085Y454329D01*
G01X455383Y452169D02*
Y453031D01*
G01X454399Y451185D02*
X455383Y452169D01*
G01X453537Y451185D02*
X454399D01*
G01X452239Y452483D02*
X453537Y451185D01*
G01X451377Y452483D02*
X452239D01*
G01X450666Y451772D02*
X451377Y452483D01*
G01X450666Y417141D02*
Y451772D01*
G01X472336Y484844D02*
X509536D01*
G01X478070Y472276D02*
X479200D01*
G01X476937Y471143D02*
X478070Y472276D01*
G01X476937Y470013D02*
Y471143D01*
G01X477806Y469145D02*
X476937Y470013D01*
G01X477806Y468015D02*
Y469145D01*
G01X476673Y466882D02*
X477806Y468015D01*
G01X475543Y466882D02*
X476673D01*
G01X474674Y467750D02*
X475543Y466882D01*
G01X473544Y467750D02*
X474674D01*
G01X472411Y466617D02*
X473544Y467750D01*
G01X472411Y465487D02*
Y466617D01*
G01X473293Y519862D02*
X474998Y518157D01*
G01X473293Y530049D02*
Y519862D01*
G01X454531Y513114D02*
X454619D01*
G01X452845Y514800D02*
X454531Y513114D01*
G01X452845Y517000D02*
Y514800D01*
G01X453345Y517500D02*
X452845Y517000D01*
G01X453345Y519399D02*
Y517500D01*
G01X452208Y520536D02*
X453345Y519399D01*
G01X452208Y521864D02*
Y520536D01*
G01X453145Y522801D02*
X452208Y521864D01*
G01X453145Y524199D02*
Y522801D01*
G01X452208Y525136D02*
X453145Y524199D01*
G01X452208Y526364D02*
Y525136D01*
G01X453245Y527401D02*
X452208Y526364D01*
G01X475492Y503200D02*
X480606Y508314D01*
G01X464392Y503200D02*
X475492D01*
G01X462167Y500975D02*
X464392Y503200D01*
G01X461035Y500975D02*
X462167D01*
G01X459516Y502494D02*
X461035Y500975D01*
G01X458384Y502494D02*
X459516D01*
G01X457253Y501363D02*
X458384Y502494D01*
G01X457253Y500231D02*
Y501363D01*
G01X458772Y498712D02*
X457253Y500231D01*
G01X458772Y497580D02*
Y498712D01*
G01X457641Y496449D02*
X458772Y497580D01*
G01X456509Y496449D02*
X457641D01*
G01X454748Y498210D02*
X456509Y496449D01*
G01X453616Y498210D02*
X454748D01*
G01X452485Y497079D02*
X453616Y498210D01*
G01X452485Y495947D02*
Y497079D01*
G01X454246Y494186D02*
X452485Y495947D01*
G01X454246Y493054D02*
Y494186D01*
G01X434886Y473694D02*
X454246Y493054D01*
G01X434886Y472736D02*
Y473694D01*
G01X436141Y471481D02*
X434886Y472736D01*
G01X436141Y470349D02*
Y471481D01*
G01X435003Y469211D02*
X436141Y470349D01*
G01X433871Y469211D02*
X435003D01*
G01X432277Y470805D02*
X433871Y469211D01*
G01X431123Y470805D02*
X432277D01*
G01X429992Y469674D02*
X431123Y470805D01*
G01X429992Y468564D02*
Y469674D01*
G01X431608Y466948D02*
X429992Y468564D01*
G01X431608Y465816D02*
Y466948D01*
G01X476037Y479844D02*
X511735D01*
G01X421781Y491660D02*
Y487647D01*
G01X438455Y508334D02*
X421781Y491660D01*
G01X438954Y508334D02*
X438455D01*
G01X439987Y509367D02*
X438954Y508334D01*
G01X439987Y511205D02*
Y509367D01*
G01X439192Y512000D02*
X439987Y511205D01*
G01X439192Y513800D02*
Y512000D01*
G01X439992Y514600D02*
X439192Y513800D01*
G01X439992Y516600D02*
Y514600D01*
G01X439592Y517000D02*
X439992Y516600D01*
G01X439592Y527700D02*
Y517000D01*
G01X472937Y482344D02*
X510635D01*
G01X471465Y480872D02*
X472937Y482344D01*
G01X471465Y480010D02*
Y480872D01*
G01X472053Y479422D02*
X471465Y480010D01*
G01X472053Y478560D02*
Y479422D01*
G01X470652Y477159D02*
X472053Y478560D01*
G01X469790Y477159D02*
X470652D01*
G01X469202Y477747D02*
X469790Y477159D01*
G01X468340Y477747D02*
X469202D01*
G01X466939Y476346D02*
X468340Y477747D01*
G01X466939Y475484D02*
Y476346D01*
G01X467527Y474896D02*
X466939Y475484D01*
G01X467527Y474034D02*
Y474896D01*
G01X466126Y472633D02*
X467527Y474034D01*
G01X465264Y472633D02*
X466126D01*
G01X464676Y473221D02*
X465264Y472633D01*
G01X463814Y473221D02*
X464676D01*
G01X462413Y471820D02*
X463814Y473221D01*
G01X462413Y470958D02*
Y471820D01*
G01X463001Y470370D02*
X462413Y470958D01*
G01X463001Y469508D02*
Y470370D01*
G01X461600Y468107D02*
X463001Y469508D01*
G01X460738Y468107D02*
X461600D01*
G01X460150Y468695D02*
X460738Y468107D01*
G01X459288Y468695D02*
X460150D01*
G01X457887Y467294D02*
X459288Y468695D01*
G01X457887Y466432D02*
Y467294D01*
G01X458475Y465844D02*
X457887Y466432D01*
G01X458475Y464982D02*
Y465844D01*
G01X473914Y505100D02*
X480766Y511952D01*
G01X471486Y505100D02*
X473914D01*
G01X470876Y505710D02*
X471486Y505100D01*
G01X470876Y507807D02*
Y505710D01*
G01X470288Y508395D02*
X470876Y507807D01*
G01X468898Y508395D02*
X470288D01*
G01X468266Y507763D02*
X468898Y508395D01*
G01X468266Y505710D02*
Y507763D01*
G01X467656Y505100D02*
X468266Y505710D01*
G01X466266Y505100D02*
X467656D01*
G01X465656Y505710D02*
X466266Y505100D01*
G01X465656Y506970D02*
Y505710D01*
G01X465046Y507580D02*
X465656Y506970D01*
G01X463656Y507580D02*
X465046D01*
G01X463046Y506970D02*
X463656Y507580D01*
G01X463046Y505710D02*
Y506970D01*
G01X462436Y505100D02*
X463046Y505710D01*
G01X457686Y505100D02*
X462436D01*
G01X449914Y497328D02*
X457686Y505100D01*
G01X449914Y492322D02*
Y497328D01*
G01X429392Y511000D02*
Y507830D01*
G01X430278Y511886D02*
X429392Y511000D01*
G01X430278Y513514D02*
Y511886D01*
G01X429309Y514483D02*
X430278Y513514D01*
G01X429309Y516217D02*
Y514483D01*
G01X430192Y517100D02*
X429309Y516217D01*
G01X430192Y527300D02*
Y517100D01*
G01X423692Y525900D02*
X423061Y526531D01*
G01X423692Y517600D02*
Y525900D01*
G01X423034Y516942D02*
X423692Y517600D01*
G01X423034Y514358D02*
Y516942D01*
G01X423317Y514075D02*
X423034Y514358D01*
G01X423317Y511625D02*
Y514075D01*
G01X422792Y511100D02*
X423317Y511625D01*
G01X422792Y506889D02*
Y511100D01*
G01X426692Y511300D02*
Y507960D01*
G01X425992Y512000D02*
X426692Y511300D01*
G01X425992Y513800D02*
Y512000D01*
G01X426692Y514500D02*
X425992Y513800D01*
G01X426692Y516600D02*
Y514500D01*
G01X426092Y517200D02*
X426692Y516600D01*
G01X426092Y521100D02*
Y517200D01*
G01X426544Y521552D02*
X426092Y521100D01*
G01X426544Y530248D02*
Y521552D01*
G01X419828Y520536D02*
Y530064D01*
G01X419492Y520200D02*
X419828Y520536D01*
G01X419492Y516900D02*
Y520200D01*
G01X420381Y516011D02*
X419492Y516900D01*
G01X420381Y514321D02*
Y516011D01*
G01X419392Y513332D02*
X420381Y514321D01*
G01X419392Y511700D02*
Y513332D01*
G01X420971Y510121D02*
X419392Y511700D01*
G01X420971Y507897D02*
Y510121D01*
G01X419854Y506780D02*
X420971Y507897D01*
G01X418722Y506780D02*
X419854D01*
G01X418263Y507239D02*
X418722Y506780D01*
G01X417131Y507239D02*
X418263D01*
G01X416459Y503385D02*
Y504517D01*
G01X456561Y519862D02*
X458266Y518157D01*
G01X456561Y531515D02*
Y519862D01*
G01X436891Y526301D02*
X436474Y526718D01*
G01X436891Y517399D02*
Y526301D01*
G01X436409Y516917D02*
X436891Y517399D01*
G01X436409Y514083D02*
Y516917D01*
G01X436650Y513842D02*
X436409Y514083D01*
G01X436650Y511858D02*
Y513842D01*
G01X436292Y511500D02*
X436650Y511858D01*
G01X436292Y509000D02*
Y511500D01*
G01X419781Y492489D02*
X436292Y509000D01*
G01X419781Y488476D02*
Y492489D01*
G01X417781Y493389D02*
Y489305D01*
G01X433292Y508900D02*
X417781Y493389D01*
G01X433292Y511300D02*
Y508900D01*
G01X432892Y511700D02*
X433292Y511300D01*
G01X432892Y514200D02*
Y511700D01*
G01X433392Y514700D02*
X432892Y514200D01*
G01X433392Y516600D02*
Y514700D01*
G01X432992Y517000D02*
X433392Y516600D01*
G01X432992Y520400D02*
Y517000D01*
G01X433213Y520621D02*
X432992Y520400D01*
G01X433213Y530555D02*
Y520621D01*
G01X449868Y519862D02*
X451573Y518157D01*
G01X449868Y529835D02*
Y519862D01*
G01X476591Y500600D02*
X482505Y506514D01*
G01X465692Y500600D02*
X476591D01*
G01X452419Y487327D02*
X465692Y500600D01*
G01X452419Y486195D02*
Y487327D01*
G01X453387Y485227D02*
X452419Y486195D01*
G01X453387Y484095D02*
Y485227D01*
G01X452256Y482964D02*
X453387Y484095D01*
G01X451124Y482964D02*
X452256D01*
G01X450106Y483982D02*
X451124Y482964D01*
G01X448974Y483982D02*
X450106D01*
G01X447843Y482851D02*
X448974Y483982D01*
G01X447843Y481719D02*
Y482851D01*
G01X448911Y480651D02*
X447843Y481719D01*
G01X448911Y479519D02*
Y480651D01*
G01X447780Y478388D02*
X448911Y479519D01*
G01X446648Y478388D02*
X447780D01*
G01X445480Y479556D02*
X446648Y478388D01*
G01X444348Y479556D02*
X445480D01*
G01X443217Y478425D02*
X444348Y479556D01*
G01X443217Y477293D02*
Y478425D01*
G01X444385Y476125D02*
X443217Y477293D01*
G01X444385Y474993D02*
Y476125D01*
G01X477891Y498100D02*
X484505Y504714D01*
G01X466366Y498100D02*
X477891D01*
G01X465283Y497017D02*
X466366Y498100D01*
G01X465283Y495863D02*
Y497017D01*
G01X466947Y494199D02*
X465283Y495863D01*
G01X466947Y493067D02*
Y494199D01*
G01X465816Y491936D02*
X466947Y493067D01*
G01X464684Y491936D02*
X465816D01*
G01X462998Y493622D02*
X464684Y491936D01*
G01X461866Y493622D02*
X462998D01*
G01X460735Y492491D02*
X461866Y493622D01*
G01X460735Y491359D02*
Y492491D01*
G01X462289Y489805D02*
X460735Y491359D01*
G01X462289Y488673D02*
Y489805D01*
G01X461158Y487542D02*
X462289Y488673D01*
G01X460026Y487542D02*
X461158D01*
G01X458406Y489162D02*
X460026Y487542D01*
G01X457274Y489162D02*
X458406D01*
G01X456143Y488031D02*
X457274Y489162D01*
G01X456143Y486899D02*
Y488031D01*
G01X457451Y485591D02*
X456143Y486899D01*
G01X457451Y484459D02*
Y485591D01*
G01X460824Y513114D02*
X460912D01*
G01X459138Y514800D02*
X460824Y513114D01*
G01X459138Y516492D02*
Y514800D01*
G01X460045Y517399D02*
X459138Y516492D01*
G01X460045Y518992D02*
Y517399D01*
G01X458901Y520136D02*
X460045Y518992D01*
G01X458901Y521556D02*
Y520136D01*
G01X459745Y522400D02*
X458901Y521556D01*
G01X459745Y524100D02*
Y522400D01*
G01X458901Y524944D02*
X459745Y524100D01*
G01X458901Y526156D02*
Y524944D01*
G01X459845Y527100D02*
X458901Y526156D01*
G01X476570Y514800D02*
X478256Y513114D01*
G01X476570Y516492D02*
Y514800D01*
G01X476745Y516667D02*
X476570Y516492D01*
G01X476745Y519300D02*
Y516667D01*
G01X475633Y520412D02*
X476745Y519300D01*
G01X475633Y521488D02*
Y520412D01*
G01X476645Y522500D02*
X475633Y521488D01*
G01X476645Y523700D02*
Y522500D01*
G01X475633Y524712D02*
X476645Y523700D01*
G01X475633Y525788D02*
Y524712D01*
G01X476770Y526925D02*
X475633Y525788D01*
G01X417392Y517600D02*
Y526200D01*
G01X416651Y511995D02*
Y513841D01*
G01X443692Y526100D02*
X443248Y526544D01*
G01X443692Y517100D02*
Y526100D01*
G01X442792Y516200D02*
X443692Y517100D01*
G01X442792Y514800D02*
Y516200D01*
G01X443692Y513900D02*
X442792Y514800D01*
G01X443692Y512000D02*
Y513900D01*
G01X442992Y511300D02*
X443692Y512000D01*
G01X442992Y509154D02*
Y511300D01*
G01X440205Y506367D02*
X442992Y509154D01*
G01X439317Y506367D02*
X440205D01*
G01X429818Y496868D02*
X439317Y506367D01*
G01X429818Y496006D02*
Y496868D01*
G01X430751Y495073D02*
X429818Y496006D01*
G01X430751Y494211D02*
Y495073D01*
G01X429767Y493227D02*
X430751Y494211D01*
G01X428905Y493227D02*
X429767D01*
G01X427972Y494160D02*
X428905Y493227D01*
G01X427110Y494160D02*
X427972D01*
G01X423781Y490831D02*
X427110Y494160D01*
G01X423781Y486818D02*
Y490831D01*
G01X476238Y477344D02*
X512935D01*
G01X472942Y474048D02*
X476238Y477344D01*
G01X472942Y473186D02*
Y474048D01*
G01X473329Y472798D02*
X472942Y473186D01*
G01X473329Y471936D02*
Y472798D01*
G01X471928Y470535D02*
X473329Y471936D01*
G01X471067Y470535D02*
X471928D01*
G01X470679Y470923D02*
X471067Y470535D01*
G01X469817Y470923D02*
X470679D01*
G01X468416Y469522D02*
X469817Y470923D01*
G01X468416Y468660D02*
Y469522D01*
G01X468803Y468272D02*
X468416Y468660D01*
G01X468803Y467410D02*
Y468272D01*
G01X467402Y466009D02*
X468803Y467410D01*
G01X466541Y466009D02*
X467402D01*
G01X466153Y466397D02*
X466541Y466009D01*
G01X465291Y466397D02*
X466153D01*
G01X463890Y464996D02*
X465291Y466397D01*
G01X446485Y517607D02*
Y533293D01*
G01X446892Y517200D02*
X446485Y517607D01*
G01X446892Y514700D02*
Y517200D01*
G01X445966Y513774D02*
X446892Y514700D01*
G01X445966Y511826D02*
Y513774D01*
G01X446743Y511049D02*
X445966Y511826D01*
G01X446743Y506951D02*
Y511049D01*
G01X417281Y582870D02*
X416645Y583506D01*
G01X417281Y581480D02*
Y582870D01*
G01X416697Y580896D02*
X417281Y581480D01*
G01X478344Y535100D02*
X473293Y530049D01*
G01X453245Y528299D02*
Y527401D01*
G01X452645Y528899D02*
X453245Y528299D01*
G01X451573Y528899D02*
X452645D01*
G01X439810Y527918D02*
X439592Y527700D01*
G01X439810Y552118D02*
Y527918D01*
G01X439819Y552127D02*
X439810Y552118D01*
G01X439819Y557427D02*
Y552127D01*
G01X439810Y557436D02*
X439819Y557427D01*
G01X439810Y576618D02*
Y557436D01*
G01X443248Y580056D02*
X439810Y576618D01*
G01X443248Y586956D02*
Y580056D01*
G01X443792Y587500D02*
X443248Y586956D01*
G01X443792Y589876D02*
Y587500D01*
G01X429761Y527731D02*
X430192Y527300D01*
G01X429761Y554469D02*
Y527731D01*
G01X429863Y554571D02*
X429761Y554469D01*
G01X429863Y559335D02*
Y554571D01*
G01X429769Y559429D02*
X429863Y559335D01*
G01X429769Y576677D02*
Y559429D01*
G01X433228Y580136D02*
X429769Y576677D01*
G01X433228Y586900D02*
Y580136D01*
G01X436577Y590249D02*
X433228Y586900D01*
G01X426528Y580836D02*
Y589536D01*
G01X423076Y577384D02*
X426528Y580836D01*
G01X423076Y568284D02*
Y577384D01*
G01X423061Y568269D02*
X423076Y568284D01*
G01X423061Y565031D02*
Y568269D01*
G01X423149Y564943D02*
X423061Y565031D01*
G01X423149Y549157D02*
Y564943D01*
G01X423090Y549098D02*
X423149Y549157D01*
G01X423090Y530498D02*
Y549098D01*
G01X423061Y530469D02*
X423090Y530498D01*
G01X423061Y526531D02*
Y530469D01*
G01X426514Y530278D02*
X426544Y530248D01*
G01X426514Y551974D02*
Y530278D01*
G01X426440Y552048D02*
X426514Y551974D01*
G01X426440Y558548D02*
Y552048D01*
G01X426528Y558636D02*
X426440Y558548D01*
G01X426528Y577136D02*
Y558636D01*
G01X429777Y580385D02*
X426528Y577136D01*
G01X429777Y586985D02*
Y580385D01*
G01X430792Y588000D02*
X429777Y586985D01*
G01X430792Y590262D02*
Y588000D01*
G01X423075Y586883D02*
X424801Y588609D01*
G01X423075Y580883D02*
Y586883D01*
G01X419829Y577637D02*
X423075Y580883D01*
G01X419829Y573563D02*
Y577637D01*
G01X419292Y573026D02*
X419829Y573563D01*
G01X419292Y568500D02*
Y573026D01*
G01X419843Y567949D02*
X419292Y568500D01*
G01X419843Y554819D02*
Y567949D01*
G01X419300Y554276D02*
X419843Y554819D01*
G01X419300Y549992D02*
Y554276D01*
G01X419814Y549478D02*
X419300Y549992D01*
G01X419814Y535678D02*
Y549478D01*
G01X419300Y535164D02*
X419814Y535678D01*
G01X419300Y530592D02*
Y535164D01*
G01X419828Y530064D02*
X419300Y530592D01*
G01X459746Y534700D02*
X456561Y531515D01*
G01X460912Y534700D02*
X459746D01*
G01X439825Y587067D02*
X441675Y588917D01*
G01X439825Y579833D02*
Y587067D01*
G01X436519Y576527D02*
X439825Y579833D01*
G01X436519Y573627D02*
Y576527D01*
G01X436462Y573570D02*
X436519Y573627D01*
G01X436462Y559030D02*
Y573570D01*
G01X436548Y558944D02*
X436462Y559030D01*
G01X436548Y529856D02*
Y558944D01*
G01X436474Y529782D02*
X436548Y529856D01*
G01X436474Y526718D02*
Y529782D01*
G01X431670Y532098D02*
X433213Y530555D01*
G01X431670Y534134D02*
Y532098D01*
G01X433214Y535678D02*
X431670Y534134D01*
G01X433214Y548978D02*
Y535678D01*
G01X431773Y550419D02*
X433214Y548978D01*
G01X431773Y553115D02*
Y550419D01*
G01X433125Y554467D02*
X431773Y553115D01*
G01X433125Y562233D02*
Y554467D01*
G01X433215Y562323D02*
X433125Y562233D01*
G01X433215Y567549D02*
Y562323D01*
G01X431742Y569022D02*
X433215Y567549D01*
G01X431742Y572058D02*
Y569022D01*
G01X433214Y573530D02*
X431742Y572058D01*
G01X433214Y576922D02*
Y573530D01*
G01X436519Y580227D02*
X433214Y576922D01*
G01X436519Y586827D02*
Y580227D01*
G01X438187Y588495D02*
X436519Y586827D01*
G01X450490Y530457D02*
X449868Y529835D01*
G01X450490Y531645D02*
Y530457D01*
G01X453545Y534700D02*
X450490Y531645D01*
G01X454533Y534700D02*
X453545D01*
G01X459845Y528300D02*
Y527100D01*
G01X459246Y528899D02*
X459845Y528300D01*
G01X458266Y528899D02*
X459246D01*
G01X476770Y528199D02*
Y526925D01*
G01X476070Y528899D02*
X476770Y528199D01*
G01X474998Y528899D02*
X476070D01*
G01X419792Y586348D02*
X423149Y589705D01*
G01X419792Y581400D02*
Y586348D01*
G01X417492Y557714D02*
Y563700D01*
G01X444880Y578288D02*
Y585722D01*
G01X443248Y576656D02*
X444880Y578288D01*
G01X443248Y526544D02*
Y576656D01*
G01X445792Y587500D02*
Y589000D01*
G01X446745Y586547D02*
X445792Y587500D01*
G01X446745Y576553D02*
Y586547D01*
G01X446510Y576318D02*
X446745Y576553D01*
G01X446510Y571118D02*
Y576318D01*
G01X446207Y570815D02*
X446510Y571118D01*
G01X446207Y568385D02*
Y570815D01*
G01X446502Y568090D02*
X446207Y568385D01*
G01X446502Y548890D02*
Y568090D01*
G01X446692Y548700D02*
X446502Y548890D01*
G01X446692Y533500D02*
Y548700D01*
G01X446485Y533293D02*
X446692Y533500D01*
G01X416561Y605769D02*
Y608261D01*
G01X444880Y590964D02*
X443792Y589876D01*
G01X444880Y593659D02*
Y590964D01*
G01X436577Y603004D02*
Y590249D01*
G01X438187Y604614D02*
X436577Y603004D01*
G01X429878Y602883D02*
X431494Y604499D01*
G01X429878Y592886D02*
Y602883D01*
G01X426528Y589536D02*
X429878Y592886D01*
G01X431494Y590964D02*
X430792Y590262D01*
G01X431494Y593642D02*
Y590964D01*
G01X424801Y588609D02*
Y593642D01*
G01X443249Y602983D02*
X444880Y604614D01*
G01X443249Y592857D02*
Y602983D01*
G01X441675Y591283D02*
X443249Y592857D01*
G01X441675Y588917D02*
Y591283D01*
G01X438187Y593659D02*
Y588495D01*
G01X424801Y597512D02*
Y604614D01*
G01X423149Y595860D02*
X424801Y597512D01*
G01X423149Y589705D02*
Y595860D01*
G01X444880Y607312D02*
Y609864D01*
G01X447092Y605100D02*
X444880Y607312D01*
G01X447092Y602900D02*
Y605100D01*
G01X446792Y602600D02*
X447092Y602900D01*
G01X446792Y590000D02*
Y602600D01*
G01X445792Y589000D02*
X446792Y590000D01*
G01X531888Y67821D02*
Y65699D01*
G01X533767Y69700D02*
X531888Y67821D01*
G01X535167Y69700D02*
X533767D01*
G01X536623Y71156D02*
X535167Y69700D01*
G01X536623Y72500D02*
Y71156D01*
G01X536007Y73116D02*
X536623Y72500D01*
G01X536007Y86241D02*
Y73116D01*
G01X534534Y87714D02*
X536007Y86241D01*
G01X532566Y89682D02*
X534534Y87714D01*
G01X532566Y90974D02*
Y89682D01*
G01X534066Y92474D02*
X532566Y90974D01*
G01X534066Y100338D02*
Y92474D01*
G01X480345Y71300D02*
X478545Y69500D01*
G01X480345Y72700D02*
Y71300D01*
G01X479733Y73312D02*
X480345Y72700D01*
G01X479733Y86325D02*
Y73312D01*
G01X478344Y87714D02*
X479733Y86325D01*
G01X495077Y67821D02*
Y65699D01*
G01X496956Y69700D02*
X495077Y67821D01*
G01X498356Y69700D02*
X496956D01*
G01X499812Y71156D02*
X498356Y69700D01*
G01X499812Y72500D02*
Y71156D01*
G01X499196Y73116D02*
X499812Y72500D01*
G01X499196Y86241D02*
Y73116D01*
G01X497723Y87714D02*
X499196Y86241D01*
G01X495816Y89621D02*
X497723Y87714D01*
G01X495816Y90924D02*
Y89621D01*
G01X497066Y92174D02*
X495816Y90924D01*
G01X497066Y97026D02*
Y92174D01*
G01X527067Y72588D02*
X528155Y71500D01*
G01X527067Y74468D02*
Y72588D01*
G01X525634Y75901D02*
X527067Y74468D01*
G01X525634Y77100D02*
Y75901D01*
G01X527134Y78600D02*
X525634Y77100D01*
G01X527134Y79800D02*
Y78600D01*
G01X525684Y81250D02*
X527134Y79800D01*
G01X525684Y82649D02*
Y81250D01*
G01X527067Y84032D02*
X525684Y82649D01*
G01X527067Y85901D02*
Y84032D01*
G01X524267Y88701D02*
X527067Y85901D01*
G01X524267Y91829D02*
Y88701D01*
G01X525195Y92757D02*
X524267Y91829D01*
G01X525195Y94067D02*
Y92757D01*
G01X525784Y94656D02*
X525195Y94067D01*
G01Y67253D02*
Y65699D01*
G01X527442Y69500D02*
X525195Y67253D01*
G01X528666Y69500D02*
X527442D01*
G01X530242Y71076D02*
X528666Y69500D01*
G01X530242Y72700D02*
Y71076D01*
G01X529467Y73475D02*
X530242Y72700D01*
G01X529467Y86488D02*
Y73475D01*
G01X528241Y87714D02*
X529467Y86488D01*
G01X526266Y89689D02*
X528241Y87714D01*
G01X526266Y90974D02*
Y89689D01*
G01X527491Y92199D02*
X526266Y90974D01*
G01X527491Y93363D02*
Y92199D01*
G01X528084Y93956D02*
X527491Y93363D01*
G01X529098Y93956D02*
X528084D01*
G01X529866Y94724D02*
X529098Y93956D01*
G01X483470Y73467D02*
X485037Y71900D01*
G01X483470Y74668D02*
Y73467D01*
G01X482112Y76026D02*
X483470Y74668D01*
G01X482112Y77399D02*
Y76026D01*
G01X483312Y78599D02*
X482112Y77399D01*
G01X483312Y79725D02*
Y78599D01*
G01X482112Y80925D02*
X483312Y79725D01*
G01X482112Y82500D02*
Y80925D01*
G01X483912Y84300D02*
X482112Y82500D01*
G01X483912Y85358D02*
Y84300D01*
G01X480570Y88700D02*
X483912Y85358D01*
G01X480570Y91636D02*
Y88700D01*
G01X481691Y92757D02*
X480570Y91636D01*
G01X488384Y67253D02*
Y65699D01*
G01X490631Y69500D02*
X488384Y67253D01*
G01X491855Y69500D02*
X490631D01*
G01X493431Y71076D02*
X491855Y69500D01*
G01X493431Y72700D02*
Y71076D01*
G01X492656Y73475D02*
X493431Y72700D01*
G01X492656Y86488D02*
Y73475D01*
G01X491430Y87714D02*
X492656Y86488D01*
G01X489580Y89564D02*
X491430Y87714D01*
G01X489580Y91238D02*
Y89564D01*
G01X491666Y93324D02*
X489580Y91238D01*
G01X491666Y94174D02*
Y93324D01*
G01X491166Y94674D02*
X491666Y94174D01*
G01X490256Y72588D02*
X491344Y71500D01*
G01X490256Y74468D02*
Y72588D01*
G01X488823Y75901D02*
X490256Y74468D01*
G01X488823Y77100D02*
Y75901D01*
G01X490323Y78600D02*
X488823Y77100D01*
G01X490323Y79800D02*
Y78600D01*
G01X488873Y81250D02*
X490323Y79800D01*
G01X488873Y82649D02*
Y81250D01*
G01X490256Y84032D02*
X488873Y82649D01*
G01X490256Y85901D02*
Y84032D01*
G01X487456Y88701D02*
X490256Y85901D01*
G01X487456Y91829D02*
Y88701D01*
G01X488384Y92757D02*
X487456Y91829D01*
G01X488367Y92774D02*
X488384Y92757D01*
G01X484353Y92774D02*
X488367D01*
G01X482570Y94557D02*
X484353Y92774D01*
G01X478356Y95800D02*
X479599Y94557D01*
G01X520281Y73467D02*
X521848Y71900D01*
G01X520281Y74668D02*
Y73467D01*
G01X518923Y76026D02*
X520281Y74668D01*
G01X518923Y77399D02*
Y76026D01*
G01X520123Y78599D02*
X518923Y77399D01*
G01X520123Y79725D02*
Y78599D01*
G01X518923Y80925D02*
X520123Y79725D01*
G01X518923Y82500D02*
Y80925D01*
G01X520723Y84300D02*
X518923Y82500D01*
G01X520723Y85358D02*
Y84300D01*
G01X517381Y88700D02*
X520723Y85358D01*
G01X517381Y91636D02*
Y88700D01*
G01X518502Y92757D02*
X517381Y91636D01*
G01X517292Y93967D02*
X518502Y92757D01*
G01X517292Y95600D02*
Y93967D01*
G01X518502Y66953D02*
Y65699D01*
G01X521049Y69500D02*
X518502Y66953D01*
G01X522049Y69500D02*
X521049D01*
G01X523849Y71300D02*
X522049Y69500D01*
G01X523849Y72700D02*
Y71300D01*
G01X523237Y73312D02*
X523849Y72700D01*
G01X523237Y86325D02*
Y73312D01*
G01X521848Y87714D02*
X523237Y86325D01*
G01X519766Y89796D02*
X521848Y87714D01*
G01X519766Y91274D02*
Y89796D01*
G01X522866Y94374D02*
X519766Y91274D01*
G01X522866Y105174D02*
Y94374D01*
G01X533667Y72367D02*
X534534Y71500D01*
G01X533667Y74668D02*
Y72367D01*
G01X532034Y76301D02*
X533667Y74668D01*
G01X532034Y77600D02*
Y76301D01*
G01X533384Y78950D02*
X532034Y77600D01*
G01X533384Y79850D02*
Y78950D01*
G01X532134Y81100D02*
X533384Y79850D01*
G01X532134Y82299D02*
Y81100D01*
G01X533667Y83832D02*
X532134Y82299D01*
G01X533667Y85800D02*
Y83832D01*
G01X530767Y88700D02*
X533667Y85800D01*
G01X530767Y91636D02*
Y88700D01*
G01X531888Y92757D02*
X530767Y91636D01*
G01X531888Y101560D02*
Y92757D01*
G01X513681Y73374D02*
X515155Y71900D01*
G01X513681Y74468D02*
Y73374D01*
G01X512248Y75901D02*
X513681Y74468D01*
G01X512248Y77124D02*
Y75901D01*
G01X513748Y78624D02*
X512248Y77124D01*
G01X513748Y79976D02*
Y78624D01*
G01X512248Y81476D02*
X513748Y79976D01*
G01X512248Y82599D02*
Y81476D01*
G01X513923Y84274D02*
X512248Y82599D01*
G01X513923Y85659D02*
Y84274D01*
G01X510881Y88701D02*
X513923Y85659D01*
G01X510881Y91829D02*
Y88701D01*
G01X511809Y92757D02*
X510881Y91829D01*
G01X511809Y92761D02*
Y92757D01*
G01X512492Y93444D02*
X511809Y92761D01*
G01X512492Y96001D02*
Y93444D01*
G01X481691Y66953D02*
Y65699D01*
G01X484238Y69500D02*
X481691Y66953D01*
G01X485238Y69500D02*
X484238D01*
G01X487038Y71300D02*
X485238Y69500D01*
G01X487038Y72700D02*
Y71300D01*
G01X486426Y73312D02*
X487038Y72700D01*
G01X486426Y86325D02*
Y73312D01*
G01X485037Y87714D02*
X486426Y86325D01*
G01X511809Y66953D02*
Y65699D01*
G01X514356Y69500D02*
X511809Y66953D01*
G01X515356Y69500D02*
X514356D01*
G01X517156Y71300D02*
X515356Y69500D01*
G01X517156Y72700D02*
Y71300D01*
G01X516544Y73312D02*
X517156Y72700D01*
G01X516544Y86325D02*
Y73312D01*
G01X515155Y87714D02*
X516544Y86325D01*
G01X513292Y89577D02*
X515155Y87714D01*
G01X513292Y91300D02*
Y89577D01*
G01X514692Y92700D02*
X513292Y91300D01*
G01X514692Y104546D02*
Y92700D01*
G01X496856Y72367D02*
X497723Y71500D01*
G01X496856Y74668D02*
Y72367D01*
G01X495223Y76301D02*
X496856Y74668D01*
G01X495223Y77600D02*
Y76301D01*
G01X496573Y78950D02*
X495223Y77600D01*
G01X496573Y79850D02*
Y78950D01*
G01X495323Y81100D02*
X496573Y79850D01*
G01X495323Y82299D02*
Y81100D01*
G01X496856Y83832D02*
X495323Y82299D01*
G01X496856Y85800D02*
Y83832D01*
G01X493956Y88700D02*
X496856Y85800D01*
G01X493956Y91636D02*
Y88700D01*
G01X495077Y92757D02*
X493956Y91636D01*
G01X495077Y95515D02*
Y92757D01*
G01X536466Y102738D02*
X534066Y100338D01*
G01X536466Y115026D02*
Y102738D01*
G01X513592Y137900D02*
X536466Y115026D01*
G01X511592Y137900D02*
X513592D01*
G01X510392Y136700D02*
X511592Y137900D01*
G01X504892Y136700D02*
X510392D01*
G01X503692Y137900D02*
X504892Y136700D01*
G01X485792Y137900D02*
X503692D01*
G01X495792Y98300D02*
X497066Y97026D01*
G01X486465Y98300D02*
X495792D01*
G01X479865Y104900D02*
X486465Y98300D01*
G01X532448Y152000D02*
X549564Y134884D01*
G01X493391Y152000D02*
X532448D01*
G01X525784Y101756D02*
Y94656D01*
G01X527266Y103238D02*
X525784Y101756D01*
G01X527266Y105374D02*
Y103238D01*
G01X526366Y106274D02*
X527266Y105374D01*
G01X526366Y110774D02*
Y106274D01*
G01X527566Y111974D02*
X526366Y110774D01*
G01X527566Y112926D02*
Y111974D01*
G01X511392Y129100D02*
X527566Y112926D01*
G01X480793Y129100D02*
X511392D01*
G01X539480Y134412D02*
X541192Y132700D01*
G01X536379Y134412D02*
X539480D01*
G01X535395Y135396D02*
X536379Y134412D01*
G01X535395Y136258D02*
Y135396D01*
G01X536368Y137231D02*
X535395Y136258D01*
G01X536368Y138024D02*
Y137231D01*
G01X535315Y139077D02*
X536368Y138024D01*
G01X534522Y139077D02*
X535315D01*
G01X533549Y138104D02*
X534522Y139077D01*
G01X532687Y138104D02*
X533549D01*
G01X531703Y139088D02*
X532687Y138104D01*
G01X531703Y139950D02*
Y139088D01*
G01X532690Y140938D02*
X531703Y139950D01*
G01X532690Y141800D02*
Y140938D01*
G01X531706Y142784D02*
X532690Y141800D01*
G01X530844Y142784D02*
X531706D01*
G01X529857Y141796D02*
X530844Y142784D01*
G01X528995Y141796D02*
X529857D01*
G01X528011Y142780D02*
X528995Y141796D01*
G01X528011Y143642D02*
Y142780D01*
G01X528998Y144630D02*
X528011Y143642D01*
G01X528998Y145492D02*
Y144630D01*
G01X528014Y146476D02*
X528998Y145492D01*
G01X527152Y146476D02*
X528014D01*
G01X526165Y145488D02*
X527152Y146476D01*
G01X525303Y145488D02*
X526165D01*
G01X522891Y147900D02*
X525303Y145488D01*
G01X491592Y147900D02*
X522891D01*
G01X527792Y149900D02*
X552166Y125526D01*
G01X492292Y149900D02*
X527792D01*
G01X529866Y95668D02*
Y94724D01*
G01X529066Y96468D02*
X529866Y95668D01*
G01X528684Y96468D02*
X529066D01*
G01X527884Y97268D02*
X528684Y96468D01*
G01X527884Y98868D02*
Y97268D01*
G01X528684Y99668D02*
X527884Y98868D01*
G01X529066Y99668D02*
X528684D01*
G01X529866Y100468D02*
X529066Y99668D01*
G01X529866Y105474D02*
Y100468D01*
G01X530066Y105674D02*
X529866Y105474D01*
G01X530066Y113525D02*
Y105674D01*
G01X511091Y132500D02*
X530066Y113525D01*
G01X483993Y132500D02*
X511091D01*
G01X535392Y158500D02*
X560892Y133000D01*
G01X484999Y94674D02*
X491166D01*
G01X483316Y96357D02*
X484999Y94674D01*
G01X481335Y96357D02*
X483316D01*
G01X479592Y98100D02*
X481335Y96357D01*
G01X479599Y94557D02*
X482570D01*
G01X534492Y154200D02*
X557384Y131308D01*
G01X494591Y154200D02*
X534492D01*
G01X517892Y96200D02*
X517292Y95600D01*
G01X519692Y96200D02*
X517892D01*
G01X520366Y96874D02*
X519692Y96200D01*
G01X520366Y105126D02*
Y96874D01*
G01X519292Y106200D02*
X520366Y105126D01*
G01X518676Y106200D02*
X519292D01*
G01X517292Y107584D02*
X518676Y106200D01*
G01X517292Y110648D02*
Y107584D01*
G01X516517Y111423D02*
X517292Y110648D01*
G01X516517Y114012D02*
Y111423D01*
G01X507329Y123200D02*
X516517Y114012D01*
G01X522992Y105300D02*
X522866Y105174D01*
G01X522992Y111074D02*
Y105300D01*
G01X508066Y126000D02*
X522992Y111074D01*
G01X533566Y103238D02*
X531888Y101560D01*
G01X533566Y105074D02*
Y103238D01*
G01X532566Y106074D02*
X533566Y105074D01*
G01X532566Y110474D02*
Y106074D01*
G01X533792Y111700D02*
X532566Y110474D01*
G01X533792Y114300D02*
Y111700D01*
G01X513492Y134600D02*
X533792Y114300D01*
G01X484890Y134600D02*
X513492D01*
G01X511937Y96556D02*
X512492Y96001D01*
G01X509600Y96556D02*
X511937D01*
G01X508800Y97356D02*
X509600Y96556D01*
G01X508800Y98956D02*
Y97356D01*
G01X509700Y99856D02*
X508800Y98956D01*
G01X511748Y99856D02*
X509700D01*
G01X512392Y100500D02*
X511748Y99856D01*
G01X512392Y101400D02*
Y100500D01*
G01X510892Y102900D02*
X512392Y101400D01*
G01X509092Y102900D02*
X510892D01*
G01X508592Y103400D02*
X509092Y102900D01*
G01X508592Y105447D02*
Y103400D01*
G01X509292Y106147D02*
X508592Y105447D01*
G01X509892Y106147D02*
X509292D01*
G01X510692Y106947D02*
X509892Y106147D01*
G01X510692Y108547D02*
Y106947D01*
G01X509892Y109347D02*
X510692Y108547D01*
G01X509292Y109347D02*
X509892D01*
G01X508592Y110047D02*
X509292Y109347D01*
G01X508592Y111200D02*
Y110047D01*
G01X509892Y112500D02*
X508592Y111200D01*
G01X509892Y113564D02*
Y112500D01*
G01X505156Y118300D02*
X509892Y113564D01*
G01X512784Y106454D02*
X514692Y104546D01*
G01X512784Y110192D02*
Y106454D01*
G01X513854Y111262D02*
X512784Y110192D01*
G01X513854Y113138D02*
Y111262D01*
G01X506292Y120700D02*
X513854Y113138D01*
G01X494118Y96474D02*
X495077Y95515D01*
G01X485745Y96474D02*
X494118D01*
G01X484062Y98157D02*
X485745Y96474D01*
G01X483071Y98157D02*
X484062D01*
G01X479528Y101700D02*
X483071Y98157D01*
G01X505876Y203316D02*
X540092Y193500D01*
G01X502292Y206900D02*
X505876Y203316D01*
G01X539892Y186100D02*
X566568Y159424D01*
G01X521592Y186100D02*
X539892D01*
G01X516476Y191216D02*
X521592Y186100D01*
G01X510076Y191216D02*
X516476D01*
G01X497392Y203900D02*
X510076Y191216D01*
G01X536893Y164300D02*
X562721Y138472D01*
G01X520193Y164300D02*
X536893D01*
G01X505634Y178859D02*
X520193Y164300D01*
G01X489633Y178859D02*
X505634D01*
G01X488292Y180200D02*
X489633Y178859D01*
G01X488292Y181201D02*
Y180200D01*
G01X488852Y181761D02*
X488292Y181201D01*
G01X490932Y181761D02*
X488852D01*
G01X491492Y182321D02*
X490932Y181761D01*
G01X491492Y183761D02*
Y182321D01*
G01X490932Y184321D02*
X491492Y183761D01*
G01X488852Y184321D02*
X490932D01*
G01X488292Y184881D02*
X488852Y184321D01*
G01X488292Y186654D02*
Y184881D01*
G01X488902Y187264D02*
X488292Y186654D01*
G01X490482Y187264D02*
X488902D01*
G01X491092Y187874D02*
X490482Y187264D01*
G01X491092Y189264D02*
Y187874D01*
G01X490482Y189874D02*
X491092Y189264D01*
G01X488902Y189874D02*
X490482D01*
G01X488292Y190484D02*
X488902Y189874D01*
G01X488292Y192801D02*
Y190484D01*
G01X483392Y197701D02*
X488292Y192801D01*
G01X529977Y188300D02*
X540992D01*
G01X529417Y188860D02*
X529977Y188300D01*
G01X529417Y191740D02*
Y188860D01*
G01X528857Y192300D02*
X529417Y191740D01*
G01X527417Y192300D02*
X528857D01*
G01X526857Y191740D02*
X527417Y192300D01*
G01X526857Y188860D02*
Y191740D01*
G01X526297Y188300D02*
X526857Y188860D01*
G01X523691Y188300D02*
X526297D01*
G01X517336Y194655D02*
X523691Y188300D01*
G01X511736Y194655D02*
X517336D01*
G01X501097Y205294D02*
X511736Y194655D01*
G01X519293Y158500D02*
X535392D01*
G01X502993Y174800D02*
X519293Y158500D01*
G01X482993Y174800D02*
X502993D01*
G01X479692Y178101D02*
X482993Y174800D01*
G01X479692Y182107D02*
Y178101D01*
G01X480302Y182717D02*
X479692Y182107D01*
G01X483082Y182717D02*
X480302D01*
G01X483692Y183327D02*
X483082Y182717D01*
G01X483692Y184717D02*
Y183327D01*
G01X483082Y185327D02*
X483692Y184717D01*
G01X483892Y188547D02*
X483282Y187937D01*
G01X483892Y189937D02*
Y188547D01*
G01X483282Y190547D02*
X483892Y189937D01*
G01X480302Y190547D02*
X483282D01*
G01X479692Y191157D02*
X480302Y190547D01*
G01X479692Y194501D02*
Y191157D01*
G01X538492Y183600D02*
X566518Y155574D01*
G01X519492Y183600D02*
X538492D01*
G01X514492Y188600D02*
X519492Y183600D01*
G01X509892Y188600D02*
X514492D01*
G01X495592Y202900D02*
X509892Y188600D01*
G01X535992Y161700D02*
X567066Y130626D01*
G01X519392Y161700D02*
X535992D01*
G01X504118Y176974D02*
X519392Y161700D01*
G01X487319Y176974D02*
X504118D01*
G01X485892Y178401D02*
X487319Y176974D01*
G01X485892Y191601D02*
Y178401D01*
G01X481192Y196301D02*
X485892Y191601D01*
G01X536592Y169400D02*
X564692Y141300D01*
G01X531105Y169400D02*
X536592D01*
G01X530495Y168790D02*
X531105Y169400D01*
G01X530495Y167510D02*
Y168790D01*
G01X529885Y166900D02*
X530495Y167510D01*
G01X528495Y166900D02*
X529885D01*
G01X527885Y167510D02*
X528495Y166900D01*
G01X527885Y168790D02*
Y167510D01*
G01X527275Y169400D02*
X527885Y168790D01*
G01X525885Y169400D02*
X527275D01*
G01X525275Y168790D02*
X525885Y169400D01*
G01X525275Y167510D02*
Y168790D01*
G01X524665Y166900D02*
X525275Y167510D01*
G01X523275Y166900D02*
X524665D01*
G01X522665Y167510D02*
X523275Y166900D01*
G01X522665Y168790D02*
Y167510D01*
G01X522055Y169400D02*
X522665Y168790D01*
G01X518593Y169400D02*
X522055D01*
G01X507249Y180744D02*
X518593Y169400D01*
G01X503148Y180744D02*
X507249D01*
G01X484992Y198900D02*
X503148Y180744D01*
G01X484992Y198962D02*
Y198900D01*
G01X532741Y443550D02*
X556692Y467501D01*
G01X527994Y443550D02*
X532741D01*
G01X527384Y442940D02*
X527994Y443550D01*
G01X527384Y441550D02*
Y442940D01*
G01X526774Y440940D02*
X527384Y441550D01*
G01X525384Y440940D02*
X526774D01*
G01X524774Y441550D02*
X525384Y440940D01*
G01X524774Y442940D02*
Y441550D01*
G01X524164Y443550D02*
X524774Y442940D01*
G01X522774Y443550D02*
X524164D01*
G01X522164Y442940D02*
X522774Y443550D01*
G01X522164Y441550D02*
Y442940D01*
G01X521554Y440940D02*
X522164Y441550D01*
G01X520164Y440940D02*
X521554D01*
G01X519554Y441550D02*
X520164Y440940D01*
G01X519554Y442940D02*
Y441550D01*
G01X518944Y443550D02*
X519554Y442940D01*
G01X514416Y443550D02*
X518944D01*
G01X507204Y450762D02*
X514416Y443550D01*
G01X494476Y450762D02*
X507204D01*
G01X487117Y443403D02*
X494476Y450762D01*
G01X487117Y434725D02*
Y443403D01*
G01X479592Y427200D02*
X487117Y434725D01*
G01X479592Y418777D02*
Y427200D01*
G01X479092Y418277D02*
X479592Y418777D01*
G01X528291Y434700D02*
X560792Y467201D01*
G01X510392Y434700D02*
X528291D01*
G01X504792Y429100D02*
X510392Y434700D01*
G01X497592Y429100D02*
X504792D01*
G01X491992Y423500D02*
X497592Y429100D01*
G01X533492Y414000D02*
X545075D01*
G01X528992Y409500D02*
X533492Y414000D01*
G01X522492Y409500D02*
X528992D01*
G01X532360Y418200D02*
X542203D01*
G01X528260Y414100D02*
X532360Y418200D01*
G01X522742Y414100D02*
X528260D01*
G01X531594Y420100D02*
X540491D01*
G01X527494Y416000D02*
X531594Y420100D01*
G01X522792Y416000D02*
X527494D01*
G01X532926Y416100D02*
X543639D01*
G01X528826Y412000D02*
X532926Y416100D01*
G01X522491Y412000D02*
X528826D01*
G01X501349Y423445D02*
X497454Y419550D01*
G01X507137Y423445D02*
X501349D01*
G01X511992Y428300D02*
X507137Y423445D01*
G01X534156Y428300D02*
X511992D01*
G01X573087Y467231D02*
X534156Y428300D01*
G01X530947Y445456D02*
X554192Y468701D01*
G01X515422Y445456D02*
X530947D01*
G01X508187Y452691D02*
X515422Y445456D01*
G01X493552Y452691D02*
X508187D01*
G01X483792Y442931D02*
X493552Y452691D01*
G01X483792Y435700D02*
Y442931D01*
G01X481392Y443197D02*
Y437600D01*
G01X492771Y454576D02*
X481392Y443197D01*
G01X509296Y454576D02*
X492771D01*
G01X516412Y447460D02*
X509296Y454576D01*
G01X518656Y447460D02*
X516412D01*
G01X519266Y448070D02*
X518656Y447460D01*
G01X519266Y449536D02*
Y448070D01*
G01X519876Y450146D02*
X519266Y449536D01*
G01X521266Y450146D02*
X519876D01*
G01X521876Y449536D02*
X521266Y450146D01*
G01X521876Y448070D02*
Y449536D01*
G01X522486Y447460D02*
X521876Y448070D01*
G01X523876Y447460D02*
X522486D01*
G01X524486Y448070D02*
X523876Y447460D01*
G01X524486Y449536D02*
Y448070D01*
G01X525096Y450146D02*
X524486Y449536D01*
G01X526486Y450146D02*
X525096D01*
G01X527096Y449536D02*
X526486Y450146D01*
G01X527096Y448070D02*
Y449536D01*
G01X527706Y447460D02*
X527096Y448070D01*
G01X529351Y447460D02*
X527706D01*
G01X551692Y469801D02*
X529351Y447460D01*
G01X539173Y442179D02*
X540806D01*
G01X537726Y440732D02*
X539173Y442179D01*
G01X537726Y439099D02*
Y440732D01*
G01X536280Y437653D02*
X537726Y439099D01*
G01X534647Y437653D02*
X536280D01*
G01X533200Y436206D02*
X534647Y437653D01*
G01X533200Y434573D02*
Y436206D01*
G01X530827Y432200D02*
X533200Y434573D01*
G01X510559Y432200D02*
X530827D01*
G01X505574Y427215D02*
X510559Y432200D01*
G01X498957Y427215D02*
X505574D01*
G01X493692Y421950D02*
X498957Y427215D01*
G01X530307Y452216D02*
X549192Y471101D01*
G01X515000Y452216D02*
X530307D01*
G01X510755Y456461D02*
X515000Y452216D01*
G01X491990Y456461D02*
X510755D01*
G01X479292Y443763D02*
X491990Y456461D01*
G01X479292Y440100D02*
Y443763D01*
G01X532520Y430200D02*
X575866Y473546D01*
G01X511226Y430200D02*
X532520D01*
G01X506356Y425330D02*
X511226Y430200D01*
G01X499972Y425330D02*
X506356D01*
G01X495792Y421150D02*
X499972Y425330D01*
G01X510104Y519862D02*
Y530049D01*
G01X511809Y518157D02*
X510104Y519862D01*
G01X511144Y517492D02*
X511809Y518157D01*
G01X511144Y513657D02*
Y517492D01*
G01X513692Y511109D02*
X511144Y513657D01*
G01X513692Y504700D02*
Y511109D01*
G01X513492Y504500D02*
X513692Y504700D01*
G01X513492Y495100D02*
Y504500D01*
G01X511992Y493600D02*
X513492Y495100D01*
G01X511992Y487300D02*
Y493600D01*
G01X509536Y484844D02*
X511992Y487300D01*
G01X523490Y519862D02*
Y529835D01*
G01X525195Y518157D02*
X523490Y519862D01*
G01X524735Y517697D02*
X525195Y518157D01*
G01X524735Y513475D02*
Y517697D01*
G01X527003Y511207D02*
X524735Y513475D01*
G01X527003Y509110D02*
Y511207D01*
G01X525992Y508099D02*
X527003Y509110D01*
G01X525992Y500500D02*
Y508099D01*
G01X526492Y500000D02*
X525992Y500500D01*
G01X526492Y497179D02*
Y500000D01*
G01X526292Y496979D02*
X526492Y497179D01*
G01X526292Y492126D02*
Y496979D01*
G01X525992Y491826D02*
X526292Y492126D01*
G01X525992Y484700D02*
Y491826D01*
G01X514636Y473344D02*
X525992Y484700D01*
G01X483135Y473344D02*
X514636D01*
G01X481199Y471408D02*
X483135Y473344D01*
G01X480069Y471408D02*
X481199D01*
G01X479200Y472276D02*
X480069Y471408D01*
G01X532523Y526156D02*
X533467Y527100D01*
G01X532523Y524944D02*
Y526156D01*
G01X533367Y524100D02*
X532523Y524944D01*
G01X533367Y522400D02*
Y524100D01*
G01X532523Y521556D02*
X533367Y522400D01*
G01X532523Y520136D02*
Y521556D01*
G01X533667Y518992D02*
X532523Y520136D01*
G01X533667Y517399D02*
Y518992D01*
G01X532760Y516492D02*
X533667Y517399D01*
G01X532760Y514800D02*
Y516492D01*
G01X534446Y513114D02*
X532760Y514800D01*
G01X534534Y513114D02*
X534446D01*
G01X534534Y512764D02*
Y513114D01*
G01X536455Y510843D02*
X534534Y512764D01*
G01X536455Y509337D02*
Y510843D01*
G01X537492Y508300D02*
X536455Y509337D01*
G01X537492Y503001D02*
Y508300D01*
G01X536455Y501964D02*
X537492Y503001D01*
G01X536455Y484015D02*
Y501964D01*
G01X528431Y475991D02*
X536455Y484015D01*
G01X528431Y474859D02*
Y475991D01*
G01X529562Y473728D02*
X528431Y474859D01*
G01X530694Y473728D02*
X529562D01*
G01X536322Y479356D02*
X530694Y473728D01*
G01X537366Y479356D02*
X536322D01*
G01X538497Y478225D02*
X537366Y479356D01*
G01X538497Y477005D02*
Y478225D01*
G01X527336Y465844D02*
X538497Y477005D01*
G01X487136Y465844D02*
X527336D01*
G01X489019Y526364D02*
X490056Y527401D01*
G01X489019Y525136D02*
Y526364D01*
G01X489956Y524199D02*
X489019Y525136D01*
G01X489956Y522801D02*
Y524199D01*
G01X489019Y521864D02*
X489956Y522801D01*
G01X489019Y520536D02*
Y521864D01*
G01X490156Y519399D02*
X489019Y520536D01*
G01X490156Y517500D02*
Y519399D01*
G01X489656Y517000D02*
X490156Y517500D01*
G01X489656Y514800D02*
Y517000D01*
G01X491342Y513114D02*
X489656Y514800D01*
G01X491430Y513114D02*
X491342D01*
G01X490792Y512476D02*
X491430Y513114D01*
G01X490792Y509114D02*
Y512476D01*
G01X489992Y508314D02*
X490792Y509114D01*
G01X480606Y508314D02*
X489992D01*
G01X516797Y519862D02*
Y530049D01*
G01X518502Y518157D02*
X516797Y519862D01*
G01X517892Y517547D02*
X518502Y518157D01*
G01X517892Y513699D02*
Y517547D01*
G01X520544Y511047D02*
X517892Y513699D01*
G01X520544Y504315D02*
Y511047D01*
G01X519744Y503515D02*
X520544Y504315D01*
G01X519492Y503515D02*
X519744D01*
G01X518692Y502715D02*
X519492Y503515D01*
G01X518692Y501115D02*
Y502715D01*
G01X519492Y500315D02*
X518692Y501115D01*
G01X519744Y500315D02*
X519492D01*
G01X520544Y499515D02*
X519744Y500315D01*
G01X520544Y497652D02*
Y499515D01*
G01X519592Y496700D02*
X520544Y497652D01*
G01X519592Y495100D02*
Y496700D01*
G01X519092Y494600D02*
X519592Y495100D01*
G01X519092Y487201D02*
Y494600D01*
G01X511735Y479844D02*
X519092Y487201D01*
G01X484949Y513114D02*
X485037D01*
G01X483263Y514800D02*
X484949Y513114D01*
G01X483263Y516492D02*
Y514800D01*
G01X483438Y516667D02*
X483263Y516492D01*
G01X483438Y519300D02*
Y516667D01*
G01X482326Y520412D02*
X483438Y519300D01*
G01X482326Y521488D02*
Y520412D01*
G01X483338Y522500D02*
X482326Y521488D01*
G01X483338Y523700D02*
Y522500D01*
G01X482326Y524712D02*
X483338Y523700D01*
G01X482326Y525788D02*
Y524712D01*
G01X483463Y526925D02*
X482326Y525788D01*
G01X512444D02*
X513581Y526925D01*
G01X512444Y524712D02*
Y525788D01*
G01X513456Y523700D02*
X512444Y524712D01*
G01X513456Y522500D02*
Y523700D01*
G01X512444Y521488D02*
X513456Y522500D01*
G01X512444Y520412D02*
Y521488D01*
G01X513556Y519300D02*
X512444Y520412D01*
G01X513556Y516667D02*
Y519300D01*
G01X513381Y516492D02*
X513556Y516667D01*
G01X513381Y514800D02*
Y516492D01*
G01X515067Y513114D02*
X513381Y514800D01*
G01X515155Y513114D02*
X515067D01*
G01X515192D02*
X515155D01*
G01X515992Y512314D02*
X515192Y513114D01*
G01X515992Y508742D02*
Y512314D01*
G01X516792Y507942D02*
X515992Y508742D01*
G01X517792Y507942D02*
X516792D01*
G01X518592Y507142D02*
X517792Y507942D01*
G01X518592Y505542D02*
Y507142D01*
G01X517792Y504742D02*
X518592Y505542D01*
G01X516992Y504742D02*
X517792D01*
G01X515592Y503342D02*
X516992Y504742D01*
G01X515592Y495300D02*
Y503342D01*
G01X516492Y494400D02*
X515592Y495300D01*
G01X516492Y488201D02*
Y494400D01*
G01X510635Y482344D02*
X516492Y488201D01*
G01X486679Y519862D02*
Y529835D01*
G01X488384Y518157D02*
X486679Y519862D01*
G01X487592Y517365D02*
X488384Y518157D01*
G01X487592Y512800D02*
Y517365D01*
G01X485844Y511052D02*
X487592Y512800D01*
G01X483566Y511052D02*
X485844D01*
G01X482666Y511952D02*
X483566Y511052D01*
G01X480766Y511952D02*
X482666D01*
G01X479986Y519862D02*
X481691Y518157D01*
G01X479986Y530049D02*
Y519862D01*
G01X525830Y526364D02*
X526867Y527401D01*
G01X525830Y525136D02*
Y526364D01*
G01X526767Y524199D02*
X525830Y525136D01*
G01X526767Y522801D02*
Y524199D01*
G01X525830Y521864D02*
X526767Y522801D01*
G01X525830Y520536D02*
Y521864D01*
G01X526967Y519399D02*
X525830Y520536D01*
G01X526967Y517500D02*
Y519399D01*
G01X526467Y517000D02*
X526967Y517500D01*
G01X526467Y514800D02*
Y517000D01*
G01X528153Y513114D02*
X526467Y514800D01*
G01X528241Y513114D02*
X528153D01*
G01X528992Y512363D02*
X528241Y513114D01*
G01X528992Y508571D02*
Y512363D01*
G01X529792Y507771D02*
X528992Y508571D01*
G01X531592Y507771D02*
X529792D01*
G01X532392Y506971D02*
X531592Y507771D01*
G01X532392Y505371D02*
Y506971D01*
G01X531592Y504571D02*
X532392Y505371D01*
G01X528463Y504571D02*
X531592D01*
G01X527892Y504000D02*
X528463Y504571D01*
G01X527892Y502200D02*
Y504000D01*
G01X528692Y501400D02*
X527892Y502200D01*
G01X528692Y495500D02*
Y501400D01*
G01X530067Y494125D02*
X528692Y495500D01*
G01X530067Y485173D02*
Y494125D01*
G01X521101Y476207D02*
X530067Y485173D01*
G01X521101Y475079D02*
Y476207D01*
G01X523560Y472620D02*
X521101Y475079D01*
G01X523560Y471666D02*
Y472620D01*
G01X522366Y470472D02*
X523560Y471666D01*
G01X521182Y470472D02*
X522366D01*
G01X518839Y472815D02*
X521182Y470472D01*
G01X517708Y472815D02*
X518839D01*
G01X515737Y470844D02*
X517708Y472815D01*
G01X484236Y470844D02*
X515737D01*
G01X531033Y517302D02*
X531888Y518157D01*
G01X531033Y513565D02*
Y517302D01*
G01X533692Y510906D02*
X531033Y513565D01*
G01X533692Y509100D02*
Y510906D01*
G01X534624Y508168D02*
X533692Y509100D01*
G01X534624Y503576D02*
Y508168D01*
G01X533792Y502744D02*
X534624Y503576D01*
G01X533792Y497578D02*
Y502744D01*
G01X532666Y496452D02*
X533792Y497578D01*
G01X532666Y483974D02*
Y496452D01*
G01X524644Y475952D02*
X532666Y483974D01*
G01X524644Y474863D02*
Y475952D01*
G01X528104Y471403D02*
X524644Y474863D01*
G01X528104Y470096D02*
Y471403D01*
G01X526352Y468344D02*
X528104Y470096D01*
G01X485937Y468344D02*
X526352D01*
G01X530183Y519862D02*
Y531515D01*
G01X531888Y518157D02*
X530183Y519862D01*
G01X493372D02*
Y531515D01*
G01X495077Y518157D02*
X493372Y519862D01*
G01X494393Y518157D02*
X495077D01*
G01X493592Y517356D02*
X494393Y518157D01*
G01X493592Y511975D02*
Y517356D01*
G01X492792Y511175D02*
X493592Y511975D01*
G01X492792Y507800D02*
Y511175D01*
G01X491506Y506514D02*
X492792Y507800D01*
G01X482505Y506514D02*
X491506D01*
G01X495712Y526156D02*
X496656Y527100D01*
G01X495712Y524944D02*
Y526156D01*
G01X496556Y524100D02*
X495712Y524944D01*
G01X496556Y522400D02*
Y524100D01*
G01X495712Y521556D02*
X496556Y522400D01*
G01X495712Y520136D02*
Y521556D01*
G01X496856Y518992D02*
X495712Y520136D01*
G01X496856Y517399D02*
Y518992D01*
G01X495949Y516492D02*
X496856Y517399D01*
G01X495949Y514800D02*
Y516492D01*
G01X497635Y513114D02*
X495949Y514800D01*
G01X497723Y513114D02*
X497635D01*
G01X498042D02*
X497723D01*
G01X499192Y511964D02*
X498042Y513114D01*
G01X499192Y510832D02*
Y511964D01*
G01X498392Y510032D02*
X499192Y510832D01*
G01X497192Y510032D02*
X498392D01*
G01X496492Y509332D02*
X497192Y510032D01*
G01X496492Y508200D02*
Y509332D01*
G01X497292Y507400D02*
X496492Y508200D01*
G01X500492Y507400D02*
X497292D01*
G01X501072Y506820D02*
X500492Y507400D01*
G01X501072Y505280D02*
Y506820D01*
G01X500506Y504714D02*
X501072Y505280D01*
G01X484505Y504714D02*
X500506D01*
G01X478256Y513114D02*
X478344D01*
G01X519137Y525788D02*
X520274Y526925D01*
G01X519137Y524712D02*
Y525788D01*
G01X520149Y523700D02*
X519137Y524712D01*
G01X520149Y522500D02*
Y523700D01*
G01X519137Y521488D02*
X520149Y522500D01*
G01X519137Y520412D02*
Y521488D01*
G01X520249Y519300D02*
X519137Y520412D01*
G01X520249Y516667D02*
Y519300D01*
G01X520074Y516492D02*
X520249Y516667D01*
G01X520074Y514800D02*
Y516492D01*
G01X521760Y513114D02*
X520074Y514800D01*
G01X521848Y513114D02*
X521760D01*
G01X523292Y511670D02*
X521848Y513114D01*
G01X523292Y502500D02*
Y511670D01*
G01X522792Y502000D02*
X523292Y502500D01*
G01X522792Y491678D02*
Y502000D01*
G01X522992Y491478D02*
X522792Y491678D01*
G01X522992Y487401D02*
Y491478D01*
G01X512935Y477344D02*
X522992Y487401D01*
G01X510104Y530049D02*
X515155Y535100D01*
G01X527167Y534700D02*
X528155D01*
G01X524112Y531645D02*
X527167Y534700D01*
G01X524112Y530457D02*
Y531645D01*
G01X523490Y529835D02*
X524112Y530457D01*
G01X532868Y528899D02*
X531888D01*
G01X533467Y528300D02*
X532868Y528899D01*
G01X533467Y527100D02*
Y528300D01*
G01X489456Y528899D02*
X488384D01*
G01X490056Y528299D02*
X489456Y528899D01*
G01X490056Y527401D02*
Y528299D01*
G01X516797Y530049D02*
X521848Y535100D01*
G01X483463Y528199D02*
Y526925D01*
G01X482763Y528899D02*
X483463Y528199D01*
G01X481691Y528899D02*
X482763D01*
G01X512881D02*
X511809D01*
G01X513581Y528199D02*
X512881Y528899D01*
G01X513581Y526925D02*
Y528199D01*
G01X490356Y534700D02*
X491344D01*
G01X487301Y531645D02*
X490356Y534700D01*
G01X487301Y530457D02*
Y531645D01*
G01X486679Y529835D02*
X487301Y530457D01*
G01X485037Y535100D02*
X479986Y530049D01*
G01X526267Y528899D02*
X525195D01*
G01X526867Y528299D02*
X526267Y528899D01*
G01X526867Y527401D02*
Y528299D01*
G01X533368Y534700D02*
X534534D01*
G01X530183Y531515D02*
X533368Y534700D01*
G01X496557D02*
X497723D01*
G01X493372Y531515D02*
X496557Y534700D01*
G01X496057Y528899D02*
X495077D01*
G01X496656Y528300D02*
X496057Y528899D01*
G01X496656Y527100D02*
Y528300D01*
G01X519574Y528899D02*
X518502D01*
G01X520274Y528199D02*
X519574Y528899D01*
G01X520274Y526925D02*
Y528199D01*
G01X592124Y66953D02*
Y65699D01*
G01X594671Y69500D02*
X592124Y66953D01*
G01X595671Y69500D02*
X594671D01*
G01X597471Y71300D02*
X595671Y69500D01*
G01X597471Y72700D02*
Y71300D01*
G01X596859Y73312D02*
X597471Y72700D01*
G01X596859Y86325D02*
Y73312D01*
G01X595470Y87714D02*
X596859Y86325D01*
G01X593692Y89492D02*
X595470Y87714D01*
G01X593692Y91200D02*
Y89492D01*
G01X594692Y92200D02*
X593692Y91200D01*
G01X594692Y148848D02*
Y92200D01*
G01X585431Y66953D02*
Y65699D01*
G01X587978Y69500D02*
X585431Y66953D01*
G01X588978Y69500D02*
X587978D01*
G01X590778Y71300D02*
X588978Y69500D01*
G01X590778Y72700D02*
Y71300D01*
G01X590166Y73312D02*
X590778Y72700D01*
G01X590166Y86325D02*
Y73312D01*
G01X588777Y87714D02*
X590166Y86325D01*
G01X586866Y89625D02*
X588777Y87714D01*
G01X586866Y91050D02*
Y89625D01*
G01X589584Y93768D02*
X586866Y91050D01*
G01X589584Y127230D02*
Y93768D01*
G01X557092Y73467D02*
X558659Y71900D01*
G01X557092Y74668D02*
Y73467D01*
G01X555734Y76026D02*
X557092Y74668D01*
G01X555734Y77399D02*
Y76026D01*
G01X556934Y78599D02*
X555734Y77399D01*
G01X556934Y79725D02*
Y78599D01*
G01X555734Y80925D02*
X556934Y79725D01*
G01X555734Y82500D02*
Y80925D01*
G01X557534Y84300D02*
X555734Y82500D01*
G01X557534Y85358D02*
Y84300D01*
G01X554192Y88700D02*
X557534Y85358D01*
G01X554192Y91636D02*
Y88700D01*
G01X555313Y92757D02*
X554192Y91636D01*
G01X555313Y96021D02*
Y92757D01*
G01X550492Y73374D02*
X551966Y71900D01*
G01X550492Y74468D02*
Y73374D01*
G01X549059Y75901D02*
X550492Y74468D01*
G01X549059Y77124D02*
Y75901D01*
G01X550559Y78624D02*
X549059Y77124D01*
G01X550559Y79976D02*
Y78624D01*
G01X549059Y81476D02*
X550559Y79976D01*
G01X549059Y82599D02*
Y81476D01*
G01X550734Y84274D02*
X549059Y82599D01*
G01X550734Y85659D02*
Y84274D01*
G01X547692Y88701D02*
X550734Y85659D01*
G01X547692Y91829D02*
Y88701D01*
G01X548620Y92757D02*
X547692Y91829D01*
G01X548434Y92942D02*
X548620Y92757D01*
G01X547407Y93970D02*
X548434Y92942D01*
G01X546700Y94677D02*
X547407Y93970D01*
G01X570478Y72367D02*
X571345Y71500D01*
G01X570478Y74668D02*
Y72367D01*
G01X568845Y76301D02*
X570478Y74668D01*
G01X568845Y77600D02*
Y76301D01*
G01X570195Y78950D02*
X568845Y77600D01*
G01X570195Y79850D02*
Y78950D01*
G01X568945Y81100D02*
X570195Y79850D01*
G01X568945Y82299D02*
Y81100D01*
G01X570478Y83832D02*
X568945Y82299D01*
G01X570478Y85800D02*
Y83832D01*
G01X567578Y88700D02*
X570478Y85800D01*
G01X567578Y91636D02*
Y88700D01*
G01X568699Y92757D02*
X567578Y91636D01*
G01X567784Y93672D02*
X568699Y92757D01*
G01X567784Y97891D02*
Y93672D01*
G01X548620Y66953D02*
Y65699D01*
G01X551167Y69500D02*
X548620Y66953D01*
G01X552167Y69500D02*
X551167D01*
G01X553967Y71300D02*
X552167Y69500D01*
G01X553967Y72700D02*
Y71300D01*
G01X553355Y73312D02*
X553967Y72700D01*
G01X553355Y86325D02*
Y73312D01*
G01X551966Y87714D02*
X553355Y86325D01*
G01X550092Y89588D02*
X551966Y87714D01*
G01X550092Y91600D02*
Y89588D01*
G01X550592Y92100D02*
X550092Y91600D01*
G01X550592Y95838D02*
Y92100D01*
G01X593903Y73467D02*
X595470Y71900D01*
G01X593903Y74668D02*
Y73467D01*
G01X592545Y76026D02*
X593903Y74668D01*
G01X592545Y77399D02*
Y76026D01*
G01X593745Y78599D02*
X592545Y77399D01*
G01X593745Y79725D02*
Y78599D01*
G01X592545Y80925D02*
X593745Y79725D01*
G01X592545Y82500D02*
Y80925D01*
G01X594345Y84300D02*
X592545Y82500D01*
G01X594345Y85358D02*
Y84300D01*
G01X591003Y88700D02*
X594345Y85358D01*
G01X591003Y91636D02*
Y88700D01*
G01X592124Y92757D02*
X591003Y91636D01*
G01X592124Y147816D02*
Y92757D01*
G01X563878Y72588D02*
X564966Y71500D01*
G01X563878Y74468D02*
Y72588D01*
G01X562445Y75901D02*
X563878Y74468D01*
G01X562445Y77100D02*
Y75901D01*
G01X563945Y78600D02*
X562445Y77100D01*
G01X563945Y79800D02*
Y78600D01*
G01X562495Y81250D02*
X563945Y79800D01*
G01X562495Y82649D02*
Y81250D01*
G01X563878Y84032D02*
X562495Y82649D01*
G01X563878Y85901D02*
Y84032D01*
G01X561078Y88701D02*
X563878Y85901D01*
G01X561078Y91829D02*
Y88701D01*
G01X562006Y92757D02*
X561078Y91829D01*
G01X563166Y93917D02*
X562006Y92757D01*
G01X563166Y99773D02*
Y93917D01*
G01X555313Y66953D02*
Y65699D01*
G01X557860Y69500D02*
X555313Y66953D01*
G01X558860Y69500D02*
X557860D01*
G01X560660Y71300D02*
X558860Y69500D01*
G01X560660Y72700D02*
Y71300D01*
G01X560048Y73312D02*
X560660Y72700D01*
G01X560048Y86325D02*
Y73312D01*
G01X558659Y87714D02*
X560048Y86325D01*
G01X556892Y89481D02*
X558659Y87714D01*
G01X556892Y91665D02*
Y89481D01*
G01X560566Y95339D02*
X556892Y91665D01*
G01X587303Y73374D02*
X588777Y71900D01*
G01X587303Y74468D02*
Y73374D01*
G01X585870Y75901D02*
X587303Y74468D01*
G01X585870Y77124D02*
Y75901D01*
G01X587370Y78624D02*
X585870Y77124D01*
G01X587370Y79976D02*
Y78624D01*
G01X585870Y81476D02*
X587370Y79976D01*
G01X585870Y82599D02*
Y81476D01*
G01X587545Y84274D02*
X585870Y82599D01*
G01X587545Y85659D02*
Y84274D01*
G01X584503Y88701D02*
X587545Y85659D01*
G01X584503Y91829D02*
Y88701D01*
G01X585431Y92757D02*
X584503Y91829D01*
G01X585431Y93861D02*
Y92757D01*
G01X584484Y94808D02*
X585431Y93861D01*
G01X562006Y67253D02*
Y65699D01*
G01X564253Y69500D02*
X562006Y67253D01*
G01X565477Y69500D02*
X564253D01*
G01X567053Y71076D02*
X565477Y69500D01*
G01X567053Y72700D02*
Y71076D01*
G01X566278Y73475D02*
X567053Y72700D01*
G01X566278Y86362D02*
Y73475D01*
G01X565266Y87374D02*
X566278Y86362D01*
G01X565052Y87588D02*
X565266Y87374D01*
G01X565052Y92646D02*
Y87588D01*
G01X565666Y93260D02*
X565052Y92646D01*
G01X565666Y98875D02*
Y93260D01*
G01X568699Y67821D02*
Y65699D01*
G01X570578Y69700D02*
X568699Y67821D01*
G01X571978Y69700D02*
X570578D01*
G01X573434Y71156D02*
X571978Y69700D01*
G01X573434Y72500D02*
Y71156D01*
G01X572818Y73116D02*
X573434Y72500D01*
G01X572818Y86241D02*
Y73116D01*
G01X571345Y87714D02*
X572818Y86241D01*
G01X569366Y89693D02*
X571345Y87714D01*
G01X569366Y90874D02*
Y89693D01*
G01X570766Y92274D02*
X569366Y90874D01*
G01X570766Y97439D02*
Y92274D01*
G01X576216Y167324D02*
X594692Y148848D01*
G01X588784Y128030D02*
X589584Y127230D01*
G01X587092Y128030D02*
X588784D01*
G01X586292Y128830D02*
X587092Y128030D01*
G01X586292Y130430D02*
Y128830D01*
G01X587092Y131230D02*
X586292Y130430D01*
G01X588784Y131230D02*
X587092D01*
G01X589392Y131838D02*
X588784Y131230D01*
G01X589392Y133822D02*
Y131838D01*
G01X588784Y134430D02*
X589392Y133822D01*
G01X587092Y134430D02*
X588784D01*
G01X586292Y135230D02*
X587092Y134430D01*
G01X586292Y149848D02*
Y135230D01*
G01X576716Y159424D02*
X586292Y149848D01*
G01X555748Y96456D02*
X555313Y96021D01*
G01X557184Y96456D02*
X555748D01*
G01X558284Y97556D02*
X557184Y96456D01*
G01X558284Y98456D02*
Y97556D01*
G01X557484Y99256D02*
X558284Y98456D01*
G01X556084Y99256D02*
X557484D01*
G01X555484Y99856D02*
X556084Y99256D01*
G01X555484Y101056D02*
Y99856D01*
G01X556284Y101856D02*
X555484Y101056D01*
G01X557584Y101856D02*
X556284D01*
G01X558284Y102556D02*
X557584Y101856D01*
G01X558284Y104556D02*
Y102556D01*
G01X556666Y106174D02*
X558284Y104556D01*
G01X556666Y110874D02*
Y106174D01*
G01X557166Y111374D02*
X556666Y110874D01*
G01X557166Y113774D02*
Y111374D01*
G01X554666Y116274D02*
X557166Y113774D01*
G01X554666Y126525D02*
Y116274D01*
G01X552455Y128736D02*
X554666Y126525D01*
G01X552455Y129598D02*
Y128736D01*
G01X553492Y130636D02*
X552455Y129598D01*
G01X553492Y131498D02*
Y130636D01*
G01X552508Y132482D02*
X553492Y131498D01*
G01X551647Y132482D02*
X552508D01*
G01X551524Y132359D02*
X551647Y132482D01*
G01X550732Y132359D02*
X551524D01*
G01X549564Y133527D02*
X550732Y132359D01*
G01X549564Y134884D02*
Y133527D01*
G01X546700Y95809D02*
Y94677D01*
G01X550420Y99529D02*
X546700Y95809D01*
G01X550420Y105520D02*
Y99529D01*
G01X550166Y105774D02*
X550420Y105520D01*
G01X550166Y111274D02*
Y105774D01*
G01X550732Y111840D02*
X550166Y111274D01*
G01X550732Y113300D02*
Y111840D01*
G01X549666Y114366D02*
X550732Y113300D01*
G01X549666Y121125D02*
Y114366D01*
G01X541192Y129599D02*
X549666Y121125D01*
G01X541192Y132700D02*
Y129599D01*
G01X569566Y99673D02*
X567784Y97891D01*
G01X569566Y100546D02*
Y99673D01*
G01X571092Y102072D02*
X569566Y100546D01*
G01X571092Y103346D02*
Y102072D01*
G01X569566Y104872D02*
X571092Y103346D01*
G01X569566Y106146D02*
Y104872D01*
G01X571092Y107672D02*
X569566Y106146D01*
G01X571092Y108946D02*
Y107672D01*
G01X569566Y110472D02*
X571092Y108946D01*
G01X569566Y111746D02*
Y110472D01*
G01X571092Y113272D02*
X569566Y111746D01*
G01X571092Y114546D02*
Y113272D01*
G01X569566Y116072D02*
X571092Y114546D01*
G01X569566Y117346D02*
Y116072D01*
G01X571092Y118872D02*
X569566Y117346D01*
G01X571092Y120146D02*
Y118872D01*
G01X569566Y121672D02*
X571092Y120146D01*
G01X569566Y122946D02*
Y121672D01*
G01X571092Y124472D02*
X569566Y122946D01*
G01X571092Y125746D02*
Y124472D01*
G01X569566Y127272D02*
X571092Y125746D01*
G01X569566Y128546D02*
Y127272D01*
G01X571092Y130072D02*
X569566Y128546D01*
G01X571092Y131346D02*
Y130072D01*
G01X569566Y132872D02*
X571092Y131346D01*
G01X569566Y134146D02*
Y132872D01*
G01X571092Y135672D02*
X569566Y134146D01*
G01X571092Y136946D02*
Y135672D01*
G01X569566Y138472D02*
X571092Y136946D01*
G01X562721Y138472D02*
X569566D01*
G01X551392Y96638D02*
X550592Y95838D01*
G01X552466Y96638D02*
X551392D01*
G01X553266Y97438D02*
X552466Y96638D01*
G01X553266Y104974D02*
Y97438D01*
G01X553766Y105474D02*
X553266Y104974D01*
G01X553766Y111174D02*
Y105474D01*
G01X553366Y111574D02*
X553766Y111174D01*
G01X553366Y113626D02*
Y111574D01*
G01X552166Y114826D02*
X553366Y113626D01*
G01X552166Y125526D02*
Y114826D01*
G01X577066Y162874D02*
X592124Y147816D01*
G01X564566Y101173D02*
X563166Y99773D01*
G01X564566Y114726D02*
Y101173D01*
G01X560892Y118400D02*
X564566Y114726D01*
G01X560892Y133000D02*
Y118400D01*
G01X560566Y114036D02*
Y95339D01*
G01X557384Y117218D02*
X560566Y114036D01*
G01X557384Y131308D02*
Y117218D01*
G01X584484Y96059D02*
Y94808D01*
G01X585284Y96859D02*
X584484Y96059D01*
G01X586184Y96859D02*
X585284D01*
G01X586984Y97659D02*
X586184Y96859D01*
G01X586984Y99200D02*
Y97659D01*
G01X586184Y100000D02*
X586984Y99200D01*
G01X585343Y100000D02*
X586184D01*
G01X584484Y100859D02*
X585343Y100000D01*
G01X584484Y103159D02*
Y100859D01*
G01X585384Y104059D02*
X584484Y103159D01*
G01X586284Y104059D02*
X585384D01*
G01X586984Y104759D02*
X586284Y104059D01*
G01X586984Y105659D02*
Y104759D01*
G01X586184Y106459D02*
X586984Y105659D01*
G01X584592Y106459D02*
X586184D01*
G01X583792Y107259D02*
X584592Y106459D01*
G01X583792Y108867D02*
Y107259D01*
G01X584592Y109667D02*
X583792Y108867D01*
G01X586192Y109667D02*
X584592D01*
G01X586992Y110467D02*
X586192Y109667D01*
G01X586992Y112067D02*
Y110467D01*
G01X586192Y112867D02*
X586992Y112067D01*
G01X584592Y112867D02*
X586192D01*
G01X583792Y113667D02*
X584592Y112867D01*
G01X583792Y115267D02*
Y113667D01*
G01X584592Y116067D02*
X583792Y115267D01*
G01X586192Y116067D02*
X584592D01*
G01X586992Y116867D02*
X586192Y116067D01*
G01X586992Y118467D02*
Y116867D01*
G01X586192Y119267D02*
X586992Y118467D01*
G01X584592Y119267D02*
X586192D01*
G01X583792Y120067D02*
X584592Y119267D01*
G01X583792Y148300D02*
Y120067D01*
G01X576518Y155574D02*
X583792Y148300D01*
G01X566518Y155574D02*
X576518D01*
G01X567066Y100275D02*
X565666Y98875D01*
G01X567066Y119496D02*
Y100275D01*
G01X566456Y120106D02*
X567066Y119496D01*
G01X564502Y120106D02*
X566456D01*
G01X563892Y120716D02*
X564502Y120106D01*
G01X563892Y122106D02*
Y120716D01*
G01X564502Y122716D02*
X563892Y122106D01*
G01X566456Y122716D02*
X564502D01*
G01X567066Y123326D02*
X566456Y122716D01*
G01X567066Y124716D02*
Y123326D01*
G01X566456Y125326D02*
X567066Y124716D01*
G01X564592Y125326D02*
X566456D01*
G01X564092Y125826D02*
X564592Y125326D01*
G01X564092Y127436D02*
Y125826D01*
G01X564592Y127936D02*
X564092Y127436D01*
G01X566456Y127936D02*
X564592D01*
G01X567066Y128546D02*
X566456Y127936D01*
G01X567066Y130626D02*
Y128546D01*
G01X573592Y100265D02*
X570766Y97439D01*
G01X573592Y138301D02*
Y100265D01*
G01X570593Y141300D02*
X573592Y138301D01*
G01X564692Y141300D02*
X570593D01*
G01X566268Y167324D02*
X576216D01*
G01X540092Y193500D02*
X566268Y167324D01*
G01X566568Y159424D02*
X576716D01*
G01X566418Y162874D02*
X577066D01*
G01X540992Y188300D02*
X566418Y162874D01*
G01X577236Y440700D02*
X603190Y466654D01*
G01X571775Y440700D02*
X577236D01*
G01X545075Y414000D02*
X571775Y440700D01*
G01X579369Y449904D02*
X599092Y469627D01*
G01X573907Y449904D02*
X579369D01*
G01X573312Y449309D02*
X573907Y449904D01*
G01X573312Y448447D02*
Y449309D01*
G01X574344Y447416D02*
X573312Y448447D01*
G01X574344Y446554D02*
Y447416D01*
G01X572943Y445153D02*
X574344Y446554D01*
G01X572081Y445153D02*
X572943D01*
G01X571049Y446184D02*
X572081Y445153D01*
G01X570187Y446184D02*
X571049D01*
G01X542203Y418200D02*
X570187Y446184D01*
G01X578333Y452404D02*
X596592Y470663D01*
G01X572795Y452404D02*
X578333D01*
G01X540491Y420100D02*
X572795Y452404D01*
G01X575700Y442700D02*
X601349Y468349D01*
G01X570239Y442700D02*
X575700D01*
G01X543639Y416100D02*
X570239Y442700D01*
G01X563436Y464809D02*
X573366Y474739D01*
G01X560356Y463362D02*
X561803Y464809D01*
G01X560356Y461729D02*
Y463362D01*
G01X558910Y460283D02*
X560356Y461729D01*
G01X557277Y460283D02*
X558910D01*
G01X555830Y458836D02*
X557277Y460283D01*
G01X555830Y457203D02*
Y458836D01*
G01X554384Y455757D02*
X555830Y457203D01*
G01X552751Y455757D02*
X554384D01*
G01X551304Y454310D02*
X552751Y455757D01*
G01X551304Y452677D02*
Y454310D01*
G01X549858Y451231D02*
X551304Y452677D01*
G01X548225Y451231D02*
X549858D01*
G01X546778Y449784D02*
X548225Y451231D01*
G01X546778Y448151D02*
Y449784D01*
G01X545332Y446705D02*
X546778Y448151D01*
G01X543699Y446705D02*
X545332D01*
G01X542252Y445258D02*
X543699Y446705D01*
G01X542252Y443625D02*
Y445258D01*
G01X540806Y442179D02*
X542252Y443625D01*
G01X555948Y525788D02*
X557085Y526925D01*
G01X555948Y524712D02*
Y525788D01*
G01X556960Y523700D02*
X555948Y524712D01*
G01X556960Y522500D02*
Y523700D01*
G01X555948Y521488D02*
X556960Y522500D01*
G01X555948Y520412D02*
Y521488D01*
G01X557060Y519300D02*
X555948Y520412D01*
G01X557060Y516667D02*
Y519300D01*
G01X556885Y516492D02*
X557060Y516667D01*
G01X556885Y514800D02*
Y516492D01*
G01X558571Y513114D02*
X556885Y514800D01*
G01X558659Y513114D02*
X558571D01*
G01X558659Y513166D02*
Y513114D01*
G01X559613Y512212D02*
X558659Y513166D01*
G01X559613Y497953D02*
Y512212D01*
G01X560466Y497100D02*
X559613Y497953D01*
G01X560466Y488694D02*
Y497100D01*
G01X556692Y484920D02*
X560466Y488694D01*
G01X556692Y467501D02*
Y484920D01*
G01X560301Y519862D02*
Y529835D01*
G01X562006Y518157D02*
X560301Y519862D01*
G01X560766Y516917D02*
X562006Y518157D01*
G01X560766Y514315D02*
Y516917D01*
G01X563806Y511275D02*
X560766Y514315D01*
G01X563806Y499417D02*
Y511275D01*
G01X564466Y498757D02*
X563806Y499417D01*
G01X564466Y481629D02*
Y498757D01*
G01X563666Y480829D02*
X564466Y481629D01*
G01X561592Y480829D02*
X563666D01*
G01X560792Y480029D02*
X561592Y480829D01*
G01X560792Y478429D02*
Y480029D01*
G01X561592Y477629D02*
X560792Y478429D01*
G01X567826Y477629D02*
X561592D01*
G01X568636Y476819D02*
X567826Y477629D01*
G01X568636Y475219D02*
Y476819D01*
G01X567846Y474429D02*
X568636Y475219D01*
G01X561638Y474429D02*
X567846D01*
G01X560792Y473583D02*
X561638Y474429D01*
G01X560792Y467201D02*
Y473583D01*
G01X592759Y525788D02*
X593896Y526925D01*
G01X592759Y524712D02*
Y525788D01*
G01X593771Y523700D02*
X592759Y524712D01*
G01X593771Y522500D02*
Y523700D01*
G01X592759Y521488D02*
X593771Y522500D01*
G01X592759Y520412D02*
Y521488D01*
G01X593871Y519300D02*
X592759Y520412D01*
G01X593871Y516667D02*
Y519300D01*
G01X593696Y516492D02*
X593871Y516667D01*
G01X593696Y514800D02*
Y516492D01*
G01X595382Y513114D02*
X593696Y514800D01*
G01X595470Y513114D02*
X595382D01*
G01X595470Y513166D02*
Y513114D01*
G01X596766Y511870D02*
X595470Y513166D01*
G01X596766Y509426D02*
Y511870D01*
G01X598312Y507880D02*
X596766Y509426D01*
G01X598312Y499254D02*
Y507880D01*
G01X598971Y498595D02*
X598312Y499254D01*
G01X600378Y498595D02*
X598971D01*
G01X601021Y499238D02*
X600378Y498595D01*
G01X601021Y506027D02*
Y499238D01*
G01X601666Y506672D02*
X601021Y506027D01*
G01X586066Y525788D02*
X587203Y526925D01*
G01X586066Y524712D02*
Y525788D01*
G01X587078Y523700D02*
X586066Y524712D01*
G01X587078Y522500D02*
Y523700D01*
G01X586066Y521488D02*
X587078Y522500D01*
G01X586066Y520412D02*
Y521488D01*
G01X587178Y519300D02*
X586066Y520412D01*
G01X587178Y516667D02*
Y519300D01*
G01X587003Y516492D02*
X587178Y516667D01*
G01X587003Y514800D02*
Y516492D01*
G01X588689Y513114D02*
X587003Y514800D01*
G01X588777Y513114D02*
X588689D01*
G01X590123Y511768D02*
X588777Y513114D01*
G01X590166Y511768D02*
X590123D01*
G01X590166Y509326D02*
Y511768D01*
G01X592692Y506800D02*
X590166Y509326D01*
G01X592692Y489581D02*
Y506800D01*
G01X593492Y488781D02*
X592692Y489581D01*
G01X596557Y488781D02*
X593492D01*
G01X597357Y487981D02*
X596557Y488781D01*
G01X597357Y486381D02*
Y487981D01*
G01X596557Y485581D02*
X597357Y486381D01*
G01X593315Y485581D02*
X596557D01*
G01X592515Y484781D02*
X593315Y485581D01*
G01X592515Y482835D02*
Y484781D01*
G01X593315Y482035D02*
X592515Y482835D01*
G01X598136Y482035D02*
X593315D01*
G01X599092Y481079D02*
X598136Y482035D01*
G01X599092Y469627D02*
Y481079D01*
G01X583726Y519862D02*
Y530049D01*
G01X585431Y518157D02*
X583726Y519862D01*
G01X584766Y517492D02*
X585431Y518157D01*
G01X584766Y513657D02*
Y517492D01*
G01X587666Y510757D02*
X584766Y513657D01*
G01X587666Y508462D02*
Y510757D01*
G01X590192Y505936D02*
X587666Y508462D01*
G01X590192Y473057D02*
Y505936D01*
G01X591036Y472213D02*
X590192Y473057D01*
G01X592636Y472213D02*
X591036D01*
G01X593392Y472969D02*
X592636Y472213D01*
G01X593392Y478721D02*
Y472969D01*
G01X594236Y479565D02*
X593392Y478721D01*
G01X595836Y479565D02*
X594236D01*
G01X596592Y478809D02*
X595836Y479565D01*
G01X596592Y470663D02*
Y478809D01*
G01X590419Y519862D02*
Y530049D01*
G01X592124Y518157D02*
X590419Y519862D01*
G01X591692Y517725D02*
X592124Y518157D01*
G01X591692Y513381D02*
Y517725D01*
G01X594166Y510907D02*
X591692Y513381D01*
G01X594166Y508726D02*
Y510907D01*
G01X595192Y507700D02*
X594166Y508726D01*
G01X595192Y492558D02*
Y507700D01*
G01X596025Y491725D02*
X595192Y492558D01*
G01X597625Y491725D02*
X596025D01*
G01X598392Y492492D02*
X597625Y491725D01*
G01X598392Y495218D02*
Y492492D01*
G01X599214Y496040D02*
X598392Y495218D01*
G01X600778Y496040D02*
X599214D01*
G01X601349Y495469D02*
X600778Y496040D01*
G01X601349Y468349D02*
Y495469D01*
G01X569334Y526156D02*
X570278Y527100D01*
G01X569334Y524944D02*
Y526156D01*
G01X570178Y524100D02*
X569334Y524944D01*
G01X570178Y522400D02*
Y524100D01*
G01X569334Y521556D02*
X570178Y522400D01*
G01X569334Y520136D02*
Y521556D01*
G01X570478Y518992D02*
X569334Y520136D01*
G01X570478Y517399D02*
Y518992D01*
G01X569571Y516492D02*
X570478Y517399D01*
G01X569571Y514800D02*
Y516492D01*
G01X571257Y513114D02*
X569571Y514800D01*
G01X571345Y513114D02*
X571257D01*
G01X574123Y467231D02*
X573087D01*
G01X575868Y468976D02*
X574123Y467231D01*
G01X575868Y470012D02*
Y468976D01*
G01X578366Y472510D02*
X575868Y470012D01*
G01X578366Y473675D02*
Y472510D01*
G01X579492Y474801D02*
X578366Y473675D01*
G01X579492Y476875D02*
Y474801D01*
G01X578366Y478001D02*
X579492Y476875D01*
G01X578366Y491454D02*
Y478001D01*
G01X577100Y492720D02*
X578366Y491454D01*
G01X572658Y492720D02*
X577100D01*
G01X571878Y493500D02*
X572658Y492720D01*
G01X571878Y495085D02*
Y493500D01*
G01X572756Y495963D02*
X571878Y495085D01*
G01X577844Y495963D02*
X572756D01*
G01X578425Y496544D02*
X577844Y495963D01*
G01X578425Y498538D02*
Y496544D01*
G01X577800Y499163D02*
X578425Y498538D01*
G01X573008Y499163D02*
X577800D01*
G01X572252Y499919D02*
X573008Y499163D01*
G01X572252Y501680D02*
Y499919D01*
G01X572862Y502290D02*
X572252Y501680D01*
G01X576185Y502290D02*
X572862D01*
G01X576795Y502900D02*
X576185Y502290D01*
G01X576795Y504290D02*
Y502900D01*
G01X576185Y504900D02*
X576795Y504290D01*
G01X573221Y504900D02*
X576185D01*
G01X572457Y505664D02*
X573221Y504900D01*
G01X572457Y511652D02*
Y505664D01*
G01X571345Y512764D02*
X572457Y511652D01*
G01X571345Y513114D02*
Y512764D01*
G01X553608Y519862D02*
Y530049D01*
G01X555313Y518157D02*
X553608Y519862D01*
G01X553955Y516799D02*
X555313Y518157D01*
G01X553955Y514537D02*
Y516799D01*
G01X557113Y511379D02*
X553955Y514537D01*
G01X557113Y497499D02*
Y511379D01*
G01X556892Y497278D02*
X557113Y497499D01*
G01X556892Y491815D02*
Y497278D01*
G01X557355Y491352D02*
X556892Y491815D01*
G01X557355Y489119D02*
Y491352D01*
G01X554192Y485956D02*
X557355Y489119D01*
G01X554192Y468701D02*
Y485956D01*
G01X549255Y525788D02*
X550392Y526925D01*
G01X549255Y524712D02*
Y525788D01*
G01X550267Y523700D02*
X549255Y524712D01*
G01X550267Y522500D02*
Y523700D01*
G01X549255Y521488D02*
X550267Y522500D01*
G01X549255Y520412D02*
Y521488D01*
G01X550367Y519300D02*
X549255Y520412D01*
G01X550367Y516667D02*
Y519300D01*
G01X550192Y516492D02*
X550367Y516667D01*
G01X550192Y514800D02*
Y516492D01*
G01X551878Y513114D02*
X550192Y514800D01*
G01X551966Y513114D02*
X551878D01*
G01X551692Y486992D02*
Y469801D01*
G01X554377Y489677D02*
X551692Y486992D01*
G01X554377Y493215D02*
Y489677D01*
G01X552747Y494845D02*
X554377Y493215D01*
G01X552747Y502152D02*
Y494845D01*
G01X553502Y502907D02*
X552747Y502152D01*
G01X554647Y502907D02*
X553502D01*
G01X555257Y503517D02*
X554647Y502907D01*
G01X555257Y504907D02*
Y503517D01*
G01X554647Y505517D02*
X555257Y504907D01*
G01X553422Y505517D02*
X554647D01*
G01X552813Y506126D02*
X553422Y505517D01*
G01X552813Y512267D02*
Y506126D01*
G01X551966Y513114D02*
X552813Y512267D01*
G01X562641Y526364D02*
X563478Y527201D01*
G01X562641Y525136D02*
Y526364D01*
G01X563492Y524285D02*
X562641Y525136D01*
G01X563492Y522715D02*
Y524285D01*
G01X562641Y521864D02*
X563492Y522715D01*
G01X562641Y520536D02*
Y521864D01*
G01X563778Y519399D02*
X562641Y520536D01*
G01X563778Y517500D02*
Y519399D01*
G01X563278Y517000D02*
X563778Y517500D01*
G01X563278Y514762D02*
Y517000D01*
G01X565266Y512774D02*
X563278Y514762D01*
G01X565592Y512448D02*
X565266Y512774D01*
G01X565592Y510101D02*
Y512448D01*
G01X566966Y508727D02*
X565592Y510101D01*
G01X566966Y481000D02*
Y508727D01*
G01X567766Y480200D02*
X566966Y481000D01*
G01X569366Y480200D02*
X567766D01*
G01X570166Y481000D02*
X569366Y480200D01*
G01X570166Y484000D02*
Y481000D01*
G01X570966Y484800D02*
X570166Y484000D01*
G01X572566Y484800D02*
X570966D01*
G01X573366Y484000D02*
X572566Y484800D01*
G01X573366Y474739D02*
Y484000D01*
G01X561803Y464809D02*
X563436D01*
G01X546915Y519862D02*
Y530049D01*
G01X548620Y518157D02*
X546915Y519862D01*
G01X547955Y517492D02*
X548620Y518157D01*
G01X547955Y513657D02*
Y517492D01*
G01X550692Y510920D02*
X547955Y513657D01*
G01X550692Y497889D02*
Y510920D01*
G01X550192Y497389D02*
X550692Y497889D01*
G01X550192Y495100D02*
Y497389D01*
G01X549192Y494100D02*
X550192Y495100D01*
G01X549192Y471101D02*
Y494100D01*
G01X566994Y519862D02*
Y531515D01*
G01X568699Y518157D02*
X566994Y519862D01*
G01X567292Y516750D02*
X568699Y518157D01*
G01X567292Y514181D02*
Y516750D01*
G01X570392Y511081D02*
X567292Y514181D01*
G01X570392Y509100D02*
Y511081D01*
G01X569466Y508174D02*
X570392Y509100D01*
G01X569466Y488200D02*
Y508174D01*
G01X570266Y487400D02*
X569466Y488200D01*
G01X571866Y487400D02*
X570266D01*
G01X572666Y488200D02*
X571866Y487400D01*
G01X572666Y489803D02*
Y488200D01*
G01X573466Y490603D02*
X572666Y489803D01*
G01X575066Y490603D02*
X573466D01*
G01X575866Y489803D02*
X575066Y490603D01*
G01X575866Y473546D02*
Y489803D01*
G01X556385Y528899D02*
X555313D01*
G01X557085Y528199D02*
X556385Y528899D01*
G01X557085Y526925D02*
Y528199D01*
G01X563978Y534700D02*
X564966D01*
G01X560923Y531645D02*
X563978Y534700D01*
G01X560923Y530457D02*
Y531645D01*
G01X560301Y529835D02*
X560923Y530457D01*
G01X593196Y528899D02*
X592124D01*
G01X593896Y528199D02*
X593196Y528899D01*
G01X593896Y526925D02*
Y528199D01*
G01X586503Y528899D02*
X585431D01*
G01X587203Y528199D02*
X586503Y528899D01*
G01X587203Y526925D02*
Y528199D01*
G01X583726Y530049D02*
X588777Y535100D01*
G01X590419Y530049D02*
X595470Y535100D01*
G01X569679Y528899D02*
X568699D01*
G01X570278Y528300D02*
X569679Y528899D01*
G01X570278Y527100D02*
Y528300D01*
G01X553608Y530049D02*
X558659Y535100D01*
G01X549692Y528899D02*
X548620D01*
G01X550392Y528199D02*
X549692Y528899D01*
G01X550392Y526925D02*
Y528199D01*
G01X562794Y528899D02*
X562006D01*
G01X563478Y528215D02*
X562794Y528899D01*
G01X563478Y527201D02*
Y528215D01*
G01X546915Y530049D02*
X551966Y535100D01*
G01X570179Y534700D02*
X571345D01*
G01X566994Y531515D02*
X570179Y534700D01*
G01X602690Y506672D02*
X601666D01*
G01X603190Y506172D02*
X602690Y506672D01*
G01X603190Y466654D02*
Y506172D01*
G01X779921Y92757D02*
X777528Y95150D01*
G01X778800Y91636D02*
X779921Y92757D01*
G01X778800Y88700D02*
Y91636D01*
G01X781700Y85800D02*
X778800Y88700D01*
G01X781700Y83832D02*
Y85800D01*
G01X780167Y82299D02*
X781700Y83832D01*
G01X780167Y81100D02*
Y82299D01*
G01X781417Y79850D02*
X780167Y81100D01*
G01X781417Y78950D02*
Y79850D01*
G01X780067Y77600D02*
X781417Y78950D01*
G01X780067Y76301D02*
Y77600D01*
G01X781700Y74668D02*
X780067Y76301D01*
G01X781700Y72367D02*
Y74668D01*
G01X782567Y71500D02*
X781700Y72367D01*
G01X773228Y67253D02*
Y65699D01*
G01X775475Y69500D02*
X773228Y67253D01*
G01X776699Y69500D02*
X775475D01*
G01X778275Y71076D02*
X776699Y69500D01*
G01X778275Y72700D02*
Y71076D01*
G01X777500Y73475D02*
X778275Y72700D01*
G01X777500Y86488D02*
Y73475D01*
G01X776274Y87714D02*
X777500Y86488D01*
G01X774392Y89596D02*
X776274Y87714D01*
G01X774392Y91056D02*
Y89596D01*
G01X775028Y91692D02*
X774392Y91056D01*
G01X775028Y125729D02*
Y91692D01*
G01X779921Y67821D02*
Y65699D01*
G01X781800Y69700D02*
X779921Y67821D01*
G01X783200Y69700D02*
X781800D01*
G01X784656Y71156D02*
X783200Y69700D01*
G01X784656Y72500D02*
Y71156D01*
G01X784040Y73116D02*
X784656Y72500D01*
G01X784040Y86241D02*
Y73116D01*
G01X782567Y87714D02*
X784040Y86241D01*
G01X780692Y89589D02*
X782567Y87714D01*
G01X780692Y91092D02*
Y89589D01*
G01X781988Y92388D02*
X780692Y91092D01*
G01X781988Y99752D02*
Y92388D01*
G01X772464Y93521D02*
X773228Y92757D01*
G01X772464Y131284D02*
Y93521D01*
G01X775100Y72588D02*
X776188Y71500D01*
G01X775100Y74468D02*
Y72588D01*
G01X773667Y75901D02*
X775100Y74468D01*
G01X773667Y77100D02*
Y75901D01*
G01X775167Y78600D02*
X773667Y77100D01*
G01X775167Y79800D02*
Y78600D01*
G01X773717Y81250D02*
X775167Y79800D01*
G01X773717Y82649D02*
Y81250D01*
G01X775100Y84032D02*
X773717Y82649D01*
G01X775100Y85901D02*
Y84032D01*
G01X772300Y88701D02*
X775100Y85901D01*
G01X772300Y91829D02*
Y88701D01*
G01X773228Y92757D02*
X772300Y91829D01*
G01X781492Y144060D02*
X897795Y260363D01*
G01X781492Y126624D02*
Y144060D01*
G01X780932Y126064D02*
X781492Y126624D01*
G01X779560Y126064D02*
X780932D01*
G01X779000Y125504D02*
X779560Y126064D01*
G01X779000Y124064D02*
Y125504D01*
G01X779560Y123504D02*
X779000Y124064D01*
G01X780932Y123504D02*
X779560D01*
G01X781492Y122944D02*
X780932Y123504D01*
G01X781492Y121504D02*
Y122944D01*
G01X780932Y120944D02*
X781492Y121504D01*
G01X779560Y120944D02*
X780932D01*
G01X779000Y120384D02*
X779560Y120944D01*
G01X779000Y118944D02*
Y120384D01*
G01X779560Y118384D02*
X779000Y118944D01*
G01X780932Y118384D02*
X779560D01*
G01X781492Y117824D02*
X780932Y118384D01*
G01X781492Y116384D02*
Y117824D01*
G01X780932Y115824D02*
X781492Y116384D01*
G01X779560Y115824D02*
X780932D01*
G01X779000Y115264D02*
X779560Y115824D01*
G01X779000Y113824D02*
Y115264D01*
G01X779560Y113264D02*
X779000Y113824D01*
G01X780932Y113264D02*
X779560D01*
G01X781492Y112704D02*
X780932Y113264D01*
G01X781492Y109672D02*
Y112704D01*
G01X781020Y109200D02*
X781492Y109672D01*
G01X778443Y109200D02*
X781020D01*
G01X777528Y108285D02*
X778443Y109200D01*
G01X777528Y95150D02*
Y108285D01*
G01X778992Y129693D02*
X775028Y125729D01*
G01X778992Y145096D02*
Y129693D01*
G01X896759Y262863D02*
X778992Y145096D01*
G01X783592Y101356D02*
X781988Y99752D01*
G01X783592Y102573D02*
Y101356D01*
G01X782792Y103373D02*
X783592Y102573D01*
G01X780492Y103373D02*
X782792D01*
G01X779692Y104173D02*
X780492Y103373D01*
G01X779692Y105373D02*
Y104173D01*
G01X780492Y106173D02*
X779692Y105373D01*
G01X782792Y106173D02*
X780492D01*
G01X783992Y107373D02*
X782792Y106173D01*
G01X783992Y143024D02*
Y107373D01*
G01X898831Y257863D02*
X783992Y143024D01*
G01X773024Y131844D02*
X772464Y131284D01*
G01X774740Y131844D02*
X773024D01*
G01X775300Y132404D02*
X774740Y131844D01*
G01X775300Y133844D02*
Y132404D01*
G01X774740Y134404D02*
X775300Y133844D01*
G01X773024Y134404D02*
X774740D01*
G01X772464Y134964D02*
X773024Y134404D01*
G01X772464Y142104D02*
Y134964D01*
G01X895723Y265363D02*
X772464Y142104D01*
G01X780354Y464565D02*
X779744Y465175D01*
G01X781741Y464565D02*
X780354D01*
G01X782311Y463995D02*
X781741Y464565D01*
G01X782311Y462605D02*
Y463995D01*
G01X781661Y461955D02*
X782311Y462605D01*
G01X780354Y461955D02*
X781661D01*
G01X779744Y461345D02*
X780354Y461955D01*
G01X779744Y460026D02*
Y461345D01*
G01X780958Y457094D02*
X779744Y460026D01*
G01X796752Y441300D02*
X780958Y457094D01*
G01X786217Y457582D02*
Y480074D01*
G01X798699Y445100D02*
X786217Y457582D01*
G01X784149Y456951D02*
Y477751D01*
G01X797900Y443200D02*
X784149Y456951D01*
G01X777467Y460450D02*
Y504747D01*
G01X779324Y455968D02*
X777467Y460450D01*
G01X795892Y439400D02*
X779324Y455968D01*
G01X773863Y526364D02*
X774900Y527401D01*
G01X773863Y525136D02*
Y526364D01*
G01X774800Y524199D02*
X773863Y525136D01*
G01X774800Y523166D02*
Y524199D01*
G01X773863Y522229D02*
X774800Y523166D01*
G01X773863Y520901D02*
Y522229D01*
G01X775000Y519764D02*
X773863Y520901D01*
G01X775000Y517500D02*
Y519764D01*
G01X774500Y517000D02*
X775000Y517500D01*
G01X774500Y514800D02*
Y517000D01*
G01X776186Y513114D02*
X774500Y514800D01*
G01X776274Y513114D02*
X776186D01*
G01X777788Y511600D02*
X776274Y513114D01*
G01X777788Y508512D02*
Y511600D01*
G01X779400Y506900D02*
X777788Y508512D01*
G01X779400Y476389D02*
Y506900D01*
G01X780010Y475779D02*
X779400Y476389D01*
G01X781650Y475779D02*
X780010D01*
G01X782280Y475149D02*
X781650Y475779D01*
G01X782280Y473759D02*
Y475149D01*
G01X781690Y473169D02*
X782280Y473759D01*
G01X780010Y473169D02*
X781690D01*
G01X779400Y472559D02*
X780010Y473169D01*
G01X779400Y470373D02*
Y472559D01*
G01X779988Y469785D02*
X779400Y470373D01*
G01X781234Y469785D02*
X779988D01*
G01X781844Y469175D02*
X781234Y469785D01*
G01X781844Y467785D02*
Y469175D01*
G01X781234Y467175D02*
X781844Y467785D01*
G01X780354Y467175D02*
X781234D01*
G01X779744Y466565D02*
X780354Y467175D01*
G01X779744Y465175D02*
Y466565D01*
G01X780556Y526156D02*
X781500Y527100D01*
G01X780556Y524944D02*
Y526156D01*
G01X781400Y524100D02*
X780556Y524944D01*
G01X781400Y522400D02*
Y524100D01*
G01X780556Y521556D02*
X781400Y522400D01*
G01X780556Y520136D02*
Y521556D01*
G01X781700Y518992D02*
X780556Y520136D01*
G01X781700Y517399D02*
Y518992D01*
G01X780793Y516492D02*
X781700Y517399D01*
G01X780793Y514800D02*
Y516492D01*
G01X782479Y513114D02*
X780793Y514800D01*
G01X782567Y513114D02*
X782479D01*
G01X784488Y511193D02*
X782567Y513114D01*
G01X784488Y504440D02*
Y511193D01*
G01X783729Y503681D02*
X784488Y504440D01*
G01X783729Y502291D02*
Y503681D01*
G01X784339Y501681D02*
X783729Y502291D01*
G01X786047Y501681D02*
X784339D01*
G01X786657Y501071D02*
X786047Y501681D01*
G01X786657Y499681D02*
Y501071D01*
G01X786047Y499071D02*
X786657Y499681D01*
G01X784338Y499071D02*
X786047D01*
G01X783728Y498461D02*
X784338Y499071D01*
G01X783728Y497071D02*
Y498461D01*
G01X784338Y496461D02*
X783728Y497071D01*
G01X786312Y496461D02*
X784338D01*
G01X786922Y495851D02*
X786312Y496461D01*
G01Y493851D02*
X786922Y494461D01*
G01X784365Y493851D02*
X786312D01*
G01X783755Y493241D02*
X784365Y493851D01*
G01X783755Y491851D02*
Y493241D01*
G01X784365Y491241D02*
X783755Y491851D01*
G01X786073Y491241D02*
X784365D01*
G01X786683Y490631D02*
X786073Y491241D01*
G01Y488631D02*
X786683Y489241D01*
G01X784577Y488631D02*
X786073D01*
G01X783914Y487968D02*
X784577Y488631D01*
G01X783914Y486578D02*
Y487968D01*
G01X784471Y486021D02*
X783914Y486578D01*
G01X786127Y486021D02*
X784471D01*
G01X786657Y485491D02*
X786127Y486021D01*
G01X786657Y484101D02*
Y485491D01*
G01X785967Y483411D02*
X786657Y484101D01*
G01X784497Y483411D02*
X785967D01*
G01X783887Y482801D02*
X784497Y483411D01*
G01X783887Y481411D02*
Y482801D01*
G01X784497Y480801D02*
X783887Y481411D01*
G01X785490Y480801D02*
X784497D01*
G01X786217Y480074D02*
X785490Y480801D01*
G01X778216Y519862D02*
Y530349D01*
G01X779921Y518157D02*
X778216Y519862D01*
G01X778800Y517036D02*
X779921Y518157D01*
G01X778800Y513817D02*
Y517036D01*
G01X781900Y510717D02*
X778800Y513817D01*
G01X781900Y480000D02*
Y510717D01*
G01X784149Y477751D02*
X781900Y480000D01*
G01X771523Y522274D02*
Y529277D01*
G01X773228Y518157D02*
X771523Y522274D01*
G01X772610Y517539D02*
X773228Y518157D01*
G01X772610Y513459D02*
Y517539D01*
G01X774742Y511327D02*
X772610Y513459D01*
G01X777467Y504747D02*
X774742Y511327D01*
G01X774300Y528899D02*
X773228D01*
G01X774900Y528299D02*
X774300Y528899D01*
G01X774900Y527401D02*
Y528299D01*
G01X780901Y528899D02*
X779921D01*
G01X781500Y528300D02*
X780901Y528899D01*
G01X781500Y527100D02*
Y528300D01*
G01X778216Y530349D02*
X782567Y534700D01*
G01X772059Y530571D02*
X776188Y534700D01*
G01X771523Y529277D02*
X772059Y530571D01*
G01X804800Y91300D02*
X809400Y95900D01*
G01X804800Y89606D02*
Y91300D01*
G01X806692Y87714D02*
X804800Y89606D01*
G01X804593Y66946D02*
X803346Y65699D01*
G01X804593Y68200D02*
Y66946D01*
G01X805893Y69500D02*
X804593Y68200D01*
G01X806893Y69500D02*
X805893D01*
G01X808693Y71300D02*
X806893Y69500D01*
G01X808693Y72700D02*
Y71300D01*
G01X808081Y73312D02*
X808693Y72700D01*
G01X808081Y86325D02*
Y73312D01*
G01X806692Y87714D02*
X808081Y86325D01*
G01X835336Y73374D02*
X836810Y71900D01*
G01X835336Y74468D02*
Y73374D01*
G01X833903Y75901D02*
X835336Y74468D01*
G01X833903Y77124D02*
Y75901D01*
G01X835403Y78624D02*
X833903Y77124D01*
G01X835403Y79976D02*
Y78624D01*
G01X833903Y81476D02*
X835403Y79976D01*
G01X833903Y82599D02*
Y81476D01*
G01X835578Y84274D02*
X833903Y82599D01*
G01X835578Y85659D02*
Y84274D01*
G01X832536Y88701D02*
X835578Y85659D01*
G01X832536Y91829D02*
Y88701D01*
G01X833464Y92757D02*
X832536Y91829D01*
G01X847992Y91192D02*
X848792Y91992D01*
G01X847992Y89618D02*
Y91192D01*
G01X849896Y87714D02*
X847992Y89618D01*
G01X846850Y67253D02*
X849097Y69500D01*
G01X846850Y65699D02*
Y67253D01*
G01X816732Y67821D02*
Y65699D01*
G01X818611Y69700D02*
X816732Y67821D01*
G01X820011Y69700D02*
X818611D01*
G01X821467Y71156D02*
X820011Y69700D01*
G01X821467Y72500D02*
Y71156D01*
G01X820851Y73116D02*
X821467Y72500D01*
G01X820851Y86241D02*
Y73116D01*
G01X819378Y87714D02*
X820851Y86241D01*
G01X845292Y94315D02*
X846850Y92757D01*
G01X845292Y173341D02*
Y94315D01*
G01X847289Y75901D02*
X848722Y74468D01*
G01X847289Y77100D02*
Y75901D01*
G01X848789Y78600D02*
X847289Y77100D01*
G01X847339Y81250D02*
X848789Y79800D01*
G01X847339Y82649D02*
Y81250D01*
G01X848722Y84032D02*
X847339Y82649D01*
G01X845922Y88701D02*
X848722Y85901D01*
G01X845922Y91829D02*
Y88701D01*
G01X846850Y92757D02*
X845922Y91829D01*
G01X796653Y92757D02*
Y131400D01*
G01X795725Y91829D02*
X796653Y92757D01*
G01X795725Y88701D02*
Y91829D01*
G01X798767Y85659D02*
X795725Y88701D01*
G01X798767Y84274D02*
Y85659D01*
G01X797092Y82599D02*
X798767Y84274D01*
G01X797092Y81476D02*
Y82599D01*
G01X798592Y79976D02*
X797092Y81476D01*
G01X798592Y78624D02*
Y79976D01*
G01X797092Y77124D02*
X798592Y78624D01*
G01X797092Y75901D02*
Y77124D01*
G01X798525Y74468D02*
X797092Y75901D01*
G01X798525Y73374D02*
Y74468D01*
G01X799999Y71900D02*
X798525Y73374D01*
G01X841404Y66946D02*
X840157Y65699D01*
G01X841404Y68200D02*
Y66946D01*
G01X842704Y69500D02*
X841404Y68200D01*
G01X843704Y69500D02*
X842704D01*
G01X845504Y71300D02*
X843704Y69500D01*
G01X845504Y72700D02*
Y71300D01*
G01X844892Y73312D02*
X845504Y72700D01*
G01X844892Y86325D02*
Y73312D01*
G01X843503Y87714D02*
X844892Y86325D01*
G01X811911Y72588D02*
X812999Y71500D01*
G01X811911Y74468D02*
Y72588D01*
G01X810478Y75901D02*
X811911Y74468D01*
G01X810478Y77100D02*
Y75901D01*
G01X811978Y78600D02*
X810478Y77100D01*
G01X811978Y79800D02*
Y78600D01*
G01X810528Y81250D02*
X811978Y79800D01*
G01X810528Y82649D02*
Y81250D01*
G01X811911Y84032D02*
X810528Y82649D01*
G01X811911Y85901D02*
Y84032D01*
G01X809111Y88701D02*
X811911Y85901D01*
G01X809111Y91829D02*
Y88701D01*
G01X810039Y92757D02*
X809111Y91829D01*
G01X805125Y73467D02*
X806692Y71900D01*
G01X805125Y74668D02*
Y73467D01*
G01X803767Y76026D02*
X805125Y74668D01*
G01X803767Y77399D02*
Y76026D01*
G01X804967Y78599D02*
X803767Y77399D01*
G01X804967Y79725D02*
Y78599D01*
G01X803767Y80925D02*
X804967Y79725D01*
G01X803767Y82500D02*
Y80925D01*
G01X805567Y84300D02*
X803767Y82500D01*
G01X805567Y85358D02*
Y84300D01*
G01X802225Y88700D02*
X805567Y85358D01*
G01X802225Y91636D02*
Y88700D01*
G01X803346Y92757D02*
X802225Y91636D01*
G01X805046Y94457D02*
X803346Y92757D01*
G01X805046Y96347D02*
Y94457D01*
G01X818511Y72367D02*
X819378Y71500D01*
G01X818511Y74668D02*
Y72367D01*
G01X816878Y76301D02*
X818511Y74668D01*
G01X816878Y77600D02*
Y76301D01*
G01X818228Y78950D02*
X816878Y77600D01*
G01X818228Y79850D02*
Y78950D01*
G01X816978Y81100D02*
X818228Y79850D01*
G01X816978Y82299D02*
Y81100D01*
G01X818511Y83832D02*
X816978Y82299D01*
G01X818511Y85800D02*
Y83832D01*
G01X815611Y88700D02*
X818511Y85800D01*
G01X815611Y91636D02*
Y88700D01*
G01X816732Y92757D02*
X815611Y91636D01*
G01X841936Y73467D02*
X843503Y71900D01*
G01X841936Y74668D02*
Y73467D01*
G01X840578Y76026D02*
X841936Y74668D01*
G01X840578Y77399D02*
Y76026D01*
G01X841778Y78599D02*
X840578Y77399D01*
G01X841778Y79725D02*
Y78599D01*
G01X840578Y80925D02*
X841778Y79725D01*
G01X840578Y82500D02*
Y80925D01*
G01X842378Y84300D02*
X840578Y82500D01*
G01X842378Y85358D02*
Y84300D01*
G01X839036Y88700D02*
X842378Y85358D01*
G01X839036Y91636D02*
Y88700D01*
G01X840157Y92757D02*
X839036Y91636D01*
G01X797900Y66946D02*
X796653Y65699D01*
G01X797900Y68200D02*
Y66946D01*
G01X799200Y69500D02*
X797900Y68200D01*
G01X800200Y69500D02*
X799200D01*
G01X802000Y71300D02*
X800200Y69500D01*
G01X802000Y72700D02*
Y71300D01*
G01X801388Y73312D02*
X802000Y72700D01*
G01X801388Y86325D02*
Y73312D01*
G01X799999Y87714D02*
X801388Y86325D01*
G01X798192Y89521D02*
X799999Y87714D01*
G01X798192Y91156D02*
Y89521D01*
G01X799153Y92117D02*
X798192Y91156D01*
G01X799153Y112100D02*
Y92117D01*
G01X810039Y67253D02*
Y65699D01*
G01X812286Y69500D02*
X810039Y67253D01*
G01X813510Y69500D02*
X812286D01*
G01X815086Y71076D02*
X813510Y69500D01*
G01X815086Y72700D02*
Y71076D01*
G01X814311Y73475D02*
X815086Y72700D01*
G01X814311Y86488D02*
Y73475D01*
G01X813085Y87714D02*
X814311Y86488D01*
G01X834711Y66946D02*
X833464Y65699D01*
G01X834711Y68200D02*
Y66946D01*
G01X836011Y69500D02*
X834711Y68200D01*
G01X837011Y69500D02*
X836011D01*
G01X838811Y71300D02*
X837011Y69500D01*
G01X838811Y72700D02*
Y71300D01*
G01X838199Y73312D02*
X838811Y72700D01*
G01X838199Y86325D02*
Y73312D01*
G01X836810Y87714D02*
X838199Y86325D01*
G01X821892Y155881D02*
X906170Y240159D01*
G01X821892Y133656D02*
Y155881D01*
G01X821092Y132856D02*
X821892Y133656D01*
G01X819892Y132856D02*
X821092D01*
G01X819092Y133656D02*
X819892Y132856D01*
G01X819092Y148856D02*
Y133656D01*
G01X818292Y149656D02*
X819092Y148856D01*
G01X817092Y149656D02*
X818292D01*
G01X816292Y148856D02*
X817092Y149656D01*
G01X816292Y98792D02*
Y148856D01*
G01X813400Y95900D02*
X816292Y98792D01*
G01X809400Y95900D02*
X813400D01*
G01X848250Y96343D02*
Y172301D01*
G01X848792Y95801D02*
X848250Y96343D01*
G01X806792Y151389D02*
X903062Y247659D01*
G01X806792Y148092D02*
Y151389D01*
G01X804400Y145700D02*
X806792Y148092D01*
G01X804400Y144000D02*
Y145700D01*
G01X806792Y141608D02*
X804400Y144000D01*
G01X806792Y131492D02*
Y141608D01*
G01X802253Y126953D02*
X806792Y131492D01*
G01X802253Y116400D02*
Y126953D01*
G01X801453Y115600D02*
X802253Y116400D01*
G01X800253Y115600D02*
X801453D01*
G01X799453Y116400D02*
X800253Y115600D01*
G01X799453Y131400D02*
Y116400D01*
G01X798653Y132200D02*
X799453Y131400D01*
G01X797453Y132200D02*
X798653D01*
G01X796653Y131400D02*
X797453Y132200D01*
G01X807592Y98893D02*
X805046Y96347D01*
G01X807592Y124500D02*
Y98893D01*
G01X808392Y125300D02*
X807592Y124500D01*
G01X809592Y125300D02*
X808392D01*
G01X810392Y124500D02*
X809592Y125300D01*
G01X810392Y103200D02*
Y124500D01*
G01X811192Y102400D02*
X810392Y103200D01*
G01X812392Y102400D02*
X811192D01*
G01X813192Y103200D02*
X812392Y102400D01*
G01X813192Y150717D02*
Y103200D01*
G01X905134Y242659D02*
X813192Y150717D01*
G01X799953Y112900D02*
X799153Y112100D01*
G01X801153Y112900D02*
X799953D01*
G01X801953Y112100D02*
X801153Y112900D01*
G01X801953Y100900D02*
Y112100D01*
G01X802753Y100100D02*
X801953Y100900D01*
G01X803953Y100100D02*
X802753D01*
G01X805092Y101239D02*
X803953Y100100D01*
G01X805092Y126092D02*
Y101239D01*
G01X809592Y130592D02*
X805092Y126092D01*
G01X809592Y150653D02*
Y130592D01*
G01X904098Y245159D02*
X809592Y150653D01*
G01X848250Y172301D02*
X906351Y230402D01*
G01X904903Y232952D02*
X845292Y173341D01*
G01X847600Y394500D02*
X800800Y441300D01*
G01X847600Y388660D02*
Y394500D01*
G01X903924Y332336D02*
X847600Y388660D01*
G01X851500Y395999D02*
X802399Y445100D01*
G01X849500Y395300D02*
X801600Y443200D01*
G01X845700Y393600D02*
X799900Y439400D01*
G01X845700Y387894D02*
Y393600D01*
G01X903347Y330247D02*
X845700Y387894D01*
G01X844900Y431478D02*
Y500712D01*
G01X870180Y406198D02*
X844900Y431478D01*
G01X800400Y455730D02*
Y506300D01*
G01X801226Y454904D02*
X800400Y455730D01*
G01X802826Y454904D02*
X801226D01*
G01X803600Y455678D02*
X802826Y454904D01*
G01X803600Y468070D02*
Y455678D01*
G01X806800Y452100D02*
Y468070D01*
G01X859600Y399300D02*
X806800Y452100D01*
G01X800800Y441300D02*
X796752D01*
G01X814388Y453400D02*
Y507000D01*
G01X815188Y452600D02*
X814388Y453400D01*
G01X816788Y452600D02*
X815188D01*
G01X817588Y453400D02*
X816788Y452600D01*
G01X817588Y470600D02*
Y453400D01*
G01X820788Y446179D02*
Y470600D01*
G01X865285Y401682D02*
X820788Y446179D01*
G01X842400Y430400D02*
Y505023D01*
G01X868295Y404505D02*
X842400Y430400D01*
G01X802399Y445100D02*
X798699D01*
G01X801600Y443200D02*
X797900D01*
G01X799900Y439400D02*
X795892D01*
G01X809300Y452300D02*
Y486200D01*
G01X861500Y400100D02*
X809300Y452300D01*
G01X811800Y452500D02*
Y505100D01*
G01X863400Y400900D02*
X811800Y452500D01*
G01X847500Y432438D02*
Y497300D01*
G01X872065Y407873D02*
X847500Y432438D01*
G01X831759Y519862D02*
X833464Y518157D01*
G01X831759Y530049D02*
Y519862D01*
G01X812997Y513114D02*
X813085D01*
G01X811311Y514800D02*
X812997Y513114D01*
G01X811311Y517000D02*
Y514800D01*
G01X811811Y517500D02*
X811311Y517000D01*
G01X811811Y519399D02*
Y517500D01*
G01X810674Y520536D02*
X811811Y519399D01*
G01X810674Y521864D02*
Y520536D01*
G01X811611Y522801D02*
X810674Y521864D01*
G01X811611Y524199D02*
Y522801D01*
G01X810674Y525136D02*
X811611Y524199D01*
G01X810674Y526364D02*
Y525136D01*
G01X811711Y527401D02*
X810674Y526364D01*
G01X848292Y506392D02*
X849896Y507996D01*
G01X845660Y506392D02*
X848292D01*
G01X845100Y505832D02*
X845660Y506392D01*
G01X845100Y504392D02*
Y505832D01*
G01X845660Y503832D02*
X845100Y504392D01*
G01X848240Y503832D02*
X845660D01*
G01X848800Y503272D02*
X848240Y503832D01*
G01Y501272D02*
X848800Y501832D01*
G01X845460Y501272D02*
X848240D01*
G01X844900Y500712D02*
X845460Y501272D01*
G01X847485Y526364D02*
X848522Y527401D01*
G01X847485Y525136D02*
Y526364D01*
G01X848422Y524199D02*
X847485Y525136D01*
G01Y521864D02*
X848422Y522801D01*
G01X847485Y520536D02*
Y521864D01*
G01X848622Y519399D02*
X847485Y520536D01*
G01X848122Y517000D02*
X848622Y517500D01*
G01X848122Y514800D02*
Y517000D01*
G01X849808Y513114D02*
X848122Y514800D01*
G01X794948Y519862D02*
Y530049D01*
G01X796653Y518157D02*
X794948Y519862D01*
G01X795988Y517492D02*
X796653Y518157D01*
G01X795988Y513657D02*
Y517492D01*
G01X798888Y510757D02*
X795988Y513657D01*
G01X798888Y507812D02*
Y510757D01*
G01X800400Y506300D02*
X798888Y507812D01*
G01X804400Y468870D02*
X803600Y468070D01*
G01X806000Y468870D02*
X804400D01*
G01X806800Y468070D02*
X806000Y468870D01*
G01X836722Y513114D02*
X836810D01*
G01X835036Y514800D02*
X836722Y513114D01*
G01X835036Y516492D02*
Y514800D01*
G01X835211Y516667D02*
X835036Y516492D01*
G01X835211Y519300D02*
Y516667D01*
G01X834099Y520412D02*
X835211Y519300D01*
G01X834099Y521488D02*
Y520412D01*
G01X835111Y522500D02*
X834099Y521488D01*
G01X835111Y523700D02*
Y522500D01*
G01X834099Y524712D02*
X835111Y523700D01*
G01X834099Y525788D02*
Y524712D01*
G01X835236Y526925D02*
X834099Y525788D01*
G01X838452Y519862D02*
X840157Y518157D01*
G01X838452Y530049D02*
Y519862D01*
G01X806692Y513166D02*
Y513114D01*
G01X807988Y511870D02*
X806692Y513166D01*
G01X807988Y508600D02*
Y511870D01*
G01X808488Y508100D02*
X807988Y508600D01*
G01X813288Y508100D02*
X808488D01*
G01X814388Y507000D02*
X813288Y508100D01*
G01X818388Y471400D02*
X817588Y470600D01*
G01X819988Y471400D02*
X818388D01*
G01X820788Y470600D02*
X819988Y471400D01*
G01X803981Y525788D02*
X805118Y526925D01*
G01X803981Y524712D02*
Y525788D01*
G01X804993Y523700D02*
X803981Y524712D01*
G01X804993Y522500D02*
Y523700D01*
G01X803981Y521488D02*
X804993Y522500D01*
G01X803981Y520412D02*
Y521488D01*
G01X805093Y519300D02*
X803981Y520412D01*
G01X805093Y516667D02*
Y519300D01*
G01X804918Y516492D02*
X805093Y516667D01*
G01X804918Y514800D02*
Y516492D01*
G01X806604Y513114D02*
X804918Y514800D01*
G01X806692Y513114D02*
X806604D01*
G01X808334Y519862D02*
X810039Y518157D01*
G01X808334Y529835D02*
Y519862D01*
G01X845145Y520554D02*
Y529835D01*
G01X846850Y518849D02*
X845145Y520554D01*
G01X846850Y518157D02*
Y518849D01*
G01X846361Y516976D02*
X846850Y518157D01*
G01X846361Y514587D02*
Y516976D01*
G01X842400Y505023D02*
X846361Y514587D01*
G01X815027Y519862D02*
X816732Y518157D01*
G01X815027Y531515D02*
Y519862D01*
G01X786922Y494461D02*
Y495851D01*
G01X786683Y489241D02*
Y490631D01*
G01X840792Y525788D02*
X841929Y526925D01*
G01X840792Y524712D02*
Y525788D01*
G01X841804Y523700D02*
X840792Y524712D01*
G01X841804Y522500D02*
Y523700D01*
G01X840792Y521488D02*
X841804Y522500D01*
G01X840792Y520412D02*
Y521488D01*
G01X841904Y519300D02*
X840792Y520412D01*
G01X841904Y516667D02*
Y519300D01*
G01X841729Y516492D02*
X841904Y516667D01*
G01X841729Y514800D02*
Y516492D01*
G01X843415Y513114D02*
X841729Y514800D01*
G01X843503Y513114D02*
X843415D01*
G01X801345Y511768D02*
X799999Y513114D01*
G01X801388Y511768D02*
X801345D01*
G01X801388Y508912D02*
Y511768D01*
G01X802900Y507400D02*
X801388Y508912D01*
G01X802900Y471863D02*
Y507400D01*
G01X803700Y471063D02*
X802900Y471863D01*
G01X805300Y471063D02*
X803700D01*
G01X806100Y471863D02*
X805300Y471063D01*
G01X806100Y486400D02*
Y471863D01*
G01X806800Y487100D02*
X806100Y486400D01*
G01X808400Y487100D02*
X806800D01*
G01X809300Y486200D02*
X808400Y487100D01*
G01X797288Y525788D02*
X798425Y526925D01*
G01X797288Y524712D02*
Y525788D01*
G01X798300Y523700D02*
X797288Y524712D01*
G01X798300Y522500D02*
Y523700D01*
G01X797288Y521488D02*
X798300Y522500D01*
G01X797288Y520412D02*
Y521488D01*
G01X798400Y519300D02*
X797288Y520412D01*
G01X798400Y516667D02*
Y519300D01*
G01X798225Y516492D02*
X798400Y516667D01*
G01X798225Y514800D02*
Y516492D01*
G01X799911Y513114D02*
X798225Y514800D01*
G01X799999Y513114D02*
X799911D01*
G01X817367Y526156D02*
X818311Y527100D01*
G01X817367Y524944D02*
Y526156D01*
G01X818211Y524100D02*
X817367Y524944D01*
G01X818211Y522400D02*
Y524100D01*
G01X817367Y521556D02*
X818211Y522400D01*
G01X817367Y520136D02*
Y521556D01*
G01X818511Y518992D02*
X817367Y520136D01*
G01X818511Y517399D02*
Y518992D01*
G01X817604Y516492D02*
X818511Y517399D01*
G01X817604Y513796D02*
Y516492D01*
G01X818286Y513114D02*
X817604Y513796D01*
G01X819378Y513114D02*
X818286D01*
G01X801641Y519862D02*
Y530049D01*
G01X803346Y518157D02*
X801641Y519862D01*
G01X801988Y516799D02*
X803346Y518157D01*
G01X801988Y514307D02*
Y516799D01*
G01X805400Y510895D02*
X801988Y514307D01*
G01X805400Y489842D02*
Y510895D01*
G01X806174Y489068D02*
X805400Y489842D01*
G01X807774Y489068D02*
X806174D01*
G01X808600Y489894D02*
X807774Y489068D01*
G01X808600Y505100D02*
Y489894D01*
G01X809400Y505900D02*
X808600Y505100D01*
G01X811000Y505900D02*
X809400D01*
G01X811800Y505100D02*
X811000Y505900D01*
G01X847500Y497300D02*
X850700Y500500D01*
G01X836810Y535100D02*
X831759Y530049D01*
G01X811711Y528299D02*
Y527401D01*
G01X811111Y528899D02*
X811711Y528299D01*
G01X810039Y528899D02*
X811111D01*
G01X847922D02*
X846850D01*
G01X848522Y528299D02*
X847922Y528899D01*
G01X794948Y530049D02*
X799999Y535100D01*
G01X835236Y528199D02*
Y526925D01*
G01X834536Y528899D02*
X835236Y528199D01*
G01X833464Y528899D02*
X834536D01*
G01X843503Y535100D02*
X838452Y530049D01*
G01X804418Y528899D02*
X803346D01*
G01X805118Y528199D02*
X804418Y528899D01*
G01X805118Y526925D02*
Y528199D01*
G01X808956Y530457D02*
X808334Y529835D01*
G01X808956Y531645D02*
Y530457D01*
G01X812011Y534700D02*
X808956Y531645D01*
G01X812999Y534700D02*
X812011D01*
G01X845767Y531645D02*
X848822Y534700D01*
G01X845767Y530457D02*
Y531645D01*
G01X845145Y529835D02*
X845767Y530457D01*
G01X818212Y534700D02*
X815027Y531515D01*
G01X819378Y534700D02*
X818212D01*
G01X841229Y528899D02*
X840157D01*
G01X841929Y528199D02*
X841229Y528899D01*
G01X841929Y526925D02*
Y528199D01*
G01X797725Y528899D02*
X796653D01*
G01X798425Y528199D02*
X797725Y528899D01*
G01X798425Y526925D02*
Y528199D01*
G01X817712Y528899D02*
X816732D01*
G01X818311Y528300D02*
X817712Y528899D01*
G01X818311Y527100D02*
Y528300D01*
G01X801641Y530049D02*
X806692Y535100D01*
G01X872592Y91892D02*
Y95008D01*
G01X871792Y91092D02*
X872592Y91892D01*
G01X871792Y89543D02*
Y91092D01*
G01X873621Y87714D02*
X871792Y89543D01*
G01X875010Y86325D02*
X873621Y87714D01*
G01X875010Y73312D02*
Y86325D01*
G01X875622Y72700D02*
X875010Y73312D01*
G01X875622Y71300D02*
Y72700D01*
G01X873822Y69500D02*
X875622Y71300D01*
G01X872822Y69500D02*
X873822D01*
G01X871522Y68200D02*
X872822Y69500D01*
G01X871522Y66946D02*
Y68200D01*
G01X870275Y65699D02*
X871522Y66946D01*
G01X870275Y94325D02*
X866592Y98008D01*
G01X870275Y92761D02*
Y94325D01*
G01X869347Y91833D02*
X870275Y92761D01*
G01X869347Y88701D02*
Y91833D01*
G01X872389Y85659D02*
X869347Y88701D01*
G01X872389Y84274D02*
Y85659D01*
G01X870714Y82599D02*
X872389Y84274D01*
G01X870714Y81476D02*
Y82599D01*
G01X872214Y79976D02*
X870714Y81476D01*
G01X872214Y78624D02*
Y79976D01*
G01X870714Y77124D02*
X872214Y78624D01*
G01X870714Y75901D02*
Y77124D01*
G01X872147Y74468D02*
X870714Y75901D01*
G01X872147Y73374D02*
Y74468D01*
G01X873621Y71900D02*
X872147Y73374D01*
G01X853543Y92757D02*
X850900Y95400D01*
G01X852422Y91636D02*
X853543Y92757D01*
G01X852422Y88700D02*
Y91636D01*
G01X855322Y85800D02*
X852422Y88700D01*
G01X855322Y83832D02*
Y85800D01*
G01X853789Y82299D02*
X855322Y83832D01*
G01X853789Y81100D02*
Y82299D01*
G01X855039Y79850D02*
X853789Y81100D01*
G01X855039Y78950D02*
Y79850D01*
G01X853689Y77600D02*
X855039Y78950D01*
G01X853689Y76301D02*
Y77600D01*
G01X855322Y74668D02*
X853689Y76301D01*
G01X855322Y72367D02*
Y74668D01*
G01X856189Y71500D02*
X855322Y72367D01*
G01X848792Y91992D02*
Y95801D01*
G01X851122Y86488D02*
X849896Y87714D01*
G01X851122Y73475D02*
Y86488D01*
G01X851897Y72700D02*
X851122Y73475D01*
G01X851897Y71076D02*
Y72700D01*
G01X850321Y69500D02*
X851897Y71076D01*
G01X849097Y69500D02*
X850321D01*
G01X876968Y93780D02*
Y92757D01*
G01X871692Y99056D02*
X876968Y93780D01*
G01X878747Y73467D02*
X880314Y71900D01*
G01X878747Y74668D02*
Y73467D01*
G01X877389Y76026D02*
X878747Y74668D01*
G01X877389Y77399D02*
Y76026D01*
G01X878589Y78599D02*
X877389Y77399D01*
G01X878589Y79725D02*
Y78599D01*
G01X877389Y80925D02*
X878589Y79725D01*
G01X877389Y82500D02*
Y80925D01*
G01X879189Y84300D02*
X877389Y82500D01*
G01X879189Y85358D02*
Y84300D01*
G01X875847Y88700D02*
X879189Y85358D01*
G01X875847Y91636D02*
Y88700D01*
G01X876968Y92757D02*
X875847Y91636D01*
G01X848722Y72588D02*
X849810Y71500D01*
G01X848722Y74468D02*
Y72588D01*
G01X848789Y79800D02*
Y78600D01*
G01X848722Y85901D02*
Y84032D01*
G01X855474Y93774D02*
X854392Y94856D01*
G01X855474Y92174D02*
Y93774D01*
G01X854292Y90992D02*
X855474Y92174D01*
G01X854292Y89611D02*
Y90992D01*
G01X856189Y87714D02*
X854292Y89611D01*
G01X857662Y86241D02*
X856189Y87714D01*
G01X857662Y73116D02*
Y86241D01*
G01X858278Y72500D02*
X857662Y73116D01*
G01X858278Y71156D02*
Y72500D01*
G01X856822Y69700D02*
X858278Y71156D01*
G01X855422Y69700D02*
X856822D01*
G01X853543Y67821D02*
X855422Y69700D01*
G01X853543Y65699D02*
Y67821D01*
G01X883661Y92757D02*
X885674Y94770D01*
G01X882733Y91829D02*
X883661Y92757D01*
G01X882733Y88701D02*
Y91829D01*
G01X885533Y85901D02*
X882733Y88701D01*
G01X885533Y84032D02*
Y85901D01*
G01X884150Y82649D02*
X885533Y84032D01*
G01X884150Y81250D02*
Y82649D01*
G01X885600Y79800D02*
X884150Y81250D01*
G01X885600Y78600D02*
Y79800D01*
G01X884100Y77100D02*
X885600Y78600D01*
G01X884100Y75901D02*
Y77100D01*
G01X885533Y74468D02*
X884100Y75901D01*
G01X885533Y72588D02*
Y74468D01*
G01X886621Y71500D02*
X885533Y72588D01*
G01X894473Y86241D02*
X893000Y87714D01*
G01X894473Y73116D02*
Y86241D01*
G01X895089Y72500D02*
X894473Y73116D01*
G01X895089Y71156D02*
Y72500D01*
G01X893633Y69700D02*
X895089Y71156D01*
G01X892233Y69700D02*
X893633D01*
G01X890354Y67821D02*
X892233Y69700D01*
G01X890354Y65699D02*
Y67821D01*
G01X892774Y92674D02*
Y100674D01*
G01X891074Y90974D02*
X892774Y92674D01*
G01X891074Y89640D02*
Y90974D01*
G01X893000Y87714D02*
X891074Y89640D01*
G01X887933Y86488D02*
X886707Y87714D01*
G01X887933Y73475D02*
Y86488D01*
G01X888708Y72700D02*
X887933Y73475D01*
G01X888708Y71076D02*
Y72700D01*
G01X887132Y69500D02*
X888708Y71076D01*
G01X885908Y69500D02*
X887132D01*
G01X883661Y67253D02*
X885908Y69500D01*
G01X883661Y65699D02*
Y67253D01*
G01X884674Y91074D02*
X888174Y94574D01*
G01X884674Y89575D02*
Y91074D01*
G01X886535Y87714D02*
X884674Y89575D01*
G01X886707Y87714D02*
X886535D01*
G01X878215Y66946D02*
X876968Y65699D01*
G01X878215Y68200D02*
Y66946D01*
G01X879515Y69500D02*
X878215Y68200D01*
G01X880515Y69500D02*
X879515D01*
G01X882315Y71300D02*
X880515Y69500D01*
G01X882315Y72700D02*
Y71300D01*
G01X881703Y73312D02*
X882315Y72700D01*
G01X881703Y86325D02*
Y73312D01*
G01X880314Y87714D02*
X881703Y86325D01*
G01X878410Y89618D02*
X880314Y87714D01*
G01X878410Y91218D02*
Y89618D01*
G01X879192Y92000D02*
X878410Y91218D01*
G01X879192Y96139D02*
Y92000D01*
G01X909633Y69500D02*
X910633D01*
G01X908333Y68200D02*
X909633Y69500D01*
G01X908333Y66946D02*
Y68200D01*
G01X907086Y65699D02*
X908333Y66946D01*
G01X908624Y91424D02*
X910824Y93624D01*
G01X908624Y89522D02*
Y91424D01*
G01X910432Y87714D02*
X908624Y89522D01*
G01X907086Y94286D02*
Y92757D01*
G01X908042Y95242D02*
X907086Y94286D01*
G01X908958Y73374D02*
X910432Y71900D01*
G01X908958Y74468D02*
Y73374D01*
G01X907525Y75901D02*
X908958Y74468D01*
G01X907525Y77124D02*
Y75901D01*
G01X909025Y78624D02*
X907525Y77124D01*
G01X909025Y79976D02*
Y78624D01*
G01X907525Y81476D02*
X909025Y79976D01*
G01X907525Y82599D02*
Y81476D01*
G01X909200Y84274D02*
X907525Y82599D01*
G01X909200Y85659D02*
Y84274D01*
G01X906158Y88701D02*
X909200Y85659D01*
G01X906158Y91829D02*
Y88701D01*
G01X907086Y92757D02*
X906158Y91829D01*
G01X890354Y101718D02*
Y92757D01*
G01X892133Y72367D02*
X893000Y71500D01*
G01X892133Y74668D02*
Y72367D01*
G01X890500Y76301D02*
X892133Y74668D01*
G01X890500Y77600D02*
Y76301D01*
G01X891850Y78950D02*
X890500Y77600D01*
G01X891850Y79850D02*
Y78950D01*
G01X890600Y81100D02*
X891850Y79850D01*
G01X890600Y82299D02*
Y81100D01*
G01X892133Y83832D02*
X890600Y82299D01*
G01X892133Y85800D02*
Y83832D01*
G01X889233Y88700D02*
X892133Y85800D01*
G01X889233Y91636D02*
Y88700D01*
G01X890354Y92757D02*
X889233Y91636D01*
G01X874853Y135900D02*
Y171653D01*
G01X874053Y135100D02*
X874853Y135900D01*
G01X872853Y135100D02*
X874053D01*
G01X872053Y135900D02*
X872853Y135100D01*
G01X872053Y149413D02*
Y135900D01*
G01X871132Y150334D02*
X872053Y149413D01*
G01X869932Y150334D02*
X871132D01*
G01X869192Y149594D02*
X869932Y150334D01*
G01X869192Y98408D02*
Y149594D01*
G01X872592Y95008D02*
X869192Y98408D01*
G01X866592Y155610D02*
Y157050D01*
G01X867152Y155050D02*
X866592Y155610D01*
G01X872340Y155050D02*
X867152D01*
G01X872900Y154490D02*
X872340Y155050D01*
G01X872900Y153050D02*
Y154490D01*
G01X872340Y152490D02*
X872900Y153050D01*
G01X867152Y152490D02*
X872340D01*
G01X866592Y151930D02*
X867152Y152490D01*
G01X866592Y98008D02*
Y151930D01*
G01X850200Y124045D02*
Y171336D01*
G01X850760Y123485D02*
X850200Y124045D01*
G01X851740Y123485D02*
X850760D01*
G01X852300Y122925D02*
X851740Y123485D01*
G01X852300Y121485D02*
Y122925D01*
G01X851740Y120925D02*
X852300Y121485D01*
G01X850760Y120925D02*
X851740D01*
G01X850200Y120365D02*
X850760Y120925D01*
G01X850200Y118925D02*
Y120365D01*
G01X850760Y118365D02*
X850200Y118925D01*
G01X851740Y118365D02*
X850760D01*
G01X852300Y117805D02*
X851740Y118365D01*
G01X852300Y116365D02*
Y117805D01*
G01X851740Y115805D02*
X852300Y116365D01*
G01X850760Y115805D02*
X851740D01*
G01X850200Y115245D02*
X850760Y115805D01*
G01X850200Y113805D02*
Y115245D01*
G01X850760Y113245D02*
X850200Y113805D01*
G01X851740Y113245D02*
X850760D01*
G01X852300Y112685D02*
X851740Y113245D01*
G01X852300Y111245D02*
Y112685D01*
G01X851740Y110685D02*
X852300Y111245D01*
G01X850760Y110685D02*
X851740D01*
G01X850200Y110125D02*
X850760Y110685D01*
G01X850200Y108685D02*
Y110125D01*
G01X850760Y108125D02*
X850200Y108685D01*
G01X851740Y108125D02*
X850760D01*
G01X852300Y107565D02*
X851740Y108125D01*
G01X852300Y106125D02*
Y107565D01*
G01X851740Y105565D02*
X852300Y106125D01*
G01X850760Y105565D02*
X851740D01*
G01X850200Y105005D02*
X850760Y105565D01*
G01X850200Y103565D02*
Y105005D01*
G01X850760Y103005D02*
X850200Y103565D01*
G01X851740Y103005D02*
X850760D01*
G01X852300Y102445D02*
X851740Y103005D01*
G01X852300Y101005D02*
Y102445D01*
G01X851740Y100445D02*
X852300Y101005D01*
G01X850760Y100445D02*
X851740D01*
G01X850200Y99885D02*
X850760Y100445D01*
G01X850200Y97800D02*
Y99885D01*
G01X850900Y97100D02*
X850200Y97800D01*
G01X850900Y95400D02*
Y97100D01*
G01X871692Y132339D02*
Y99056D01*
G01X872553Y133200D02*
X871692Y132339D01*
G01X873753Y133200D02*
X872553D01*
G01X874553Y132400D02*
X873753Y133200D01*
G01X874553Y112600D02*
Y132400D01*
G01X875353Y111800D02*
X874553Y112600D01*
G01X876553Y111800D02*
X875353D01*
G01X877353Y112600D02*
X876553Y111800D01*
G01X877353Y169253D02*
Y112600D01*
G01X852992Y129773D02*
Y168292D01*
G01X854392Y128373D02*
X852992Y129773D01*
G01X854392Y94856D02*
Y128373D01*
G01X885474Y130037D02*
Y169123D01*
G01X884864Y129427D02*
X885474Y130037D01*
G01X884260Y129427D02*
X884864D01*
G01X883700Y128867D02*
X884260Y129427D01*
G01X883700Y127377D02*
Y128867D01*
G01X884260Y126817D02*
X883700Y127377D01*
G01X884864Y126817D02*
X884260D01*
G01X885474Y126207D02*
X884864Y126817D01*
G01X885474Y124817D02*
Y126207D01*
G01X884864Y124207D02*
X885474Y124817D01*
G01X883760Y124207D02*
X884864D01*
G01X883150Y123597D02*
X883760Y124207D01*
G01X883150Y122207D02*
Y123597D01*
G01X883760Y121597D02*
X883150Y122207D01*
G01X884864Y121597D02*
X883760D01*
G01X885474Y120987D02*
X884864Y121597D01*
G01X885474Y119597D02*
Y120987D01*
G01X884864Y118987D02*
X885474Y119597D01*
G01X883760Y118987D02*
X884864D01*
G01X883150Y118377D02*
X883760Y118987D01*
G01X883150Y116987D02*
Y118377D01*
G01X883760Y116377D02*
X883150Y116987D01*
G01X884864Y116377D02*
X883760D01*
G01X885474Y115767D02*
X884864Y116377D01*
G01X885474Y111474D02*
Y115767D01*
G01X884674Y110674D02*
X885474Y111474D01*
G01X884674Y105974D02*
Y110674D01*
G01X885674Y104974D02*
X884674Y105974D01*
G01X885674Y100744D02*
Y104974D01*
G01X884692Y99762D02*
X885674Y100744D01*
G01X884692Y97544D02*
Y99762D01*
G01X885674Y96562D02*
X884692Y97544D01*
G01X885674Y94770D02*
Y96562D01*
G01X892992Y145353D02*
Y162758D01*
G01X896174Y142171D02*
X892992Y145353D01*
G01X896174Y115274D02*
Y142171D01*
G01X894924Y114024D02*
X896174Y115274D01*
G01X894924Y102824D02*
Y114024D01*
G01X892774Y100674D02*
X894924Y102824D01*
G01X887992Y123481D02*
Y168105D01*
G01X889292Y122181D02*
X887992Y123481D01*
G01X889292Y120956D02*
Y122181D01*
G01X887992Y119656D02*
X889292Y120956D01*
G01X887992Y118731D02*
Y119656D01*
G01X888792Y117931D02*
X887992Y118731D01*
G01X889192Y117931D02*
X888792D01*
G01X889900Y117223D02*
X889192Y117931D01*
G01X889900Y115239D02*
Y117223D01*
G01X889392Y114731D02*
X889900Y115239D01*
G01X888792Y114731D02*
X889392D01*
G01X887992Y113931D02*
X888792Y114731D01*
G01X887992Y111656D02*
Y113931D01*
G01X888574Y111074D02*
X887992Y111656D01*
G01X888574Y106574D02*
Y111074D01*
G01X888174Y106174D02*
X888574Y106574D01*
G01X888174Y94574D02*
Y106174D01*
G01X881053Y98000D02*
X879192Y96139D01*
G01X881053Y106440D02*
Y98000D01*
G01X880493Y107000D02*
X881053Y106440D01*
G01X878813Y107000D02*
X880493D01*
G01X878253Y106440D02*
X878813Y107000D01*
G01X878253Y99853D02*
Y106440D01*
G01X877239Y98839D02*
X878253Y99853D01*
G01X875053Y98839D02*
X877239D01*
G01X874253Y99639D02*
X875053Y98839D01*
G01X874253Y108800D02*
Y99639D01*
G01X875053Y109600D02*
X874253Y108800D01*
G01X879053Y109600D02*
X875053D01*
G01X879853Y110400D02*
X879053Y109600D01*
G01X879853Y145952D02*
Y110400D01*
G01X880463Y146562D02*
X879853Y145952D01*
G01X881590Y146562D02*
X880463D01*
G01X882200Y147172D02*
X881590Y146562D01*
G01X882200Y148562D02*
Y147172D01*
G01X881590Y149172D02*
X882200Y148562D01*
G01X880463Y149172D02*
X881590D01*
G01X879853Y149782D02*
X880463Y149172D01*
G01X879853Y151172D02*
Y149782D01*
G01X880463Y151782D02*
X879853Y151172D01*
G01X881590Y151782D02*
X880463D01*
G01X882200Y152392D02*
X881590Y151782D01*
G01X882200Y153782D02*
Y152392D01*
G01X881590Y154392D02*
X882200Y153782D01*
G01X880463Y154392D02*
X881590D01*
G01X879853Y155002D02*
X880463Y154392D01*
G01X879853Y156392D02*
Y155002D01*
G01X910174Y147440D02*
X910734Y148000D01*
G01X910992Y136408D02*
X910174Y137226D01*
G01X908042Y102406D02*
Y95242D01*
G01X909074Y103438D02*
X908042Y102406D01*
G01X909074Y105174D02*
Y103438D01*
G01X908274Y105974D02*
X909074Y105174D01*
G01X908274Y110774D02*
Y105974D01*
G01X909174Y111674D02*
X908274Y110774D01*
G01X909174Y113156D02*
Y111674D01*
G01X908492Y113838D02*
X909174Y113156D01*
G01X908492Y135308D02*
Y113838D01*
G01X907674Y136126D02*
X908492Y135308D01*
G01X907674Y153140D02*
Y136126D01*
G01X908284Y153750D02*
X907674Y153140D01*
G01X912140Y153750D02*
X908284D01*
G01X892174Y103538D02*
X890354Y101718D01*
G01X892174Y105074D02*
Y103538D01*
G01X891074Y106174D02*
X892174Y105074D01*
G01X891074Y110474D02*
Y106174D01*
G01X892450Y111850D02*
X891074Y110474D01*
G01X892450Y115050D02*
Y111850D01*
G01X893674Y116274D02*
X892450Y115050D01*
G01X893674Y122917D02*
Y116274D01*
G01X892874Y123717D02*
X893674Y122917D01*
G01X891292Y123717D02*
X892874D01*
G01X890492Y124517D02*
X891292Y123717D01*
G01X890492Y126117D02*
Y124517D01*
G01X891292Y126917D02*
X890492Y126117D01*
G01X892874Y126917D02*
X891292D01*
G01X893674Y127717D02*
X892874Y126917D01*
G01X893674Y129317D02*
Y127717D01*
G01X892874Y130117D02*
X893674Y129317D01*
G01X891292Y130117D02*
X892874D01*
G01X890492Y130917D02*
X891292Y130117D01*
G01X890492Y132517D02*
Y130917D01*
G01X891292Y133317D02*
X890492Y132517D01*
G01X892874Y133317D02*
X891292D01*
G01X893674Y134117D02*
X892874Y133317D01*
G01X893674Y135717D02*
Y134117D01*
G01X892874Y136517D02*
X893674Y135717D01*
G01X891292Y136517D02*
X892874D01*
G01X890492Y137317D02*
X891292Y136517D01*
G01X890492Y138917D02*
Y137317D01*
G01X891292Y139717D02*
X890492Y138917D01*
G01X891940Y139717D02*
X891292D01*
G01X892500Y140277D02*
X891940Y139717D01*
G01X892500Y142309D02*
Y140277D01*
G01X890492Y144317D02*
X892500Y142309D01*
G01X890492Y164293D02*
Y144317D01*
G01X899400Y191000D02*
X912757Y204357D01*
G01X894200Y191000D02*
X899400D01*
G01X874853Y171653D02*
X894200Y191000D01*
G01X902400Y201600D02*
X913180Y212380D01*
G01X900000Y201600D02*
X902400D01*
G01X897041Y198641D02*
X900000Y201600D01*
G01X897041Y197849D02*
Y198641D01*
G01X898199Y196691D02*
X897041Y197849D01*
G01X898199Y195899D02*
Y196691D01*
G01X897180Y194880D02*
X898199Y195899D01*
G01X896388Y194880D02*
X897180D01*
G01X895230Y196038D02*
X896388Y194880D01*
G01X894438Y196038D02*
X895230D01*
G01X866592Y168192D02*
X894438Y196038D01*
G01X866592Y165850D02*
Y168192D01*
G01X867152Y165290D02*
X866592Y165850D01*
G01X872340Y165290D02*
X867152D01*
G01X872900Y164730D02*
X872340Y165290D01*
G01X872900Y163290D02*
Y164730D01*
G01X872340Y162730D02*
X872900Y163290D01*
G01X867152Y162730D02*
X872340D01*
G01X866592Y162170D02*
X867152Y162730D01*
G01X866592Y160730D02*
Y162170D01*
G01X867152Y160170D02*
X866592Y160730D01*
G01X872340Y160170D02*
X867152D01*
G01X872900Y159610D02*
X872340Y160170D01*
G01X872900Y158170D02*
Y159610D01*
G01X872340Y157610D02*
X872900Y158170D01*
G01X867152Y157610D02*
X872340D01*
G01X866592Y157050D02*
X867152Y157610D01*
G01X850200Y171336D02*
X906716Y227852D01*
G01X894700Y186600D02*
X877353Y169253D01*
G01X897900Y186600D02*
X894700D01*
G01X917056Y205756D02*
X897900Y186600D01*
G01X852992Y168292D02*
X906700Y222000D01*
G01X898152Y177800D02*
X920331Y199979D01*
G01X894151Y177800D02*
X898152D01*
G01X885474Y169123D02*
X894151Y177800D01*
G01X899273Y168100D02*
X927974Y196801D01*
G01X898334Y168100D02*
X899273D01*
G01X892992Y162758D02*
X898334Y168100D01*
G01X898259Y174300D02*
X921363Y197404D01*
G01X894187Y174300D02*
X898259D01*
G01X887992Y168105D02*
X894187Y174300D01*
G01X880463Y157002D02*
X879853Y156392D01*
G01X881590Y157002D02*
X880463D01*
G01X882200Y157612D02*
X881590Y157002D01*
G01X882200Y159002D02*
Y157612D01*
G01X881590Y159612D02*
X882200Y159002D01*
G01X880463Y159612D02*
X881590D01*
G01X879853Y160222D02*
X880463Y159612D01*
G01X879853Y161612D02*
Y160222D01*
G01X880463Y162222D02*
X879853Y161612D01*
G01X881590Y162222D02*
X880463D01*
G01X882200Y162832D02*
X881590Y162222D01*
G01X882200Y164222D02*
Y162832D01*
G01X881590Y164832D02*
X882200Y164222D01*
G01X880463Y164832D02*
X881590D01*
G01X879853Y165442D02*
X880463Y164832D01*
G01X879853Y168053D02*
Y165442D01*
G01X894400Y182600D02*
X879853Y168053D01*
G01X897507Y182600D02*
X894400D01*
G01X918220Y203313D02*
X897507Y182600D01*
G01X909810Y156912D02*
X912140D01*
G01X909200Y157522D02*
X909810Y156912D01*
G01X909200Y158912D02*
Y157522D01*
G01X909810Y159522D02*
X909200Y158912D01*
G01X915540Y159522D02*
X909810D01*
G01X896899Y170700D02*
X890492Y164293D01*
G01X898266Y170700D02*
X896899D01*
G01X924669Y197103D02*
X898266Y170700D01*
G01X897795Y260363D02*
X908000D01*
G01X906170Y240159D02*
X907500D01*
G01X906716Y227852D02*
X910448D01*
G01X906351Y230402D02*
X910506D01*
G01X907500Y262863D02*
X896759D01*
G01X908000Y257863D02*
X898831D01*
G01X910653Y232952D02*
X904903D01*
G01X907702Y225302D02*
X909817D01*
G01X906700Y224300D02*
X907702Y225302D01*
G01X906700Y222000D02*
Y224300D01*
G01X903062Y247659D02*
X908000D01*
G01X907500Y265363D02*
X895723D01*
G01X908000Y242659D02*
X905134D01*
G01X908000Y245159D02*
X904098D01*
G01X908841Y332336D02*
X903924D01*
G01X904257Y337336D02*
X851500Y390093D01*
G01X908914Y337336D02*
X904257D01*
G01X904090Y334836D02*
X849500Y389426D01*
G01X908899Y334836D02*
X904090D01*
G01X908732Y330247D02*
X903347D01*
G01X870180Y398866D02*
Y406198D01*
G01X908665Y360381D02*
X870180Y398866D01*
G01X912872Y360381D02*
X908665D01*
G01X859600Y392992D02*
Y399300D01*
G01X905032Y347560D02*
X859600Y392992D01*
G01X908942Y347560D02*
X905032D01*
G01X906008Y382405D02*
X882800Y405613D01*
G01X906356Y392878D02*
X890482Y408752D01*
G01X865285Y395306D02*
Y401682D01*
G01X906591Y354000D02*
X865285Y395306D01*
G01X909088Y354000D02*
X906591D01*
G01X868295Y398085D02*
Y404505D01*
G01X908549Y357831D02*
X868295Y398085D01*
G01X912844Y357831D02*
X908549D01*
G01X873950Y400428D02*
Y409524D01*
G01X908751Y365627D02*
X873950Y400428D01*
G01X912107Y365627D02*
X908751D01*
G01X851500Y390093D02*
Y395999D01*
G01X849500Y389426D02*
Y395300D01*
G01X861500Y393758D02*
Y400100D01*
G01X905642Y349616D02*
X861500Y393758D01*
G01X908942Y349616D02*
X905642D01*
G01X907593Y384308D02*
X885346Y406555D01*
G01X907712Y384308D02*
X907593D01*
G01X904586Y391041D02*
X887962Y407665D01*
G01X863400Y394524D02*
Y400900D01*
G01X906464Y351460D02*
X863400Y394524D01*
G01X909030Y351460D02*
X906464D01*
G01X872065Y399647D02*
Y407873D01*
G01X908636Y363076D02*
X872065Y399647D01*
G01X912107Y363076D02*
X908636D01*
G01X896000Y457205D02*
Y487900D01*
G01X895390Y456595D02*
X896000Y457205D01*
G01X893210Y456595D02*
X895390D01*
G01X892600Y455985D02*
X893210Y456595D01*
G01X892600Y454005D02*
Y455985D01*
G01X893210Y453395D02*
X892600Y454005D01*
G01X895390Y453395D02*
X893210D01*
G01X896000Y452785D02*
X895390Y453395D01*
G01X896000Y450805D02*
Y452785D01*
G01X895390Y450195D02*
X896000Y450805D01*
G01X893210Y450195D02*
X895390D01*
G01X892600Y449585D02*
X893210Y450195D01*
G01X892600Y447605D02*
Y449585D01*
G01X893210Y446995D02*
X892600Y447605D01*
G01X895390Y446995D02*
X893210D01*
G01X896000Y446385D02*
X895390Y446995D01*
G01X896000Y444405D02*
Y446385D01*
G01X895390Y443795D02*
X896000Y444405D01*
G01X893910Y443795D02*
X895390D01*
G01X893300Y443185D02*
X893910Y443795D01*
G01X893300Y441205D02*
Y443185D01*
G01X893910Y440595D02*
X893300Y441205D01*
G01X895390Y440595D02*
X893910D01*
G01X896000Y439985D02*
X895390Y440595D01*
G01X896000Y436924D02*
Y439985D01*
G01X905106Y427818D02*
X896000Y436924D01*
G01X905106Y414584D02*
Y427818D01*
G01X911268Y408422D02*
X905106Y414584D01*
G01X864100Y446700D02*
Y499299D01*
G01X864900Y445900D02*
X864100Y446700D01*
G01X866400Y445900D02*
X864900D01*
G01X867200Y446700D02*
X866400Y445900D01*
G01X867200Y455300D02*
Y446700D01*
G01X868000Y456100D02*
X867200Y455300D01*
G01X869600Y456100D02*
X868000D01*
G01X870400Y455300D02*
X869600Y456100D01*
G01X870400Y437800D02*
Y455300D01*
G01X869200Y436600D02*
X870400Y437800D01*
G01X869200Y435300D02*
Y436600D01*
G01X870400Y434100D02*
X869200Y435300D01*
G01X870400Y429136D02*
Y434100D01*
G01X882800Y416736D02*
X870400Y429136D01*
G01X882800Y405613D02*
Y416736D01*
G01X880500Y429901D02*
Y468017D01*
G01X882154Y428247D02*
X880500Y429901D01*
G01X883016Y428247D02*
X882154D01*
G01X884102Y429334D02*
X883016Y428247D01*
G01X884964Y429334D02*
X884102D01*
G01X886365Y427933D02*
X884964Y429334D01*
G01X886365Y427071D02*
Y427933D01*
G01X885279Y425984D02*
X886365Y427071D01*
G01X885279Y425122D02*
Y425984D01*
G01X886680Y423721D02*
X885279Y425122D01*
G01X887542Y423721D02*
X886680D01*
G01X888628Y424808D02*
X887542Y423721D01*
G01X889490Y424808D02*
X888628D01*
G01X890891Y423407D02*
X889490Y424808D01*
G01X890891Y422545D02*
Y423407D01*
G01X889805Y421458D02*
X890891Y422545D01*
G01X889805Y420596D02*
Y421458D01*
G01X890482Y419919D02*
X889805Y420596D01*
G01X890482Y408752D02*
Y419919D01*
G01X909800Y437745D02*
Y466700D01*
G01X916000Y431545D02*
X909800Y437745D01*
G01X893300Y461000D02*
Y488042D01*
G01X890539Y458239D02*
X893300Y461000D01*
G01X890539Y438770D02*
Y458239D01*
G01X902550Y426759D02*
X890539Y438770D01*
G01X902550Y413533D02*
Y426759D01*
G01X909416Y406667D02*
X902550Y413533D01*
G01X850100Y433374D02*
Y485646D01*
G01X873950Y409524D02*
X850100Y433374D01*
G01X900050Y412424D02*
X907161Y405313D01*
G01X900050Y425723D02*
Y412424D01*
G01X888449Y437324D02*
X900050Y425723D01*
G01X888449Y459550D02*
Y437324D01*
G01X891200Y462301D02*
X888449Y459550D01*
G01X891200Y480739D02*
Y462301D01*
G01X876700Y463200D02*
X872300Y467600D01*
G01X876700Y459737D02*
Y463200D01*
G01X876140Y459177D02*
X876700Y459737D01*
G01X873060Y459177D02*
X876140D01*
G01X872500Y458617D02*
X873060Y459177D01*
G01X872500Y457177D02*
Y458617D01*
G01X873060Y456617D02*
X872500Y457177D01*
G01X876140Y456617D02*
X873060D01*
G01X876700Y456057D02*
X876140Y456617D01*
G01X876700Y454617D02*
Y456057D01*
G01X876140Y454057D02*
X876700Y454617D01*
G01X873060Y454057D02*
X876140D01*
G01X872500Y453497D02*
X873060Y454057D01*
G01X872500Y452057D02*
Y453497D01*
G01X873060Y451497D02*
X872500Y452057D01*
G01X876140Y451497D02*
X873060D01*
G01X876700Y450937D02*
X876140Y451497D01*
G01X876700Y449497D02*
Y450937D01*
G01X876140Y448937D02*
X876700Y449497D01*
G01X873060Y448937D02*
X876140D01*
G01X872500Y448377D02*
X873060Y448937D01*
G01X872500Y446937D02*
Y448377D01*
G01X873060Y446377D02*
X872500Y446937D01*
G01X876140Y446377D02*
X873060D01*
G01X876700Y445817D02*
X876140Y446377D01*
G01X876700Y444377D02*
Y445817D01*
G01X876140Y443817D02*
X876700Y444377D01*
G01X873060Y443817D02*
X876140D01*
G01X872500Y443257D02*
X873060Y443817D01*
G01X872500Y441817D02*
Y443257D01*
G01X873060Y441257D02*
X872500Y441817D01*
G01X876140Y441257D02*
X873060D01*
G01X876700Y440697D02*
X876140Y441257D01*
G01X876700Y439257D02*
Y440697D01*
G01X876140Y438697D02*
X876700Y439257D01*
G01X873060Y438697D02*
X876140D01*
G01X872500Y438137D02*
X873060Y438697D01*
G01X872500Y436697D02*
Y438137D01*
G01X873060Y436137D02*
X872500Y436697D01*
G01X876140Y436137D02*
X873060D01*
G01X876700Y435577D02*
X876140Y436137D01*
G01X876700Y426437D02*
Y435577D01*
G01X885346Y417791D02*
X876700Y426437D01*
G01X885346Y406555D02*
Y417791D01*
G01X878600Y464000D02*
X874200Y468400D01*
G01X878600Y428237D02*
Y464000D01*
G01X887962Y418875D02*
X878600Y428237D01*
G01X887962Y407665D02*
Y418875D01*
G01X888200Y462500D02*
Y477800D01*
G01X886449Y460749D02*
X888200Y462500D01*
G01X886449Y435788D02*
Y460749D01*
G01X897550Y424687D02*
X886449Y435788D01*
G01X897550Y411317D02*
Y424687D01*
G01X905358Y403509D02*
X897550Y411317D01*
G01X849896Y507996D02*
Y513114D01*
G01X848800Y501832D02*
Y503272D01*
G01X848422Y522801D02*
Y524199D01*
G01X848622Y517500D02*
Y519399D01*
G01X849896Y513114D02*
X849808D01*
G01X890989Y526156D02*
X891933Y527100D01*
G01X890989Y524944D02*
Y526156D01*
G01X891833Y524100D02*
X890989Y524944D01*
G01X891833Y522400D02*
Y524100D01*
G01X890989Y521556D02*
X891833Y522400D01*
G01X890989Y520136D02*
Y521556D01*
G01X892133Y518992D02*
X890989Y520136D01*
G01X892133Y517399D02*
Y518992D01*
G01X891226Y516492D02*
X892133Y517399D01*
G01X891226Y514800D02*
Y516492D01*
G01X892912Y513114D02*
X891226Y514800D01*
G01X893000Y513114D02*
X892912D01*
G01X894974Y511140D02*
X893000Y513114D01*
G01X894974Y488926D02*
Y511140D01*
G01X896000Y487900D02*
X894974Y488926D01*
G01X868800Y516686D02*
X870275Y518161D01*
G01X868800Y514467D02*
Y516686D01*
G01X872200Y511067D02*
X868800Y514467D01*
G01X872200Y509200D02*
Y511067D01*
G01X873300Y508100D02*
X872200Y509200D01*
G01X873300Y506300D02*
Y508100D01*
G01X872600Y505600D02*
X873300Y506300D01*
G01X870401Y505600D02*
X872600D01*
G01X864100Y499299D02*
X870401Y505600D01*
G01X868570Y519866D02*
Y530049D01*
G01X870275Y518161D02*
X868570Y519866D01*
G01X877603Y525788D02*
X878740Y526925D01*
G01X877603Y524712D02*
Y525788D01*
G01X878615Y523700D02*
X877603Y524712D01*
G01X878615Y522500D02*
Y523700D01*
G01X877603Y521488D02*
X878615Y522500D01*
G01X877603Y520412D02*
Y521488D01*
G01X878715Y519300D02*
X877603Y520412D01*
G01X878715Y516667D02*
Y519300D01*
G01X878540Y516492D02*
X878715Y516667D01*
G01X878540Y514800D02*
Y516492D01*
G01X880226Y513114D02*
X878540Y514800D01*
G01X880314Y513114D02*
X880226D01*
G01X880314Y513166D02*
Y513114D01*
G01X881610Y511870D02*
X880314Y513166D01*
G01X881610Y505210D02*
Y511870D01*
G01X880500Y504100D02*
X881610Y505210D01*
G01X880500Y497297D02*
Y504100D01*
G01X879940Y496737D02*
X880500Y497297D01*
G01X876660Y496737D02*
X879940D01*
G01X876100Y496177D02*
X876660Y496737D01*
G01X876100Y494737D02*
Y496177D01*
G01X876660Y494177D02*
X876100Y494737D01*
G01X879940Y494177D02*
X876660D01*
G01X880500Y493617D02*
X879940Y494177D01*
G01X880500Y492177D02*
Y493617D01*
G01X879940Y491617D02*
X880500Y492177D01*
G01X876660Y491617D02*
X879940D01*
G01X876100Y491057D02*
X876660Y491617D01*
G01X876100Y489617D02*
Y491057D01*
G01X876660Y489057D02*
X876100Y489617D01*
G01X879940Y489057D02*
X876660D01*
G01X880500Y488497D02*
X879940Y489057D01*
G01X880500Y487057D02*
Y488497D01*
G01X879940Y486497D02*
X880500Y487057D01*
G01X876660Y486497D02*
X879940D01*
G01X876100Y485937D02*
X876660Y486497D01*
G01X876100Y484497D02*
Y485937D01*
G01X876660Y483937D02*
X876100Y484497D01*
G01X879940Y483937D02*
X876660D01*
G01X880500Y483377D02*
X879940Y483937D01*
G01X880500Y481937D02*
Y483377D01*
G01X879940Y481377D02*
X880500Y481937D01*
G01X876660Y481377D02*
X879940D01*
G01X876100Y480817D02*
X876660Y481377D01*
G01X876100Y479377D02*
Y480817D01*
G01X876660Y478817D02*
X876100Y479377D01*
G01X879940Y478817D02*
X876660D01*
G01X880500Y478257D02*
X879940Y478817D01*
G01X880500Y476817D02*
Y478257D01*
G01X879940Y476257D02*
X880500Y476817D01*
G01X876660Y476257D02*
X879940D01*
G01X876100Y475697D02*
X876660Y476257D01*
G01X876100Y474257D02*
Y475697D01*
G01X876660Y473697D02*
X876100Y474257D01*
G01X879940Y473697D02*
X876660D01*
G01X880500Y473137D02*
X879940Y473697D01*
G01X880500Y471697D02*
Y473137D01*
G01X879940Y471137D02*
X880500Y471697D01*
G01X876660Y471137D02*
X879940D01*
G01X876100Y470577D02*
X876660Y471137D01*
G01X876100Y469137D02*
Y470577D01*
G01X876660Y468577D02*
X876100Y469137D01*
G01X879940Y468577D02*
X876660D01*
G01X880500Y468017D02*
X879940Y468577D01*
G01X905381Y519862D02*
Y530049D01*
G01X907086Y518157D02*
X905381Y519862D01*
G01X906421Y517492D02*
X907086Y518157D01*
G01X906421Y513657D02*
Y517492D01*
G01X909321Y510757D02*
X906421Y513657D01*
G01X909321Y495120D02*
Y510757D01*
G01X907200Y492999D02*
X909321Y495120D01*
G01X907200Y487941D02*
Y492999D01*
G01X907760Y487381D02*
X907200Y487941D01*
G01X909300Y487381D02*
X907760D01*
G01X909800Y486881D02*
X909300Y487381D01*
G01X909800Y485481D02*
Y486881D01*
G01X909140Y484821D02*
X909800Y485481D01*
G01X907760Y484821D02*
X909140D01*
G01X907200Y484261D02*
X907760Y484821D01*
G01X907200Y482821D02*
Y484261D01*
G01X907760Y482261D02*
X907200Y482821D01*
G01X909300Y482261D02*
X907760D01*
G01X909800Y481761D02*
X909300Y482261D01*
G01X909800Y480361D02*
Y481761D01*
G01X909140Y479701D02*
X909800Y480361D01*
G01X908000Y479701D02*
X909140D01*
G01X907200Y478901D02*
X908000Y479701D01*
G01X907200Y469300D02*
Y478901D01*
G01X909800Y466700D02*
X907200Y469300D01*
G01X888649Y519862D02*
Y531515D01*
G01X890354Y518157D02*
X888649Y519862D01*
G01X889585Y517388D02*
X890354Y518157D01*
G01X889585Y513543D02*
Y517388D01*
G01X891900Y511228D02*
X889585Y513543D01*
G01X891900Y506600D02*
Y511228D01*
G01X890900Y505600D02*
X891900Y506600D01*
G01X890900Y490442D02*
Y505600D01*
G01X893300Y488042D02*
X890900Y490442D01*
G01X854178Y526156D02*
X855122Y527100D01*
G01X854178Y524944D02*
Y526156D01*
G01X855022Y524100D02*
X854178Y524944D01*
G01X855022Y522400D02*
Y524100D01*
G01X854178Y521556D02*
X855022Y522400D01*
G01X854178Y520136D02*
Y521556D01*
G01X855322Y518992D02*
X854178Y520136D01*
G01X855322Y517399D02*
Y518992D01*
G01X854415Y516492D02*
X855322Y517399D01*
G01X854415Y514800D02*
Y516492D01*
G01X856101Y513114D02*
X854415Y514800D01*
G01X856189Y513114D02*
X856101D01*
G01X857700Y511603D02*
X856189Y513114D01*
G01X857700Y508000D02*
Y511603D01*
G01X853300Y503600D02*
X857700Y508000D01*
G01X853300Y497900D02*
Y503600D01*
G01X852500Y497100D02*
X853300Y497900D01*
G01X850900Y497100D02*
X852500D01*
G01X850100Y496300D02*
X850900Y497100D01*
G01X850100Y494446D02*
Y496300D01*
G01X850660Y493886D02*
X850100Y494446D01*
G01X854040Y493886D02*
X850660D01*
G01X854600Y493326D02*
X854040Y493886D01*
G01X854600Y491886D02*
Y493326D01*
G01X854040Y491326D02*
X854600Y491886D01*
G01X850660Y491326D02*
X854040D01*
G01X850100Y490766D02*
X850660Y491326D01*
G01X850100Y489326D02*
Y490766D01*
G01X850660Y488766D02*
X850100Y489326D01*
G01X854040Y488766D02*
X850660D01*
G01X854600Y488206D02*
X854040Y488766D01*
G01X854600Y486766D02*
Y488206D01*
G01X854040Y486206D02*
X854600Y486766D01*
G01X850660Y486206D02*
X854040D01*
G01X850100Y485646D02*
X850660Y486206D01*
G01X890590Y481349D02*
X891200Y480739D01*
G01X888510Y481349D02*
X890590D01*
G01X887900Y481959D02*
X888510Y481349D01*
G01X887900Y483939D02*
Y481959D01*
G01X888510Y484549D02*
X887900Y483939D01*
G01X890590Y484549D02*
X888510D01*
G01X891200Y485159D02*
X890590Y484549D01*
G01X891200Y486200D02*
Y485159D01*
G01X888300Y489100D02*
X891200Y486200D01*
G01X888300Y494100D02*
Y489100D01*
G01X887200Y495200D02*
X888300Y494100D01*
G01X887200Y501596D02*
Y495200D01*
G01X888400Y502796D02*
X887200Y501596D01*
G01X888400Y504796D02*
Y502796D01*
G01X887200Y505996D02*
X888400Y504796D01*
G01X887200Y507996D02*
Y505996D01*
G01X888400Y509196D02*
X887200Y507996D01*
G01X888400Y512301D02*
Y509196D01*
G01X887587Y513114D02*
X888400Y512301D01*
G01X886707Y513114D02*
X887587D01*
G01X886619D02*
X886707D01*
G01X884933Y514800D02*
X886619Y513114D01*
G01X884933Y517000D02*
Y514800D01*
G01X885433Y517500D02*
X884933Y517000D01*
G01X885433Y519399D02*
Y517500D01*
G01X884296Y520536D02*
X885433Y519399D01*
G01X884296Y521864D02*
Y520536D01*
G01X885233Y522801D02*
X884296Y521864D01*
G01X885233Y524199D02*
Y522801D01*
G01X884296Y525136D02*
X885233Y524199D01*
G01X884296Y526364D02*
Y525136D01*
G01X885333Y527401D02*
X884296Y526364D01*
G01X907721Y525788D02*
X908858Y526925D01*
G01X907721Y524712D02*
Y525788D01*
G01X908733Y523700D02*
X907721Y524712D01*
G01X908733Y522500D02*
Y523700D01*
G01X907721Y521488D02*
X908733Y522500D01*
G01X907721Y520412D02*
Y521488D01*
G01X908833Y519300D02*
X907721Y520412D01*
G01X908833Y516667D02*
Y519300D01*
G01X908658Y516492D02*
X908833Y516667D01*
G01X908658Y514800D02*
Y516492D01*
G01X910344Y513114D02*
X908658Y514800D01*
G01X870910Y525788D02*
X872047Y526925D01*
G01X870910Y524712D02*
Y525788D01*
G01X871922Y523700D02*
X870910Y524712D01*
G01X871922Y522500D02*
Y523700D01*
G01X870910Y521488D02*
X871922Y522500D01*
G01X870910Y520412D02*
Y521488D01*
G01X872022Y519300D02*
X870910Y520412D01*
G01X872022Y516667D02*
Y519300D01*
G01X871847Y516492D02*
X872022Y516667D01*
G01X871847Y514800D02*
Y516492D01*
G01X873533Y513114D02*
X871847Y514800D01*
G01X873621Y513114D02*
X873533D01*
G01X874967Y511768D02*
X873621Y513114D01*
G01X875010Y511768D02*
X874967D01*
G01X875010Y509390D02*
Y511768D01*
G01X876200Y508200D02*
X875010Y509390D01*
G01X876200Y506500D02*
Y508200D01*
G01X874350Y504650D02*
X876200Y506500D01*
G01X874350Y502750D02*
Y504650D01*
G01X873500Y501900D02*
X874350Y502750D01*
G01X870300Y501900D02*
X873500D01*
G01X866600Y498200D02*
X870300Y501900D01*
G01X866600Y473500D02*
Y498200D01*
G01X867100Y473000D02*
X866600Y473500D01*
G01X871800Y473000D02*
X867100D01*
G01X872300Y472500D02*
X871800Y473000D01*
G01X872300Y467600D02*
Y472500D01*
G01X875610Y516799D02*
X876968Y518157D01*
G01X875610Y514307D02*
Y516799D01*
G01X879010Y510907D02*
X875610Y514307D01*
G01X879010Y506610D02*
Y510907D01*
G01X878000Y505600D02*
X879010Y506610D01*
G01X878000Y500400D02*
Y505600D01*
G01X877300Y499700D02*
X878000Y500400D01*
G01X871400Y499700D02*
X877300D01*
G01X869200Y497500D02*
X871400Y499700D01*
G01X869200Y496206D02*
Y497500D01*
G01X869760Y495646D02*
X869200Y496206D01*
G01X872940Y495646D02*
X869760D01*
G01X873500Y495086D02*
X872940Y495646D01*
G01X873500Y493646D02*
Y495086D01*
G01X872940Y493086D02*
X873500Y493646D01*
G01X869760Y493086D02*
X872940D01*
G01X869200Y492526D02*
X869760Y493086D01*
G01X869200Y491086D02*
Y492526D01*
G01X869760Y490526D02*
X869200Y491086D01*
G01X872940Y490526D02*
X869760D01*
G01X873500Y489966D02*
X872940Y490526D01*
G01X873500Y488526D02*
Y489966D01*
G01X872940Y487966D02*
X873500Y488526D01*
G01X869760Y487966D02*
X872940D01*
G01X869200Y487406D02*
X869760Y487966D01*
G01X869200Y485966D02*
Y487406D01*
G01X869760Y485406D02*
X869200Y485966D01*
G01X872940Y485406D02*
X869760D01*
G01X873500Y484846D02*
X872940Y485406D01*
G01X873500Y483406D02*
Y484846D01*
G01X872940Y482846D02*
X873500Y483406D01*
G01X869760Y482846D02*
X872940D01*
G01X869200Y482286D02*
X869760Y482846D01*
G01X869200Y480846D02*
Y482286D01*
G01X869760Y480286D02*
X869200Y480846D01*
G01X872940Y480286D02*
X869760D01*
G01X873500Y479726D02*
X872940Y480286D01*
G01X873500Y478286D02*
Y479726D01*
G01X872940Y477726D02*
X873500Y478286D01*
G01X869760Y477726D02*
X872940D01*
G01X869200Y477166D02*
X869760Y477726D01*
G01X869200Y475700D02*
Y477166D01*
G01X870000Y474900D02*
X869200Y475700D01*
G01X873700Y474900D02*
X870000D01*
G01X874200Y474400D02*
X873700Y474900D01*
G01X874200Y468400D02*
Y474400D01*
G01X875263Y519862D02*
Y530049D01*
G01X876968Y518157D02*
X875263Y519862D01*
G01X851838D02*
Y531515D01*
G01X853543Y518157D02*
X851838Y519862D01*
G01X853341Y518157D02*
X853543D01*
G01X852110Y516926D02*
X853341Y518157D01*
G01X852110Y513990D02*
Y516926D01*
G01X855200Y510900D02*
X852110Y513990D01*
G01X855200Y508700D02*
Y510900D01*
G01X850700Y504200D02*
X855200Y508700D01*
G01X850700Y500500D02*
Y504200D01*
G01X883001Y518157D02*
X883661D01*
G01X882200Y517356D02*
X883001Y518157D01*
G01X882200Y514228D02*
Y517356D01*
G01X885500Y510928D02*
X882200Y514228D01*
G01X885500Y502801D02*
Y510928D01*
G01X884774Y502075D02*
X885500Y502801D01*
G01X884774Y489626D02*
Y502075D01*
G01X885600Y488800D02*
X884774Y489626D01*
G01X885600Y480400D02*
Y488800D01*
G01X888200Y477800D02*
X885600Y480400D01*
G01X881956Y519862D02*
Y529835D01*
G01X883661Y518157D02*
X881956Y519862D01*
G01X848522Y527401D02*
Y528299D01*
G01X891334Y528899D02*
X890354D01*
G01X891933Y528300D02*
X891334Y528899D01*
G01X891933Y527100D02*
Y528300D01*
G01X868570Y530049D02*
X873621Y535100D01*
G01X878040Y528899D02*
X876968D01*
G01X878740Y528199D02*
X878040Y528899D01*
G01X878740Y526925D02*
Y528199D01*
G01X905381Y530049D02*
X910432Y535100D01*
G01X891834Y534700D02*
X893000D01*
G01X888649Y531515D02*
X891834Y534700D01*
G01X848822D02*
X849810D01*
G01X854523Y528899D02*
X853543D01*
G01X855122Y528300D02*
X854523Y528899D01*
G01X855122Y527100D02*
Y528300D01*
G01X885333Y528299D02*
Y527401D01*
G01X884733Y528899D02*
X885333Y528299D01*
G01X883661Y528899D02*
X884733D01*
G01X908158D02*
X907086D01*
G01X908858Y528199D02*
X908158Y528899D01*
G01X908858Y526925D02*
Y528199D01*
G01X871347Y528899D02*
X870275D01*
G01X872047Y528199D02*
X871347Y528899D01*
G01X872047Y526925D02*
Y528199D01*
G01X875263Y530049D02*
X880314Y535100D01*
G01X855023Y534700D02*
X856189D01*
G01X851838Y531515D02*
X855023Y534700D01*
G01X885633D02*
X886621D01*
G01X882578Y531645D02*
X885633Y534700D01*
G01X882578Y530457D02*
Y531645D01*
G01X881956Y529835D02*
X882578Y530457D01*
G01X963981Y17062D02*
X963976Y17057D01*
G01X963981Y18481D02*
Y17062D01*
G01X965617Y20117D02*
X963981Y18481D01*
G01X965617Y29302D02*
Y20117D01*
G01X965974Y29659D02*
X965617Y29302D01*
G01X965974Y31659D02*
Y29659D01*
G01X965374Y32259D02*
X965974Y31659D01*
G01X965374Y34559D02*
Y32259D01*
G01X962334Y10819D02*
X960629Y9114D01*
G01X962334Y29916D02*
Y10819D01*
G01X962250Y30000D02*
X962334Y29916D01*
G01X962250Y48589D02*
Y30000D01*
G01X970669Y16169D02*
Y17057D01*
G01X968964Y14464D02*
X970669Y16169D01*
G01X968964Y5788D02*
Y14464D01*
G01X969574Y5178D02*
X968964Y5788D01*
G01X970625Y5178D02*
X969574D01*
G01X971235Y4568D02*
X970625Y5178D01*
G01X971235Y2668D02*
Y4568D01*
G01X970625Y2058D02*
X971235Y2668D01*
G01X969574Y2058D02*
X970625D01*
G01X968964Y1448D02*
X969574Y2058D01*
G01X968964Y-2964D02*
Y1448D01*
G01X970669Y-4669D02*
X968964Y-2964D01*
G01X970669Y-7108D02*
Y-4669D01*
G01Y24469D02*
Y17057D01*
G01X972300Y26100D02*
X970669Y24469D01*
G01X960629Y2071D02*
Y-4536D01*
G01X959000Y3700D02*
X960629Y2071D01*
G01X959000Y10474D02*
Y3700D01*
G01X959600Y11074D02*
X959000Y10474D01*
G01X959600Y14300D02*
Y11074D01*
G01X958900Y15000D02*
X959600Y14300D01*
G01X958900Y28985D02*
Y15000D01*
G01X959674Y29759D02*
X958900Y28985D01*
G01X959674Y32727D02*
Y29759D01*
G01X958988Y33413D02*
X959674Y32727D01*
G01X968474Y29959D02*
Y34207D01*
G01X969054Y29379D02*
X968474Y29959D01*
G01X969054Y26439D02*
Y29379D01*
G01X968008Y25393D02*
X969054Y26439D01*
G01X968008Y20207D02*
Y25393D01*
G01X965600Y17799D02*
X968008Y20207D01*
G01X965600Y11053D02*
Y17799D01*
G01X965713Y10940D02*
X965600Y11053D01*
G01X965713Y-2987D02*
Y10940D01*
G01X963976Y-4724D02*
X965713Y-2987D01*
G01X963976Y-7108D02*
Y-4724D01*
G01X913779Y101737D02*
Y92757D01*
G01X915558Y73467D02*
X917125Y71900D01*
G01X915558Y74668D02*
Y73467D01*
G01X914200Y76026D02*
X915558Y74668D01*
G01X914200Y77399D02*
Y76026D01*
G01X915400Y78599D02*
X914200Y77399D01*
G01X915400Y79725D02*
Y78599D01*
G01X914200Y80925D02*
X915400Y79725D01*
G01X914200Y82500D02*
Y80925D01*
G01X916000Y84300D02*
X914200Y82500D01*
G01X916000Y85358D02*
Y84300D01*
G01X912658Y88700D02*
X916000Y85358D01*
G01X912658Y91636D02*
Y88700D01*
G01X913779Y92757D02*
X912658Y91636D01*
G01X950590Y92757D02*
Y100290D01*
G01X949344Y91511D02*
X950590Y92757D01*
G01X949344Y89299D02*
Y91511D01*
G01X952337Y86306D02*
X949344Y89299D01*
G01X952337Y73499D02*
Y86306D01*
G01X953936Y71900D02*
X952337Y73499D01*
G01X965700Y34885D02*
X965374Y34559D01*
G01X965700Y48860D02*
Y34885D01*
G01X965600Y48960D02*
X965700Y48860D01*
G01X965600Y67085D02*
Y48960D01*
G01X965974Y67459D02*
X965600Y67085D01*
G01X965974Y69459D02*
Y67459D01*
G01X965374Y70059D02*
X965974Y69459D01*
G01X965374Y72359D02*
Y70059D01*
G01X965699Y72684D02*
X965374Y72359D01*
G01X965699Y75034D02*
Y72684D01*
G01X965374Y75359D02*
X965699Y75034D01*
G01X965374Y85674D02*
Y75359D01*
G01X965974Y86274D02*
X965374Y85674D01*
G01X965974Y88174D02*
Y86274D01*
G01X965274Y88874D02*
X965974Y88174D01*
G01X965274Y90974D02*
Y88874D01*
G01X965974Y91674D02*
X965274Y90974D01*
G01X965974Y97974D02*
Y91674D01*
G01X918514Y86325D02*
X917125Y87714D01*
G01X918514Y73312D02*
Y86325D01*
G01X919126Y72700D02*
X918514Y73312D01*
G01X919126Y71300D02*
Y72700D01*
G01X917326Y69500D02*
X919126Y71300D01*
G01X916326Y69500D02*
X917326D01*
G01X915026Y68200D02*
X916326Y69500D01*
G01X915026Y66946D02*
Y68200D01*
G01X913779Y65699D02*
X915026Y66946D01*
G01X918374Y94474D02*
Y95365D01*
G01X915292Y91392D02*
X918374Y94474D01*
G01X915292Y89547D02*
Y91392D01*
G01X917125Y87714D02*
X915292Y89547D01*
G01X920472Y92757D02*
X923192Y95477D01*
G01X919544Y91829D02*
X920472Y92757D01*
G01X919544Y88701D02*
Y91829D01*
G01X922344Y85901D02*
X919544Y88701D01*
G01X922344Y72588D02*
Y85901D01*
G01X923432Y71500D02*
X922344Y72588D01*
G01X962371Y48710D02*
X962250Y48589D01*
G01X962371Y66962D02*
Y48710D01*
G01X961974Y67359D02*
X962371Y66962D01*
G01X961974Y69359D02*
Y67359D01*
G01X962574Y69959D02*
X961974Y69359D01*
G01X962574Y72459D02*
Y69959D01*
G01X962296Y72737D02*
X962574Y72459D01*
G01X962296Y76117D02*
Y72737D01*
G01X962574Y76395D02*
X962296Y76117D01*
G01X962574Y85874D02*
Y76395D01*
G01X962074Y86374D02*
X962574Y85874D01*
G01X962074Y88274D02*
Y86374D01*
G01X962774Y88974D02*
X962074Y88274D01*
G01X962774Y91074D02*
Y88974D01*
G01X962043Y91805D02*
X962774Y91074D01*
G01X962043Y97043D02*
Y91805D01*
G01X953392Y93756D02*
Y97092D01*
G01X955874Y91274D02*
X953392Y93756D01*
G01X955874Y89652D02*
Y91274D01*
G01X953936Y87714D02*
X955874Y89652D01*
G01X955325Y86325D02*
X953936Y87714D01*
G01X955325Y72976D02*
Y86325D01*
G01X955937Y72364D02*
X955325Y72976D01*
G01X955937Y71300D02*
Y72364D01*
G01X954137Y69500D02*
X955937Y71300D01*
G01X953137Y69500D02*
X954137D01*
G01X951837Y68200D02*
X953137Y69500D01*
G01X951837Y66946D02*
Y68200D01*
G01X950590Y65699D02*
X951837Y66946D01*
G01X927474Y93066D02*
Y102196D01*
G01X927165Y92757D02*
X927474Y93066D01*
G01X926044Y91636D02*
X927165Y92757D01*
G01X926044Y88700D02*
Y91636D01*
G01X928944Y85800D02*
X926044Y88700D01*
G01X928944Y72367D02*
Y85800D01*
G01X929811Y71500D02*
X928944Y72367D01*
G01X958988Y48960D02*
Y33413D01*
G01X959600Y49572D02*
X958988Y48960D01*
G01X959600Y51531D02*
Y49572D01*
G01X958924Y52207D02*
X959600Y51531D01*
G01X958924Y66809D02*
Y52207D01*
G01X959674Y67559D02*
X958924Y66809D01*
G01X959674Y72169D02*
Y67559D01*
G01X959000Y72843D02*
X959674Y72169D01*
G01X959000Y76301D02*
Y72843D01*
G01X958674Y76627D02*
X959000Y76301D01*
G01X958674Y85474D02*
Y76627D01*
G01X959674Y86474D02*
X958674Y85474D01*
G01X959674Y88224D02*
Y86474D01*
G01X958674Y89224D02*
X959674Y88224D01*
G01X958674Y91274D02*
Y89224D01*
G01X959674Y92274D02*
X958674Y91274D01*
G01X959674Y97674D02*
Y92274D01*
G01X968100Y92148D02*
Y97100D01*
G01X969274Y90974D02*
X968100Y92148D01*
G01X969274Y88974D02*
Y90974D01*
G01X968674Y88374D02*
X969274Y88974D01*
G01X968674Y86174D02*
Y88374D01*
G01X969274Y85574D02*
X968674Y86174D01*
G01X969274Y83774D02*
Y85574D01*
G01X968939Y83439D02*
X969274Y83774D01*
G01X968939Y69624D02*
Y83439D01*
G01X968700Y69385D02*
X968939Y69624D01*
G01X968700Y67533D02*
Y69385D01*
G01X969064Y67169D02*
X968700Y67533D01*
G01X969064Y53024D02*
Y67169D01*
G01X968950Y52910D02*
X969064Y53024D01*
G01X968950Y34683D02*
Y52910D01*
G01X968474Y34207D02*
X968950Y34683D01*
G01X921482Y91032D02*
X925074Y94624D01*
G01X921482Y89566D02*
Y91032D01*
G01X923334Y87714D02*
X921482Y89566D01*
G01X923518Y87714D02*
X923334D01*
G01X924744Y86488D02*
X923518Y87714D01*
G01X924744Y73475D02*
Y86488D01*
G01X925519Y72700D02*
X924744Y73475D01*
G01X925519Y71076D02*
Y72700D01*
G01X923943Y69500D02*
X925519Y71076D01*
G01X922719Y69500D02*
X923943D01*
G01X920472Y67253D02*
X922719Y69500D01*
G01X920472Y65699D02*
Y67253D01*
G01X911821Y86325D02*
X910432Y87714D01*
G01X911821Y73312D02*
Y86325D01*
G01X912433Y72700D02*
X911821Y73312D01*
G01X912433Y71300D02*
Y72700D01*
G01X910633Y69500D02*
X912433Y71300D01*
G01X910824Y93624D02*
Y101588D01*
G01X943897Y92761D02*
Y92757D01*
G01X945792Y94656D02*
X943897Y92761D01*
G01X945644Y73499D02*
X947243Y71900D01*
G01X945644Y86750D02*
Y73499D01*
G01X942644Y89750D02*
X945644Y86750D01*
G01X942644Y91504D02*
Y89750D01*
G01X943897Y92757D02*
X942644Y91504D01*
G01X929574Y92674D02*
Y101338D01*
G01X927774Y90874D02*
X929574Y92674D01*
G01X927774Y89751D02*
Y90874D01*
G01X929811Y87714D02*
X927774Y89751D01*
G01X931284Y86241D02*
X929811Y87714D01*
G01X931284Y73116D02*
Y86241D01*
G01X931900Y72500D02*
X931284Y73116D01*
G01X931900Y71156D02*
Y72500D01*
G01X930444Y69700D02*
X931900Y71156D01*
G01X929044Y69700D02*
X930444D01*
G01X927165Y67821D02*
X929044Y69700D01*
G01X927165Y65699D02*
Y67821D01*
G01X948192Y94092D02*
Y103192D01*
G01X945400Y91300D02*
X948192Y94092D01*
G01X945400Y89557D02*
Y91300D01*
G01X947243Y87714D02*
X945400Y89557D01*
G01X948632Y86325D02*
X947243Y87714D01*
G01X948632Y73312D02*
Y86325D01*
G01X949244Y72700D02*
X948632Y73312D01*
G01X949244Y71300D02*
Y72700D01*
G01X947444Y69500D02*
X949244Y71300D01*
G01X946444Y69500D02*
X947444D01*
G01X945144Y68200D02*
X946444Y69500D01*
G01X945144Y66946D02*
Y68200D01*
G01X943897Y65699D02*
X945144Y66946D01*
G01X915874Y103832D02*
X913779Y101737D01*
G01X915874Y105274D02*
Y103832D01*
G01X915174Y105974D02*
X915874Y105274D01*
G01X915174Y110874D02*
Y105974D01*
G01X915774Y111474D02*
X915174Y110874D01*
G01X915774Y114156D02*
Y111474D01*
G01X913492Y116438D02*
X915774Y114156D01*
G01X913492Y133556D02*
Y116438D01*
G01X914592Y134656D02*
X913492Y133556D01*
G01X916440Y134656D02*
X914592D01*
G01X917000Y135216D02*
X916440Y134656D01*
G01X917000Y137535D02*
Y135216D01*
G01X916440Y138095D02*
X917000Y137535D01*
G01X914560Y138095D02*
X916440D01*
G01X913950Y138705D02*
X914560Y138095D01*
G01X913950Y140095D02*
Y138705D01*
G01X914560Y140705D02*
X913950Y140095D01*
G01X919590Y140705D02*
X914560D01*
G01X920200Y141315D02*
X919590Y140705D01*
G01X920200Y142705D02*
Y141315D01*
G01X919590Y143315D02*
X920200Y142705D01*
G01X914560Y143315D02*
X919590D01*
G01X913950Y143925D02*
X914560Y143315D01*
G01X913950Y145315D02*
Y143925D01*
G01X914560Y145925D02*
X913950Y145315D01*
G01X919590Y145925D02*
X914560D01*
G01X920200Y146535D02*
X919590Y145925D01*
G01X920200Y166692D02*
Y146535D01*
G01X956492Y120600D02*
Y162958D01*
G01X955692Y119800D02*
X956492Y120600D01*
G01X951660Y119800D02*
X955692D01*
G01X951100Y119240D02*
X951660Y119800D01*
G01X951100Y116972D02*
Y119240D01*
G01X951660Y116412D02*
X951100Y116972D01*
G01X955692Y116412D02*
X951660D01*
G01X956492Y115612D02*
X955692Y116412D01*
G01X956492Y113656D02*
Y115612D01*
G01X955592Y112756D02*
X956492Y113656D01*
G01X953756Y112756D02*
X955592D01*
G01X952500Y111500D02*
X953756Y112756D01*
G01X952500Y109000D02*
Y111500D01*
G01X951874Y108374D02*
X952500Y109000D01*
G01X951874Y104226D02*
Y108374D01*
G01X953600Y102500D02*
X951874Y104226D01*
G01X953600Y101699D02*
Y102500D01*
G01X952901Y101000D02*
X953600Y101699D01*
G01X951300Y101000D02*
X952901D01*
G01X950590Y100290D02*
X951300Y101000D01*
G01X970500Y102500D02*
X965974Y97974D01*
G01X970500Y107569D02*
Y102500D01*
G01X990881Y127950D02*
X970500Y107569D01*
G01X922392Y131946D02*
Y165277D01*
G01X921782Y131336D02*
X922392Y131946D01*
G01X917210Y131336D02*
X921782D01*
G01X916600Y130726D02*
X917210Y131336D01*
G01X916600Y129336D02*
Y130726D01*
G01X917210Y128726D02*
X916600Y129336D01*
G01X920840Y128726D02*
X917210D01*
G01X921400Y128166D02*
X920840Y128726D01*
G01X921400Y126260D02*
Y128166D01*
G01X920840Y125700D02*
X921400Y126260D01*
G01X916602Y125700D02*
X920840D01*
G01X915992Y125090D02*
X916602Y125700D01*
G01X915992Y117474D02*
Y125090D01*
G01X918592Y114874D02*
X915992Y117474D01*
G01X918592Y111406D02*
Y114874D01*
G01X919074Y110924D02*
X918592Y111406D01*
G01X919074Y106224D02*
Y110924D01*
G01X918374Y105524D02*
X919074Y106224D01*
G01X918374Y102737D02*
Y105524D01*
G01X916192Y100555D02*
X918374Y102737D01*
G01X916192Y97547D02*
Y100555D01*
G01X918374Y95365D02*
X916192Y97547D01*
G01X925574Y123153D02*
Y162192D01*
G01X925014Y122593D02*
X925574Y123153D01*
G01X920660Y122593D02*
X925014D01*
G01X920100Y122033D02*
X920660Y122593D01*
G01X920100Y119953D02*
Y122033D01*
G01X920660Y119393D02*
X920100Y119953D01*
G01X924694Y119393D02*
X920660D01*
G01X925276Y118811D02*
X924694Y119393D01*
G01X925276Y118277D02*
Y118811D01*
G01X922592Y115593D02*
X925276Y118277D01*
G01X922592Y111892D02*
Y115593D01*
G01X921474Y110774D02*
X922592Y111892D01*
G01X921474Y106574D02*
Y110774D01*
G01X923192Y104856D02*
X921474Y106574D01*
G01X923192Y101564D02*
Y104856D01*
G01X922392Y100764D02*
X923192Y101564D01*
G01X920792Y100764D02*
X922392D01*
G01X919992Y99964D02*
X920792Y100764D01*
G01X919992Y98364D02*
Y99964D01*
G01X920692Y97664D02*
X919992Y98364D01*
G01X922292Y97664D02*
X920692D01*
G01X923192Y96764D02*
X922292Y97664D01*
G01X923192Y95477D02*
Y96764D01*
G01X968500Y103500D02*
X962043Y97043D01*
G01X968500Y108198D02*
Y103500D01*
G01X988881Y128579D02*
X968500Y108198D01*
G01X958992Y155856D02*
X964400Y161264D01*
G01X958992Y110336D02*
Y155856D01*
G01X958026Y109370D02*
X958992Y110336D01*
G01X956992Y109370D02*
X958026D01*
G01X956192Y108570D02*
X956992Y109370D01*
G01X956192Y106970D02*
Y108570D01*
G01X957400Y105762D02*
X956192Y106970D01*
G01X957400Y101100D02*
Y105762D01*
G01X953392Y97092D02*
X957400Y101100D01*
G01X929800Y115599D02*
Y157284D01*
G01X929074Y114873D02*
X929800Y115599D01*
G01X929074Y111574D02*
Y114873D01*
G01X927874Y110374D02*
X929074Y111574D01*
G01X927874Y106274D02*
Y110374D01*
G01X929292Y104856D02*
X927874Y106274D01*
G01X929292Y104014D02*
Y104856D01*
G01X927474Y102196D02*
X929292Y104014D01*
G01X966200Y104200D02*
X959674Y97674D01*
G01X966200Y109261D02*
Y104200D01*
G01X986881Y129942D02*
X966200Y109261D01*
G01X968100Y97100D02*
X972200Y101200D01*
G01X927800Y117200D02*
Y161751D01*
G01X925174Y114574D02*
X927800Y117200D01*
G01X925174Y111174D02*
Y114574D01*
G01X925374Y110974D02*
X925174Y111174D01*
G01X925374Y106274D02*
Y110974D01*
G01X925074Y105974D02*
X925374Y106274D01*
G01X925074Y94624D02*
Y105974D01*
G01X918300Y153000D02*
Y168626D01*
G01X913300Y148000D02*
X918300Y153000D01*
G01X910734Y148000D02*
X913300D01*
G01X910174Y137226D02*
Y147440D01*
G01X910992Y115238D02*
Y136408D01*
G01X911774Y114456D02*
X910992Y115238D01*
G01X911774Y111374D02*
Y114456D01*
G01X912340Y110808D02*
X911774Y111374D01*
G01X912340Y106240D02*
Y110808D01*
G01X911574Y105474D02*
X912340Y106240D01*
G01X911574Y102338D02*
Y105474D01*
G01X910824Y101588D02*
X911574Y102338D01*
G01X912700Y154310D02*
X912140Y153750D01*
G01X912700Y156352D02*
Y154310D01*
G01X945792Y103508D02*
Y94656D01*
G01X945274Y104026D02*
X945792Y103508D01*
G01X945274Y108574D02*
Y104026D01*
G01X946374Y109674D02*
X945274Y108574D01*
G01X946374Y112674D02*
Y109674D01*
G01X944792Y114256D02*
X946374Y112674D01*
G01X944792Y128857D02*
Y114256D01*
G01X948500Y132565D02*
X944792Y128857D01*
G01X948500Y135785D02*
Y132565D01*
G01X948192Y136093D02*
X948500Y135785D01*
G01X948192Y137693D02*
Y136093D01*
G01X948992Y138493D02*
X948192Y137693D01*
G01X950700Y138493D02*
X948992D01*
G01X951500Y139293D02*
X950700Y138493D01*
G01X951500Y140893D02*
Y139293D01*
G01X950700Y141693D02*
X951500Y140893D01*
G01X948992Y141693D02*
X950700D01*
G01X948192Y142493D02*
X948992Y141693D01*
G01X948192Y144093D02*
Y142493D01*
G01X948992Y144893D02*
X948192Y144093D01*
G01X951100Y144893D02*
X948992D01*
G01X951900Y145693D02*
X951100Y144893D01*
G01X951900Y147293D02*
Y145693D01*
G01X951100Y148093D02*
X951900Y147293D01*
G01X948992Y148093D02*
X951100D01*
G01X948192Y148893D02*
X948992Y148093D01*
G01X948192Y150493D02*
Y148893D01*
G01X948992Y151293D02*
X948192Y150493D01*
G01X951200Y151293D02*
X948992D01*
G01X952000Y152093D02*
X951200Y151293D01*
G01X952000Y153693D02*
Y152093D01*
G01X951200Y154493D02*
X952000Y153693D01*
G01X948992Y154493D02*
X951200D01*
G01X948192Y155293D02*
X948992Y154493D01*
G01X948192Y158093D02*
Y155293D01*
G01X933892Y115991D02*
Y158710D01*
G01X931724Y113823D02*
X933892Y115991D01*
G01X931724Y103488D02*
Y113823D01*
G01X929574Y101338D02*
X931724Y103488D01*
G01X953992Y124760D02*
Y163124D01*
G01X953432Y124200D02*
X953992Y124760D01*
G01X947852Y124200D02*
X953432D01*
G01X947292Y123640D02*
X947852Y124200D01*
G01X947292Y115456D02*
Y123640D01*
G01X948692Y114056D02*
X947292Y115456D01*
G01X948692Y108908D02*
Y114056D01*
G01X949174Y108426D02*
X948692Y108908D01*
G01X949174Y104174D02*
Y108426D01*
G01X948192Y103192D02*
X949174Y104174D01*
G01X912757Y208243D02*
X914344Y209830D01*
G01X912757Y204357D02*
Y208243D01*
G01X943449Y189941D02*
X920200Y166692D01*
G01X913180Y212380D02*
X914216D01*
G01X969219Y175685D02*
X973085D01*
G01X960441Y166907D02*
X969219Y175685D01*
G01X960441Y166115D02*
Y166907D01*
G01X962082Y164474D02*
X960441Y166115D01*
G01X962082Y163682D02*
Y164474D01*
G01X961063Y162663D02*
X962082Y163682D01*
G01X960271Y162663D02*
X961063D01*
G01X958630Y164304D02*
X960271Y162663D01*
G01X957838Y164304D02*
X958630D01*
G01X956492Y162958D02*
X957838Y164304D01*
G01X922392Y165277D02*
X945356Y188241D01*
G01X953826Y190444D02*
Y193611D01*
G01X925574Y162192D02*
X953826Y190444D01*
G01X970001Y173800D02*
X974600D01*
G01X964400Y168199D02*
X970001Y173800D01*
G01X964400Y161264D02*
Y168199D01*
G01X959200Y186684D02*
Y194265D01*
G01X954781Y182265D02*
X959200Y186684D01*
G01X953919Y182265D02*
X954781D01*
G01X953023Y183161D02*
X953919Y182265D01*
G01X952161Y183161D02*
X953023D01*
G01X950760Y181760D02*
X952161Y183161D01*
G01X950760Y180898D02*
Y181760D01*
G01X951656Y180002D02*
X950760Y180898D01*
G01X951656Y179140D02*
Y180002D01*
G01X950255Y177739D02*
X951656Y179140D01*
G01X949393Y177739D02*
X950255D01*
G01X948497Y178635D02*
X949393Y177739D01*
G01X947635Y178635D02*
X948497D01*
G01X946234Y177234D02*
X947635Y178635D01*
G01X946234Y176372D02*
Y177234D01*
G01X947130Y175476D02*
X946234Y176372D01*
G01X947130Y174614D02*
Y175476D01*
G01X945729Y173213D02*
X947130Y174614D01*
G01X944867Y173213D02*
X945729D01*
G01X943971Y174109D02*
X944867Y173213D01*
G01X943109Y174109D02*
X943971D01*
G01X941708Y172708D02*
X943109Y174109D01*
G01X941708Y171846D02*
Y172708D01*
G01X942604Y170950D02*
X941708Y171846D01*
G01X942604Y170088D02*
Y170950D01*
G01X941203Y168687D02*
X942604Y170088D01*
G01X940341Y168687D02*
X941203D01*
G01X939445Y169583D02*
X940341Y168687D01*
G01X938583Y169583D02*
X939445D01*
G01X937182Y168182D02*
X938583Y169583D01*
G01X937182Y167320D02*
Y168182D01*
G01X938078Y166424D02*
X937182Y167320D01*
G01X938078Y165562D02*
Y166424D01*
G01X936677Y164161D02*
X938078Y165562D01*
G01X935815Y164161D02*
X936677D01*
G01X934919Y165057D02*
X935815Y164161D01*
G01X934057Y165057D02*
X934919D01*
G01X932656Y163656D02*
X934057Y165057D01*
G01X932656Y162794D02*
Y163656D01*
G01X933552Y161898D02*
X932656Y162794D01*
G01X933552Y161036D02*
Y161898D01*
G01X929800Y157284D02*
X933552Y161036D01*
G01X956376Y190327D02*
Y193511D01*
G01X927800Y161751D02*
X956376Y190327D01*
G01X941672Y191998D02*
X941899D01*
G01X918300Y168626D02*
X941672Y191998D01*
G01X912140Y156912D02*
X912700Y156352D01*
G01X916150Y160132D02*
X915540Y159522D01*
G01X916150Y161522D02*
Y160132D01*
G01X915540Y162132D02*
X916150Y161522D01*
G01X911910Y162132D02*
X915540D01*
G01X911300Y162742D02*
X911910Y162132D01*
G01X911300Y164132D02*
Y162742D01*
G01X911910Y164742D02*
X911300Y164132D01*
G01X915540Y164742D02*
X911910D01*
G01X916150Y165352D02*
X915540Y164742D01*
G01X916150Y169857D02*
Y165352D01*
G01X940145Y193852D02*
X916150Y169857D01*
G01X948844Y158745D02*
X948192Y158093D01*
G01X950556Y158745D02*
X948844D01*
G01X951492Y159681D02*
X950556Y158745D01*
G01X951492Y163291D02*
Y159681D01*
G01X967656Y179455D02*
X951492Y163291D01*
G01X970355Y179455D02*
X967656D01*
G01X973636Y182736D02*
X970355Y179455D01*
G01X961476Y186294D02*
Y193991D01*
G01X933892Y158710D02*
X961476Y186294D01*
G01X971570Y177570D02*
X976186Y182186D01*
G01X968438Y177570D02*
X971570D01*
G01X953992Y163124D02*
X968438Y177570D01*
G01X962707Y401938D02*
Y408803D01*
G01X957579Y399557D02*
Y406859D01*
G01X965276Y401814D02*
Y409841D01*
G01X960157Y400397D02*
Y407817D01*
G01X952700Y463500D02*
Y465466D01*
G01X953200Y463000D02*
X952700Y463500D01*
G01X958582Y463000D02*
X953200D01*
G01X959356Y462226D02*
X958582Y463000D01*
G01X959356Y460925D02*
Y462226D01*
G01X958698Y460267D02*
X959356Y460925D01*
G01X953300Y460267D02*
X958698D01*
G01X952500Y459467D02*
X953300Y460267D01*
G01X952500Y458367D02*
Y459467D01*
G01X953300Y457567D02*
X952500Y458367D01*
G01X957704Y457567D02*
X953300D01*
G01X959100Y456171D02*
X957704Y457567D01*
G01X959100Y434101D02*
Y456171D01*
G01X978208Y414993D02*
X959100Y434101D01*
G01X936200Y435310D02*
Y466600D01*
G01X962707Y408803D02*
X936200Y435310D01*
G01X964307Y435593D02*
Y478038D01*
G01X983308Y416592D02*
X964307Y435593D01*
G01X931100Y433338D02*
Y465400D01*
G01X957579Y406859D02*
X931100Y433338D01*
G01X916000Y417813D02*
Y431545D01*
G01X923652Y410161D02*
X916000Y417813D01*
G01X915900Y451500D02*
Y488000D01*
G01X916500Y450900D02*
X915900Y451500D01*
G01X918100Y450900D02*
X916500D01*
G01X918800Y451600D02*
X918100Y450900D01*
G01X918800Y454700D02*
Y451600D01*
G01X919400Y455300D02*
X918800Y454700D01*
G01X920600Y455300D02*
X919400D01*
G01X921200Y454700D02*
X920600Y455300D01*
G01X921200Y419827D02*
Y454700D01*
G01X928671Y412356D02*
X921200Y419827D01*
G01X950100Y455800D02*
Y483200D01*
G01X950900Y455000D02*
X950100Y455800D01*
G01X952052Y455000D02*
X950900D01*
G01X953048Y454004D02*
X952052Y455000D01*
G01X953048Y452501D02*
Y454004D01*
G01X952248Y451701D02*
X953048Y452501D01*
G01X951200Y451701D02*
X952248D01*
G01X950400Y450901D02*
X951200Y451701D01*
G01X950400Y449301D02*
Y450901D01*
G01X951200Y448501D02*
X950400Y449301D01*
G01X955696Y448501D02*
X951200D01*
G01X956596Y447601D02*
X955696Y448501D01*
G01X956596Y432996D02*
Y447601D01*
G01X975658Y413934D02*
X956596Y432996D01*
G01X938800Y436317D02*
Y477195D01*
G01X965276Y409841D02*
X938800Y436317D01*
G01X912300Y449341D02*
Y494301D01*
G01X912860Y448781D02*
X912300Y449341D01*
G01X918340Y448781D02*
X912860D01*
G01X918900Y448221D02*
X918340Y448781D01*
G01X918900Y446781D02*
Y448221D01*
G01X918340Y446221D02*
X918900Y446781D01*
G01X912860Y446221D02*
X918340D01*
G01X912300Y445661D02*
X912860Y446221D01*
G01X912300Y444221D02*
Y445661D01*
G01X912860Y443661D02*
X912300Y444221D01*
G01X916740Y443661D02*
X912860D01*
G01X917300Y443101D02*
X916740Y443661D01*
G01X917300Y441661D02*
Y443101D01*
G01X916740Y441101D02*
X917300Y441661D01*
G01X912860Y441101D02*
X916740D01*
G01X912300Y440541D02*
X912860Y441101D01*
G01X912300Y438200D02*
Y440541D01*
G01X918100Y432400D02*
X912300Y438200D01*
G01X918100Y419320D02*
Y432400D01*
G01X925330Y412090D02*
X918100Y419320D01*
G01X933700Y434274D02*
Y465700D01*
G01X960157Y407817D02*
X933700Y434274D01*
G01X918421Y457800D02*
Y482621D01*
G01X918921Y457300D02*
X918421Y457800D01*
G01X920600Y457300D02*
X918921D01*
G01X921100Y457800D02*
X920600Y457300D01*
G01X921100Y459400D02*
Y457800D01*
G01X921700Y460000D02*
X921100Y459400D01*
G01X923100Y460000D02*
X921700D01*
G01X923800Y459300D02*
X923100Y460000D01*
G01X923800Y449500D02*
Y459300D01*
G01X924360Y448940D02*
X923800Y449500D01*
G01X925740Y448940D02*
X924360D01*
G01X926300Y448380D02*
X925740Y448940D01*
G01X926300Y446940D02*
Y448380D01*
G01X925740Y446380D02*
X926300Y446940D01*
G01X924360Y446380D02*
X925740D01*
G01X923800Y445820D02*
X924360Y446380D01*
G01X923800Y444380D02*
Y445820D01*
G01X924360Y443820D02*
X923800Y444380D01*
G01X925740Y443820D02*
X924360D01*
G01X926300Y443260D02*
X925740Y443820D01*
G01X926300Y441820D02*
Y443260D01*
G01X925740Y441260D02*
X926300Y441820D01*
G01X924360Y441260D02*
X925740D01*
G01X923800Y440700D02*
X924360Y441260D01*
G01X923800Y439260D02*
Y440700D01*
G01X924360Y438700D02*
X923800Y439260D01*
G01X925740Y438700D02*
X924360D01*
G01X926300Y438140D02*
X925740Y438700D01*
G01X926300Y436700D02*
Y438140D01*
G01X925740Y436140D02*
X926300Y436700D01*
G01X924360Y436140D02*
X925740D01*
G01X923800Y435580D02*
X924360Y436140D01*
G01X923800Y420784D02*
Y435580D01*
G01X930449Y414135D02*
X923800Y420784D01*
G01X961653Y434947D02*
Y466131D01*
G01X980758Y415842D02*
X961653Y434947D01*
G01X944532Y525788D02*
X945669Y526925D01*
G01X944532Y524712D02*
Y525788D01*
G01X945544Y523700D02*
X944532Y524712D01*
G01X945544Y522500D02*
Y523700D01*
G01X944532Y521488D02*
X945544Y522500D01*
G01X944532Y520412D02*
Y521488D01*
G01X945644Y519300D02*
X944532Y520412D01*
G01X945644Y516667D02*
Y519300D01*
G01X945469Y516492D02*
X945644Y516667D01*
G01X945469Y514800D02*
Y516492D01*
G01X947155Y513114D02*
X945469Y514800D01*
G01X947243Y513114D02*
X947155D01*
G01X948589Y511768D02*
X947243Y513114D01*
G01X948632Y511768D02*
X948589D01*
G01X948632Y499368D02*
Y511768D01*
G01X949800Y498200D02*
X948632Y499368D01*
G01X949800Y494900D02*
Y498200D01*
G01X948632Y493732D02*
X949800Y494900D01*
G01X948632Y488368D02*
Y493732D01*
G01X952700Y484300D02*
X948632Y488368D01*
G01X952700Y469396D02*
Y484300D01*
G01X953310Y468786D02*
X952700Y469396D01*
G01X956164Y468786D02*
X953310D01*
G01X956827Y468123D02*
X956164Y468786D01*
G01X956827Y466633D02*
Y468123D01*
G01X956270Y466076D02*
X956827Y466633D01*
G01X953310Y466076D02*
X956270D01*
G01X952700Y465466D02*
X953310Y466076D01*
G01X925460Y519862D02*
Y531515D01*
G01X927165Y518157D02*
X925460Y519862D01*
G01X925732Y516724D02*
X927165Y518157D01*
G01X925732Y514207D02*
Y516724D01*
G01X929082Y510857D02*
X925732Y514207D01*
G01X929082Y507398D02*
Y510857D01*
G01X928282Y506598D02*
X929082Y507398D01*
G01X928000Y506598D02*
X928282D01*
G01X927200Y505798D02*
X928000Y506598D01*
G01X927200Y504198D02*
Y505798D01*
G01X928000Y503398D02*
X927200Y504198D01*
G01X928282Y503398D02*
X928000D01*
G01X929082Y502598D02*
X928282Y503398D01*
G01X929082Y494982D02*
Y502598D01*
G01X927974Y493874D02*
X929082Y494982D01*
G01X927974Y489126D02*
Y493874D01*
G01X930316Y486784D02*
X927974Y489126D01*
G01X930316Y472484D02*
Y486784D01*
G01X936200Y466600D02*
X930316Y472484D01*
G01X962360Y519860D02*
Y533060D01*
G01X962000Y519500D02*
X962360Y519860D01*
G01X962000Y517100D02*
Y519500D01*
G01X962700Y516400D02*
X962000Y517100D01*
G01X962700Y514300D02*
Y516400D01*
G01X961900Y513500D02*
X962700Y514300D01*
G01X961900Y512000D02*
Y513500D01*
G01X962500Y511400D02*
X961900Y512000D01*
G01X962500Y501700D02*
Y511400D01*
G01X987400Y476800D02*
X962500Y501700D01*
G01X951225Y525788D02*
X952362Y526925D01*
G01X951225Y524712D02*
Y525788D01*
G01X952237Y523700D02*
X951225Y524712D01*
G01X952237Y522500D02*
Y523700D01*
G01X951225Y521488D02*
X952237Y522500D01*
G01X951225Y520412D02*
Y521488D01*
G01X952337Y519300D02*
X951225Y520412D01*
G01X952337Y516667D02*
Y519300D01*
G01X952162Y516492D02*
X952337Y516667D01*
G01X952162Y514800D02*
Y516492D01*
G01X953848Y513114D02*
X952162Y514800D01*
G01X953936Y513114D02*
X953848D01*
G01X953936Y513166D02*
Y513114D01*
G01X955774Y511328D02*
X953936Y513166D01*
G01X955774Y500000D02*
Y511328D01*
G01X956300Y499474D02*
X955774Y500000D01*
G01X956300Y492484D02*
Y499474D01*
G01X957327Y491457D02*
X956300Y492484D01*
G01X961667Y491457D02*
X957327D01*
G01X962318Y490806D02*
X961667Y491457D01*
G01X962318Y489416D02*
Y490806D01*
G01X961749Y488847D02*
X962318Y489416D01*
G01X958517Y488847D02*
X961749D01*
G01X957907Y488237D02*
X958517Y488847D01*
G01X957907Y486847D02*
Y488237D01*
G01X958517Y486237D02*
X957907Y486847D01*
G01X962421Y486237D02*
X958517D01*
G01X963057Y485601D02*
X962421Y486237D01*
G01X963057Y484211D02*
Y485601D01*
G01X962473Y483627D02*
X963057Y484211D01*
G01X958517Y483627D02*
X962473D01*
G01X957907Y483017D02*
X958517Y483627D01*
G01X957907Y480900D02*
Y483017D01*
G01X958707Y480100D02*
X957907Y480900D01*
G01X962245Y480100D02*
X958707D01*
G01X964307Y478038D02*
X962245Y480100D01*
G01X918767Y519862D02*
Y529835D01*
G01X920472Y518157D02*
X918767Y519862D01*
G01X919232Y516917D02*
X920472Y518157D01*
G01X919232Y514007D02*
Y516917D01*
G01X922382Y510857D02*
X919232Y514007D01*
G01X922382Y508982D02*
Y510857D01*
G01X921300Y507900D02*
X922382Y508982D01*
G01X921300Y503500D02*
Y507900D01*
G01X922400Y502400D02*
X921300Y503500D01*
G01X922400Y495200D02*
Y502400D01*
G01X921574Y494374D02*
X922400Y495200D01*
G01X921574Y490726D02*
Y494374D01*
G01X923600Y488700D02*
X921574Y490726D01*
G01X923600Y465700D02*
Y488700D01*
G01X924200Y465100D02*
X923600Y465700D01*
G01X925600Y465100D02*
X924200D01*
G01X926200Y465700D02*
X925600Y465100D01*
G01X926200Y467100D02*
Y465700D01*
G01X926900Y467800D02*
X926200Y467100D01*
G01X928700Y467800D02*
X926900D01*
G01X931100Y465400D02*
X928700Y467800D01*
G01X969030Y519830D02*
Y530570D01*
G01X968700Y519500D02*
X969030Y519830D01*
G01X968700Y516900D02*
Y519500D01*
G01X969300Y516300D02*
X968700Y516900D01*
G01X969300Y514400D02*
Y516300D01*
G01X968800Y513900D02*
X969300Y514400D01*
G01X968800Y511900D02*
Y513900D01*
G01X969200Y511500D02*
X968800Y511900D01*
G01X969200Y501000D02*
Y511500D01*
G01X991400Y478800D02*
X969200Y501000D01*
G01X912074Y519862D02*
Y530049D01*
G01X913779Y518157D02*
X912074Y519862D01*
G01X912421Y516799D02*
X913779Y518157D01*
G01X912421Y514307D02*
Y516799D01*
G01X915821Y510907D02*
X912421Y514307D01*
G01X915821Y495320D02*
Y510907D01*
G01X915500Y494999D02*
X915821Y495320D01*
G01X915500Y488400D02*
Y494999D01*
G01X915900Y488000D02*
X915500Y488400D01*
G01X965607Y519493D02*
Y530307D01*
G01X966000Y519100D02*
X965607Y519493D01*
G01X966000Y517000D02*
Y519100D01*
G01X965200Y516200D02*
X966000Y517000D01*
G01X965200Y514400D02*
Y516200D01*
G01X965800Y513800D02*
X965200Y514400D01*
G01X965800Y511500D02*
Y513800D01*
G01X965500Y511200D02*
X965800Y511500D01*
G01X965500Y501800D02*
Y511200D01*
G01X989400Y477900D02*
X965500Y501800D01*
G01X942192Y519862D02*
Y530049D01*
G01X943897Y518157D02*
X942192Y519862D01*
G01X943232Y517492D02*
X943897Y518157D01*
G01X943232Y513657D02*
Y517492D01*
G01X946132Y510757D02*
X943232Y513657D01*
G01X946132Y500032D02*
Y510757D01*
G01X945600Y499500D02*
X946132Y500032D01*
G01X945600Y494400D02*
Y499500D01*
G01X946600Y493400D02*
X945600Y494400D01*
G01X946600Y486700D02*
Y493400D01*
G01X950100Y483200D02*
X946600Y486700D01*
G01X927800Y526156D02*
X928744Y527100D01*
G01X927800Y524944D02*
Y526156D01*
G01X928644Y524100D02*
X927800Y524944D01*
G01X928644Y522400D02*
Y524100D01*
G01X927800Y521556D02*
X928644Y522400D01*
G01X927800Y520136D02*
Y521556D01*
G01X928944Y518992D02*
X927800Y520136D01*
G01X928944Y517399D02*
Y518992D01*
G01X928037Y516492D02*
X928944Y517399D01*
G01X928037Y514800D02*
Y516492D01*
G01X929723Y513114D02*
X928037Y514800D01*
G01X929811Y513114D02*
X929723D01*
G01X931732Y511193D02*
X929811Y513114D01*
G01X931732Y489068D02*
Y511193D01*
G01X932400Y488400D02*
X931732Y489068D01*
G01X932400Y483900D02*
Y488400D01*
G01X932970Y483330D02*
X932400Y483900D01*
G01X934670Y483330D02*
X932970D01*
G01X935500Y482500D02*
X934670Y483330D01*
G01X935500Y481330D02*
Y482500D01*
G01X934890Y480720D02*
X935500Y481330D01*
G01X933020Y480720D02*
X934890D01*
G01X932400Y480100D02*
X933020Y480720D01*
G01X932400Y473199D02*
Y480100D01*
G01X933220Y472379D02*
X932400Y473199D01*
G01X934820Y472379D02*
X933220D01*
G01X935800Y473359D02*
X934820Y472379D01*
G01X935800Y477095D02*
Y473359D01*
G01X936600Y477895D02*
X935800Y477095D01*
G01X938100Y477895D02*
X936600D01*
G01X938800Y477195D02*
X938100Y477895D01*
G01X910432Y513114D02*
X910344D01*
G01X911778Y511768D02*
X910432Y513114D01*
G01X911821Y511768D02*
X911778D01*
G01X911821Y507588D02*
Y511768D01*
G01X912621Y506788D02*
X911821Y507588D01*
G01X912900Y506788D02*
X912621D01*
G01X913700Y505988D02*
X912900Y506788D01*
G01X913700Y504388D02*
Y505988D01*
G01X912900Y503588D02*
X913700Y504388D01*
G01X912621Y503588D02*
X912900D01*
G01X911821Y502788D02*
X912621Y503588D01*
G01X911821Y494780D02*
Y502788D01*
G01X912300Y494301D02*
X911821Y494780D01*
G01X921107Y526364D02*
X922144Y527401D01*
G01X921107Y525136D02*
Y526364D01*
G01X922044Y524199D02*
X921107Y525136D01*
G01X922044Y522801D02*
Y524199D01*
G01X921107Y521864D02*
X922044Y522801D01*
G01X921107Y520536D02*
Y521864D01*
G01X922244Y519399D02*
X921107Y520536D01*
G01X922244Y517500D02*
Y519399D01*
G01X921744Y517000D02*
X922244Y517500D01*
G01X921744Y514800D02*
Y517000D01*
G01X923430Y513114D02*
X921744Y514800D01*
G01X923518Y513114D02*
X923430D01*
G01X925032Y511600D02*
X923518Y513114D01*
G01X925032Y506732D02*
Y511600D01*
G01X924610Y506310D02*
X925032Y506732D01*
G01X924000Y506310D02*
X924610D01*
G01X923200Y505510D02*
X924000Y506310D01*
G01X923200Y503910D02*
Y505510D01*
G01X924000Y503110D02*
X923200Y503910D01*
G01X924590Y503110D02*
X924000D01*
G01X925400Y502300D02*
X924590Y503110D01*
G01X925400Y495200D02*
Y502300D01*
G01X926100Y494500D02*
X925400Y495200D01*
G01X926100Y483580D02*
Y494500D01*
G01X926700Y482980D02*
X926100Y483580D01*
G01X927741Y482980D02*
X926700D01*
G01X928351Y482370D02*
X927741Y482980D01*
G01X928351Y480980D02*
Y482370D01*
G01X927741Y480370D02*
X928351Y480980D01*
G01X926160Y480370D02*
X927741D01*
G01X925523Y479733D02*
X926160Y480370D01*
G01X925523Y478343D02*
Y479733D01*
G01X926106Y477760D02*
X925523Y478343D01*
G01X927715Y477760D02*
X926106D01*
G01X928378Y477097D02*
X927715Y477760D01*
G01X928378Y475707D02*
Y477097D01*
G01X927821Y475150D02*
X928378Y475707D01*
G01X926132Y475150D02*
X927821D01*
G01X925596Y474614D02*
X926132Y475150D01*
G01X925596Y473804D02*
Y474614D01*
G01X933700Y465700D02*
X925596Y473804D01*
G01X914414Y525788D02*
X915551Y526925D01*
G01X914414Y524712D02*
Y525788D01*
G01X915426Y523700D02*
X914414Y524712D01*
G01X915426Y522500D02*
Y523700D01*
G01X914414Y521488D02*
X915426Y522500D01*
G01X914414Y520412D02*
Y521488D01*
G01X915526Y519300D02*
X914414Y520412D01*
G01X915526Y516667D02*
Y519300D01*
G01X915351Y516492D02*
X915526Y516667D01*
G01X915351Y514800D02*
Y516492D01*
G01X917037Y513114D02*
X915351Y514800D01*
G01X917125Y513114D02*
X917037D01*
G01X917125Y513166D02*
Y513114D01*
G01X918421Y511870D02*
X917125Y513166D01*
G01X918421Y497752D02*
Y511870D01*
G01X919000Y497173D02*
X918421Y497752D01*
G01X919000Y483200D02*
Y497173D01*
G01X918421Y482621D02*
X919000Y483200D01*
G01X948885Y519862D02*
Y530049D01*
G01X950590Y518157D02*
X948885Y519862D01*
G01X949232Y516799D02*
X950590Y518157D01*
G01X949232Y514307D02*
Y516799D01*
G01X952632Y510907D02*
X949232Y514307D01*
G01X952632Y499700D02*
Y510907D01*
G01X952300Y499368D02*
X952632Y499700D01*
G01X952300Y494000D02*
Y499368D01*
G01X953900Y492400D02*
X952300Y494000D01*
G01X953900Y487800D02*
Y492400D01*
G01X955400Y486300D02*
X953900Y487800D01*
G01X955400Y478564D02*
Y486300D01*
G01X956320Y477644D02*
X955400Y478564D01*
G01X957912Y477644D02*
X956320D01*
G01X958489Y477067D02*
X957912Y477644D01*
G01X958489Y475067D02*
Y477067D01*
G01X957866Y474444D02*
X958489Y475067D01*
G01X956598Y474444D02*
X957866D01*
G01X955798Y473644D02*
X956598Y474444D01*
G01X955798Y471986D02*
Y473644D01*
G01X961653Y466131D02*
X955798Y471986D01*
G01X944969Y528899D02*
X943897D01*
G01X945669Y528199D02*
X944969Y528899D01*
G01X945669Y526925D02*
Y528199D01*
G01X928645Y534700D02*
X929811D01*
G01X925460Y531515D02*
X928645Y534700D01*
G01X959600Y587400D02*
Y591392D01*
G01X959010Y586810D02*
X959600Y587400D01*
G01X959010Y580390D02*
Y586810D01*
G01X962242Y577158D02*
X959010Y580390D01*
G01X962242Y568358D02*
Y577158D01*
G01X962346Y568254D02*
X962242Y568358D01*
G01X962346Y552146D02*
Y568254D01*
G01X962257Y552057D02*
X962346Y552146D01*
G01X962257Y535343D02*
Y552057D01*
G01X962700Y534900D02*
X962257Y535343D01*
G01X962700Y533400D02*
Y534900D01*
G01X962360Y533060D02*
X962700Y533400D01*
G01X951662Y528899D02*
X950590D01*
G01X952362Y528199D02*
X951662Y528899D01*
G01X952362Y526925D02*
Y528199D01*
G01X922444Y534700D02*
X923432D01*
G01X919389Y531645D02*
X922444Y534700D01*
G01X919389Y530457D02*
Y531645D01*
G01X918767Y529835D02*
X919389Y530457D01*
G01X962257Y583743D02*
Y590070D01*
G01X968927Y577073D02*
X962257Y583743D01*
G01X968927Y573727D02*
Y577073D01*
G01X968800Y573600D02*
X968927Y573727D01*
G01X968800Y568400D02*
Y573600D01*
G01X969031Y568169D02*
X968800Y568400D01*
G01X969031Y554135D02*
Y568169D01*
G01X968700Y553804D02*
X969031Y554135D01*
G01X968700Y549500D02*
Y553804D01*
G01X968927Y549273D02*
X968700Y549500D01*
G01X968927Y530673D02*
Y549273D01*
G01X969030Y530570D02*
X968927Y530673D01*
G01X912074Y530049D02*
X917125Y535100D01*
G01X960629Y581988D02*
Y585714D01*
G01X965695Y576922D02*
X960629Y581988D01*
G01X965695Y568395D02*
Y576922D01*
G01X965607Y568307D02*
X965695Y568395D01*
G01X965607Y552093D02*
Y568307D01*
G01X965695Y552005D02*
X965607Y552093D01*
G01X965695Y533105D02*
Y552005D01*
G01X966000Y532800D02*
X965695Y533105D01*
G01X966000Y530700D02*
Y532800D01*
G01X965607Y530307D02*
X966000Y530700D01*
G01X968928Y583572D02*
X975657Y576843D01*
G01X968928Y591012D02*
Y583572D01*
G01X965695Y583305D02*
Y589805D01*
G01X972395Y576605D02*
X965695Y583305D01*
G01X942192Y530049D02*
X947243Y535100D01*
G01X928145Y528899D02*
X927165D01*
G01X928744Y528300D02*
X928145Y528899D01*
G01X928744Y527100D02*
Y528300D01*
G01X921544Y528899D02*
X920472D01*
G01X922144Y528299D02*
X921544Y528899D01*
G01X922144Y527401D02*
Y528299D01*
G01X914851Y528899D02*
X913779D01*
G01X915551Y528199D02*
X914851Y528899D01*
G01X915551Y526925D02*
Y528199D01*
G01X948885Y530049D02*
X953936Y535100D01*
G01X960629Y607429D02*
Y609864D01*
G01X958500Y605300D02*
X960629Y607429D01*
G01X958500Y597200D02*
Y605300D01*
G01X958893Y596807D02*
X958500Y597200D01*
G01X958893Y592099D02*
Y596807D01*
G01X959600Y591392D02*
X958893Y592099D01*
G01X963976Y591789D02*
Y593657D01*
G01X962257Y590070D02*
X963976Y591789D01*
G01X969539Y606162D02*
X970669Y607292D01*
G01X969539Y594787D02*
Y606162D01*
G01X970669Y593657D02*
X969539Y594787D01*
G01X970669Y592753D02*
X968928Y591012D01*
G01X970669Y593657D02*
Y592753D01*
G01X963976Y599606D02*
Y607292D01*
G01X965607Y597975D02*
X963976Y599606D01*
G01X965607Y589893D02*
Y597975D01*
G01X965695Y589805D02*
X965607Y589893D01*
G01X971452Y601826D02*
X972062Y602436D01*
G01X971452Y600836D02*
Y601826D01*
G01X972062Y600226D02*
X971452Y600836D01*
G01X971870Y597406D02*
X972480Y598016D01*
G01Y595806D02*
X971870Y596416D01*
G01X997441Y-1743D02*
Y9122D01*
G01Y11800D02*
Y9122D01*
G01X999146Y13505D02*
X997441Y11800D01*
G01X999146Y20954D02*
Y13505D01*
G01X995700Y24400D02*
X999146Y20954D01*
G01X995700Y34545D02*
Y24400D01*
G01X1004287Y-1588D02*
X1004133Y-1742D01*
G01X1004287Y8968D02*
Y-1588D01*
G01X1004133Y9122D02*
X1004287Y8968D01*
G01X1004500Y9489D02*
X1004133Y9122D01*
G01X1004500Y14901D02*
Y9489D01*
G01X1005744Y16145D02*
X1004500Y14901D01*
G01X1005744Y28756D02*
Y16145D01*
G01X1004900Y29600D02*
X1005744Y28756D01*
G01X1004900Y34200D02*
Y29600D01*
G01X992274Y-5392D02*
X994094Y-9786D01*
G01X992274Y-3426D02*
Y-5392D01*
G01X992600Y-3100D02*
X992274Y-3426D01*
G01X992600Y-1080D02*
Y-3100D01*
G01X991731Y-211D02*
X992600Y-1080D01*
G01X991731Y7491D02*
Y-211D01*
G01X992471Y8231D02*
X991731Y7491D01*
G01X992471Y13138D02*
Y8231D01*
G01X994094Y17057D02*
X992471Y13138D01*
G01X994094Y19806D02*
Y17057D01*
G01X989143Y24757D02*
X994094Y19806D01*
G01X989143Y31682D02*
Y24757D01*
G01X989006Y31819D02*
X989143Y31682D01*
G01X989006Y43549D02*
Y31819D01*
G01X989550Y-5910D02*
X990748Y-7108D01*
G01X989550Y-3750D02*
Y-5910D01*
G01X988948Y-3148D02*
X989550Y-3750D01*
G01X988948Y-952D02*
Y-3148D01*
G01X989500Y-400D02*
X988948Y-952D01*
G01X989500Y6100D02*
Y-400D01*
G01X989043Y6557D02*
X989500Y6100D01*
G01X989043Y15352D02*
Y6557D01*
G01X990748Y17057D02*
X989043Y15352D01*
G01X990748Y20153D02*
Y17057D01*
G01X985696Y25205D02*
X990748Y20153D01*
G01X985696Y29009D02*
Y25205D01*
G01X986446Y29759D02*
X985696Y29009D01*
G01X986446Y31459D02*
Y29759D01*
G01X985700Y32205D02*
X986446Y31459D01*
G01X985700Y48200D02*
Y32205D01*
G01X995200Y-5642D02*
X994094Y-4536D01*
G01X996033Y-5642D02*
X995200D01*
G01X996857Y-4818D02*
X996033Y-5642D01*
G01X996857Y-3823D02*
Y-4818D01*
G01X995716Y-2682D02*
X996857Y-3823D01*
G01X995716Y-632D02*
Y-2682D01*
G01X994995Y89D02*
X995716Y-632D01*
G01X994008Y89D02*
X994995D01*
G01X993359Y738D02*
X994008Y89D01*
G01X993359Y1728D02*
Y738D01*
G01X993930Y2299D02*
X993359Y1728D01*
G01X995068Y2299D02*
X993930D01*
G01X995678Y2909D02*
X995068Y2299D01*
G01X995678Y3899D02*
Y2909D01*
G01X995068Y4509D02*
X995678Y3899D01*
G01X993943Y4509D02*
X995068D01*
G01X993360Y5092D02*
X993943Y4509D01*
G01X993360Y6082D02*
Y5092D01*
G01X993997Y6719D02*
X993360Y6082D01*
G01X994831Y6719D02*
X993997D01*
G01X995441Y7329D02*
X994831Y6719D01*
G01X995441Y8621D02*
Y7329D01*
G01X994940Y9122D02*
X995441Y8621D01*
G01X994094Y9122D02*
X994940D01*
G01X994094Y11982D02*
Y9122D01*
G01X995729Y13617D02*
X994094Y11982D01*
G01X995729Y21171D02*
Y13617D01*
G01X992489Y24411D02*
X995729Y21171D01*
G01X992489Y50631D02*
Y24411D01*
G01X987401Y6858D02*
Y9114D01*
G01X986791Y6248D02*
X987401Y6858D01*
G01X983119Y6248D02*
X986791D01*
G01X982509Y5638D02*
X983119Y6248D01*
G01X982509Y3738D02*
Y5638D01*
G01X983119Y3128D02*
X982509Y3738D01*
G01X986791Y3128D02*
X983119D01*
G01X987401Y2518D02*
X986791Y3128D01*
G01X987401Y316D02*
Y2518D01*
G01X986700Y-385D02*
X987401Y316D01*
G01X986700Y-1644D02*
Y-385D01*
G01X985100Y-3244D02*
X986700Y-1644D01*
G01X985100Y-4700D02*
Y-3244D01*
G01X985700Y-5300D02*
X985100Y-4700D01*
G01X986637Y-5300D02*
X985700D01*
G01X987401Y-4536D02*
X986637Y-5300D01*
G01X982054Y29765D02*
Y33461D01*
G01X982400Y29419D02*
X982054Y29765D01*
G01X982400Y21900D02*
Y29419D01*
G01X985660Y18640D02*
X982400Y21900D01*
G01X985660Y10855D02*
Y18640D01*
G01X987401Y9114D02*
X985660Y10855D01*
G01X1002528Y15451D02*
X1004134Y17057D01*
G01X1002528Y3428D02*
Y15451D01*
G01X1002300Y3200D02*
X1002528Y3428D01*
G01X1002300Y-2900D02*
Y3200D01*
G01X1004134Y-4734D02*
X1002300Y-2900D01*
G01X1004134Y-7108D02*
Y-4734D01*
G01Y25166D02*
Y17057D01*
G01X1002500Y26800D02*
X1004134Y25166D01*
G01X1002500Y48306D02*
Y26800D01*
G01X972300Y28999D02*
Y26100D01*
G01X973060Y29759D02*
X972300Y28999D01*
G01X973060Y34239D02*
Y29759D01*
G01X977362Y238D02*
Y-1743D01*
G01X976800Y800D02*
X977362Y238D01*
G01X976800Y8552D02*
Y800D01*
G01X977362Y9114D02*
X976800Y8552D01*
G01X972300Y14176D02*
X977362Y9114D01*
G01X972300Y18829D02*
Y14176D01*
G01X975657Y22186D02*
X972300Y18829D01*
G01X975657Y29262D02*
Y22186D01*
G01X975200Y29719D02*
X975657Y29262D01*
G01X975200Y32199D02*
Y29719D01*
G01X975710Y32709D02*
X975200Y32199D01*
G01X975710Y53724D02*
Y32709D01*
G01X1000772Y-9895D02*
X1000787Y-9901D01*
G01X999059Y-5759D02*
X1000772Y-9895D01*
G01X999059Y-3552D02*
Y-5759D01*
G01X1000000Y-1280D02*
X999059Y-3552D01*
G01X1000000Y6400D02*
Y-1280D01*
G01X999072Y7328D02*
X1000000Y6400D01*
G01X999072Y10173D02*
Y7328D01*
G01X1000787Y11888D02*
X999072Y10173D01*
G01X1000787Y17057D02*
Y11888D01*
G01X999905Y30790D02*
Y34130D01*
G01X999182Y30067D02*
X999905Y30790D01*
G01X999182Y24918D02*
Y30067D01*
G01X1001300Y22800D02*
X999182Y24918D01*
G01X1001300Y17570D02*
Y22800D01*
G01X1000787Y17057D02*
X1001300Y17570D01*
G01X979000Y12072D02*
X974015Y17057D01*
G01X979000Y4708D02*
Y12072D01*
G01X979594Y4114D02*
X979000Y4708D01*
G01X979594Y-2206D02*
Y4114D01*
G01X974015Y-7785D02*
X979594Y-2206D01*
G01X974015Y-9901D02*
Y-7785D01*
G01X978441Y32578D02*
Y34240D01*
G01X979860Y31159D02*
X978441Y32578D01*
G01X979860Y29485D02*
Y31159D01*
G01X979100Y28725D02*
X979860Y29485D01*
G01X979100Y26519D02*
Y28725D01*
G01X979360Y26259D02*
X979100Y26519D01*
G01X979360Y22402D02*
Y26259D01*
G01X974015Y17057D02*
X979360Y22402D01*
G01X995780Y34625D02*
X995700Y34545D01*
G01X995780Y48040D02*
Y34625D01*
G01X995710Y48110D02*
X995780Y48040D01*
G01X995710Y59638D02*
Y48110D01*
G01X996701Y60629D02*
X995710Y59638D01*
G01X996701Y62758D02*
Y60629D01*
G01X995710Y63749D02*
X996701Y62758D01*
G01X995710Y67295D02*
Y63749D01*
G01X995246Y67759D02*
X995710Y67295D01*
G01X995246Y69159D02*
Y67759D01*
G01X996046Y69959D02*
X995246Y69159D01*
G01X996046Y72159D02*
Y69959D01*
G01X995798Y72407D02*
X996046Y72159D01*
G01X995798Y83526D02*
Y72407D01*
G01X996046Y83774D02*
X995798Y83526D01*
G01X996046Y85574D02*
Y83774D01*
G01X995446Y86174D02*
X996046Y85574D01*
G01X995446Y88374D02*
Y86174D01*
G01X996046Y88974D02*
X995446Y88374D01*
G01X996046Y90974D02*
Y88974D01*
G01X995260Y91760D02*
X996046Y90974D01*
G01X995260Y96092D02*
Y91760D01*
G01X1006200Y35500D02*
X1004900Y34200D01*
G01X1006200Y45100D02*
Y35500D01*
G01X1005775Y45525D02*
X1006200Y45100D01*
G01X1005775Y48032D02*
Y45525D01*
G01X1005532Y48275D02*
X1005775Y48032D01*
G01X1005532Y53900D02*
Y48275D01*
G01X1005761Y54129D02*
X1005532Y53900D01*
G01X1005761Y66630D02*
Y54129D01*
G01X1005268Y67123D02*
X1005761Y66630D01*
G01X1005268Y72539D02*
Y67123D01*
G01X1005814Y73085D02*
X1005268Y72539D01*
G01X1005814Y75077D02*
Y73085D01*
G01X1005532Y75359D02*
X1005814Y75077D01*
G01X1005532Y85674D02*
Y75359D01*
G01X1005728Y85870D02*
X1005532Y85674D01*
G01X1005728Y96429D02*
Y85870D01*
G01X989010Y43553D02*
X989006Y43549D01*
G01X989010Y50638D02*
Y43553D01*
G01X989120Y50748D02*
X989010Y50638D01*
G01X989120Y69852D02*
Y50748D01*
G01X989013Y69959D02*
X989120Y69852D01*
G01X989013Y81297D02*
Y69959D01*
G01X989346Y81630D02*
X989013Y81297D01*
G01X989346Y85874D02*
Y81630D01*
G01X988846Y86374D02*
X989346Y85874D01*
G01X988846Y88274D02*
Y86374D01*
G01X989546Y88974D02*
X988846Y88274D01*
G01X989546Y91074D02*
Y88974D01*
G01X988815Y91805D02*
X989546Y91074D01*
G01X988815Y97827D02*
Y91805D01*
G01X985680Y48220D02*
X985700Y48200D01*
G01X985680Y66793D02*
Y48220D01*
G01X985738Y66851D02*
X985680Y66793D01*
G01X985738Y75567D02*
Y66851D01*
G01X985446Y75859D02*
X985738Y75567D01*
G01X985446Y85156D02*
Y75859D01*
G01X986171Y85881D02*
X985446Y85156D01*
G01X986171Y88531D02*
Y85881D01*
G01X985446Y89256D02*
X986171Y88531D01*
G01X985446Y91274D02*
Y89256D01*
G01X985974Y91802D02*
X985446Y91274D01*
G01X985974Y97815D02*
Y91802D01*
G01X992430Y50690D02*
X992489Y50631D01*
G01X992430Y72643D02*
Y50690D01*
G01X992470Y72683D02*
X992430Y72643D01*
G01X992470Y75035D02*
Y72683D01*
G01X992146Y75359D02*
X992470Y75035D01*
G01X992146Y85674D02*
Y75359D01*
G01X992746Y86274D02*
X992146Y85674D01*
G01X992746Y88174D02*
Y86274D01*
G01X992046Y88874D02*
X992746Y88174D01*
G01X992046Y90974D02*
Y88874D01*
G01X992746Y91674D02*
X992046Y90974D01*
G01X992746Y98929D02*
Y91674D01*
G01X982060Y91574D02*
Y97461D01*
G01X982660Y90974D02*
X982060Y91574D01*
G01X982660Y88974D02*
Y90974D01*
G01X982060Y88374D02*
X982660Y88974D01*
G01X982060Y86174D02*
Y88374D01*
G01X982660Y85574D02*
X982060Y86174D01*
G01X982660Y83774D02*
Y85574D01*
G01X982414Y83528D02*
X982660Y83774D01*
G01X982414Y72405D02*
Y83528D01*
G01X982093Y72084D02*
X982414Y72405D01*
G01X982093Y67526D02*
Y72084D01*
G01X982420Y67199D02*
X982093Y67526D01*
G01X982420Y52800D02*
Y67199D01*
G01X981918Y52298D02*
X982420Y52800D01*
G01X981918Y49602D02*
Y52298D01*
G01X982420Y49100D02*
X981918Y49602D01*
G01X982420Y45734D02*
Y49100D01*
G01X982060Y45374D02*
X982420Y45734D01*
G01X982060Y38339D02*
Y45374D01*
G01X982450Y37949D02*
X982060Y38339D01*
G01X982450Y33857D02*
Y37949D01*
G01X982054Y33461D02*
X982450Y33857D01*
G01X1002430Y48376D02*
X1002500Y48306D01*
G01X1002430Y69657D02*
Y48376D01*
G01X1002519Y69746D02*
X1002430Y69657D01*
G01X1002519Y86087D02*
Y69746D01*
G01X1002232Y86374D02*
X1002519Y86087D01*
G01X1002232Y88274D02*
Y86374D01*
G01X1002932Y88974D02*
X1002232Y88274D01*
G01X1002932Y91074D02*
Y88974D01*
G01X1002201Y91805D02*
X1002932Y91074D01*
G01X1002201Y95731D02*
Y91805D01*
G01X972400Y34899D02*
X973060Y34239D01*
G01X972400Y48014D02*
Y34899D01*
G01X973060Y48674D02*
X972400Y48014D01*
G01X973060Y51140D02*
Y48674D01*
G01X972380Y51820D02*
X973060Y51140D01*
G01X972380Y66879D02*
Y51820D01*
G01X972700Y67199D02*
X972380Y66879D01*
G01X972700Y72391D02*
Y67199D01*
G01X972396Y72695D02*
X972700Y72391D01*
G01X972396Y75523D02*
Y72695D01*
G01X972060Y75859D02*
X972396Y75523D01*
G01X972060Y85474D02*
Y75859D01*
G01X972469Y85883D02*
X972060Y85474D01*
G01X972469Y88815D02*
Y85883D01*
G01X972215Y89069D02*
X972469Y88815D01*
G01X972215Y91429D02*
Y89069D01*
G01X972500Y91714D02*
X972215Y91429D01*
G01X972500Y95800D02*
Y91714D01*
G01X975630Y53804D02*
X975710Y53724D01*
G01X975630Y67089D02*
Y53804D01*
G01X975360Y67359D02*
X975630Y67089D01*
G01X975360Y69359D02*
Y67359D01*
G01X975960Y69959D02*
X975360Y69359D01*
G01X975960Y72459D02*
Y69959D01*
G01X975714Y72705D02*
X975960Y72459D01*
G01X975714Y81384D02*
Y72705D01*
G01X975960Y81630D02*
X975714Y81384D01*
G01X975960Y85874D02*
Y81630D01*
G01X975460Y86374D02*
X975960Y85874D01*
G01X975460Y88274D02*
Y86374D01*
G01X976160Y88974D02*
X975460Y88274D01*
G01X976160Y91074D02*
Y88974D01*
G01X975429Y91805D02*
X976160Y91074D01*
G01X975429Y96129D02*
Y91805D01*
G01X999374Y91816D02*
Y95733D01*
G01X998832Y91274D02*
X999374Y91816D01*
G01X998832Y89224D02*
Y91274D01*
G01X999832Y88224D02*
X998832Y89224D01*
G01X999832Y86474D02*
Y88224D01*
G01X998832Y85474D02*
X999832Y86474D01*
G01X998832Y83393D02*
Y85474D01*
G01X999849Y82376D02*
X998832Y83393D01*
G01X999849Y80273D02*
Y82376D01*
G01X998832Y79256D02*
X999849Y80273D01*
G01X998832Y75859D02*
Y79256D01*
G01X999051Y75640D02*
X998832Y75859D01*
G01X999051Y72578D02*
Y75640D01*
G01X998832Y72359D02*
X999051Y72578D01*
G01X998832Y70259D02*
Y72359D01*
G01X999832Y69259D02*
X998832Y70259D01*
G01X999832Y67559D02*
Y69259D01*
G01X999150Y66877D02*
X999832Y67559D01*
G01X999150Y64633D02*
Y66877D01*
G01X1000255Y63528D02*
X999150Y64633D01*
G01X1000255Y60881D02*
Y63528D01*
G01X999150Y59776D02*
X1000255Y60881D01*
G01X999150Y53792D02*
Y59776D01*
G01X998709Y53351D02*
X999150Y53792D01*
G01X998709Y51547D02*
Y53351D01*
G01X999681Y50575D02*
X998709Y51547D01*
G01X999681Y48523D02*
Y50575D01*
G01X999060Y47902D02*
X999681Y48523D01*
G01X999060Y45664D02*
Y47902D01*
G01X1000105Y44619D02*
X999060Y45664D01*
G01X1000105Y42469D02*
Y44619D01*
G01X999060Y41424D02*
X1000105Y42469D01*
G01X999060Y34975D02*
Y41424D01*
G01X999905Y34130D02*
X999060Y34975D01*
G01X979360Y91674D02*
Y97560D01*
G01X978660Y90974D02*
X979360Y91674D01*
G01X978660Y89230D02*
Y90974D01*
G01X979643Y88247D02*
X978660Y89230D01*
G01X979643Y86557D02*
Y88247D01*
G01X978760Y85674D02*
X979643Y86557D01*
G01X978760Y75359D02*
Y85674D01*
G01X978990Y75129D02*
X978760Y75359D01*
G01X978990Y72949D02*
Y75129D01*
G01X978429Y72388D02*
X978990Y72949D01*
G01X978429Y70390D02*
Y72388D01*
G01X979703Y69116D02*
X978429Y70390D01*
G01X979703Y67220D02*
Y69116D01*
G01X979100Y66617D02*
X979703Y67220D01*
G01X979100Y53614D02*
Y66617D01*
G01X978382Y52896D02*
X979100Y53614D01*
G01X978382Y51352D02*
Y52896D01*
G01X979595Y50139D02*
X978382Y51352D01*
G01X979595Y48709D02*
Y50139D01*
G01X978980Y48094D02*
X979595Y48709D01*
G01X978980Y34779D02*
Y48094D01*
G01X978441Y34240D02*
X978980Y34779D01*
G01X995870Y96702D02*
X995260Y96092D01*
G01X997579Y96702D02*
X995870D01*
G01X998924Y98047D02*
X997579Y96702D01*
G01X998924Y98909D02*
Y98047D01*
G01X997751Y100082D02*
X998924Y98909D01*
G01X997751Y101105D02*
Y100082D01*
G01X1005238Y108592D02*
X997751Y101105D01*
G01X1007199Y108592D02*
X1005238D01*
G01X1008906Y110299D02*
X1007199Y108592D01*
G01X1008906Y191225D02*
Y110299D01*
G01X1014906Y105607D02*
X1005728Y96429D01*
G01X1014906Y196325D02*
Y105607D01*
G01X990881Y200481D02*
Y127950D01*
G01X1032240Y115700D02*
X1042600Y105340D01*
G01X1032240Y190375D02*
Y115700D01*
G01X999315Y108327D02*
X988815Y97827D01*
G01X999315Y113643D02*
Y108327D01*
G01X1004906Y119234D02*
X999315Y113643D01*
G01X1004906Y190725D02*
Y119234D01*
G01X988393Y100234D02*
X985974Y97815D01*
G01X988393Y101364D02*
Y100234D01*
G01X987176Y102581D02*
X988393Y101364D01*
G01X987176Y103747D02*
Y102581D01*
G01X988207Y104778D02*
X987176Y103747D01*
G01X989506Y104778D02*
X988207D01*
G01X990657Y103627D02*
X989506Y104778D01*
G01X991786Y103627D02*
X990657D01*
G01X992919Y104760D02*
X991786Y103627D01*
G01X992919Y105917D02*
Y104760D01*
G01X991177Y107659D02*
X992919Y105917D01*
G01X991177Y108656D02*
Y107659D01*
G01X992353Y109832D02*
X991177Y108656D01*
G01X993531Y109832D02*
X992353D01*
G01X995210Y108153D02*
X993531Y109832D01*
G01X996312Y108153D02*
X995210D01*
G01X997315Y109156D02*
X996312Y108153D01*
G01X997315Y114472D02*
Y109156D01*
G01X1002906Y120063D02*
X997315Y114472D01*
G01X1002906Y200493D02*
Y120063D01*
G01X1001886Y108069D02*
X992746Y98929D01*
G01X1001886Y112117D02*
Y108069D01*
G01X1002810Y113041D02*
X1001886Y112117D01*
G01X1005752Y113041D02*
X1002810D01*
G01X1006906Y114195D02*
X1005752Y113041D01*
G01X1006906Y191175D02*
Y114195D01*
G01X1000906Y120892D02*
Y200173D01*
G01X985400Y105386D02*
X1000906Y120892D01*
G01X985400Y100801D02*
Y105386D01*
G01X982060Y97461D02*
X985400Y100801D01*
G01X1012906Y106436D02*
X1002201Y95731D01*
G01X1012906Y196375D02*
Y106436D01*
G01X1030240Y114870D02*
X1040600Y104510D01*
G01X1030240Y190271D02*
Y114870D01*
G01X988881Y191212D02*
Y128579D01*
G01X979200Y102500D02*
X972500Y95800D01*
G01X979200Y109597D02*
Y102500D01*
G01X994906Y125303D02*
X979200Y109597D01*
G01X994906Y200336D02*
Y125303D01*
G01X986881Y190678D02*
Y129942D01*
G01X992881Y127012D02*
Y200681D01*
G01X972200Y106331D02*
X992881Y127012D01*
G01X972200Y101200D02*
Y106331D01*
G01X981400Y102100D02*
X975429Y96129D01*
G01X981400Y107044D02*
Y102100D01*
G01X996906Y122550D02*
X981400Y107044D01*
G01X996906Y201105D02*
Y122550D01*
G01X1010906Y107265D02*
Y191275D01*
G01X1009257Y105616D02*
X1010906Y107265D01*
G01X1008125Y105616D02*
X1009257D01*
G01X1007687Y106054D02*
X1008125Y105616D01*
G01X1006555Y106054D02*
X1007687D01*
G01X1005424Y104923D02*
X1006555Y106054D01*
G01X1005424Y103791D02*
Y104923D01*
G01X1005862Y103353D02*
X1005424Y103791D01*
G01X1005862Y102221D02*
Y103353D01*
G01X1004731Y101090D02*
X1005862Y102221D01*
G01X1003599Y101090D02*
X1004731D01*
G01X1002711Y101978D02*
X1003599Y101090D01*
G01X1001579Y101978D02*
X1002711D01*
G01X1000448Y100847D02*
X1001579Y101978D01*
G01X1000448Y99715D02*
Y100847D01*
G01X1001336Y98827D02*
X1000448Y99715D01*
G01X1001336Y97695D02*
Y98827D01*
G01X999374Y95733D02*
X1001336Y97695D01*
G01X998906Y121721D02*
Y200994D01*
G01X983200Y106015D02*
X998906Y121721D01*
G01X983200Y101400D02*
Y106015D01*
G01X979360Y97560D02*
X983200Y101400D01*
G01X978828Y181428D02*
Y194186D01*
G01X973085Y175685D02*
X978828Y181428D01*
G01X1030238Y190273D02*
X1030240Y190271D01*
G01X981397Y180597D02*
Y194186D01*
G01X974600Y173800D02*
X981397Y180597D01*
G01X973636Y192131D02*
Y182736D01*
G01X976186Y182186D02*
Y192141D01*
G01X987400Y399687D02*
Y476800D01*
G01X1012140Y408908D02*
Y401713D01*
G01X991400Y399889D02*
Y478800D01*
G01X989400Y399607D02*
Y477900D01*
G01X995400Y480458D02*
Y398948D01*
G01X993400Y399647D02*
Y479629D01*
G01X997400Y395781D02*
Y481400D01*
G01X1032800Y402828D02*
Y491912D01*
G01X978208Y406691D02*
Y414993D01*
G01X1013400Y410168D02*
X1012140Y408908D01*
G01X1013400Y502438D02*
Y410168D01*
G01X983308Y406691D02*
Y416592D01*
G01X1007400Y492678D02*
Y413816D01*
G01X1008109Y410535D02*
Y405305D01*
G01X1009400Y411826D02*
X1008109Y410535D01*
G01X1009400Y494928D02*
Y411826D01*
G01X1005400Y413600D02*
Y492292D01*
G01X1011400Y410997D02*
Y495758D01*
G01X1010140Y409737D02*
X1011400Y410997D01*
G01X1010140Y404760D02*
Y409737D01*
G01X1028800Y405271D02*
Y493570D01*
G01X1001400Y486828D02*
Y406100D01*
G01X975658Y406691D02*
Y413934D01*
G01X999400Y485999D02*
Y405706D01*
G01X1003400Y405714D02*
Y491628D01*
G01X1030800Y405204D02*
Y492741D01*
G01X980758Y406691D02*
Y415842D01*
G01X1006400Y509438D02*
X1013400Y502438D01*
G01X1006400Y524824D02*
Y509438D01*
G01X1009223Y527647D02*
X1006400Y524824D01*
G01X1003198Y496880D02*
X1007400Y492678D01*
G01X1003198Y497848D02*
Y496880D01*
G01X1001403Y499643D02*
X1003198Y497848D01*
G01X1000555Y499643D02*
X1001403D01*
G01X998672Y501526D02*
X1000555Y499643D01*
G01X998672Y502826D02*
Y501526D01*
G01X995347Y506151D02*
X998672Y502826D01*
G01X995347Y508747D02*
Y506151D01*
G01X996000Y509400D02*
X995347Y508747D01*
G01X996000Y511400D02*
Y509400D01*
G01X995668Y511732D02*
X996000Y511400D01*
G01X995668Y513868D02*
Y511732D01*
G01X995900Y514100D02*
X995668Y513868D01*
G01X995900Y516600D02*
Y514100D01*
G01X995300Y517200D02*
X995900Y516600D01*
G01X995300Y520800D02*
Y517200D01*
G01X995727Y521227D02*
X995300Y520800D01*
G01X995727Y533027D02*
Y521227D01*
G01X998206Y506122D02*
X1009400Y494928D01*
G01X998206Y510606D02*
Y506122D01*
G01X999306Y511706D02*
X998206Y510606D01*
G01X999306Y514194D02*
Y511706D01*
G01X998900Y514600D02*
X999306Y514194D01*
G01X998900Y516300D02*
Y514600D01*
G01X999900Y517300D02*
X998900Y516300D01*
G01X999900Y524200D02*
Y517300D01*
G01X999163Y524937D02*
X999900Y524200D01*
G01X999163Y532837D02*
Y524937D01*
G01X992376Y522024D02*
Y535676D01*
G01X992600Y521800D02*
X992376Y522024D01*
G01X992600Y517000D02*
Y521800D01*
G01X992100Y516500D02*
X992600Y517000D01*
G01X992100Y514400D02*
Y516500D01*
G01X992700Y513800D02*
X992100Y514400D01*
G01X992700Y511700D02*
Y513800D01*
G01X991900Y510900D02*
X992700Y511700D01*
G01X991900Y505792D02*
Y510900D01*
G01X1005400Y492292D02*
X991900Y505792D01*
G01X980700Y495158D02*
X995400Y480458D01*
G01X980700Y504599D02*
Y495158D01*
G01X976000Y509299D02*
X980700Y504599D01*
G01X976000Y511600D02*
Y509299D01*
G01X975581Y512019D02*
X976000Y511600D01*
G01X975581Y513981D02*
Y512019D01*
G01X975805Y514205D02*
X975581Y513981D01*
G01X975805Y516495D02*
Y514205D01*
G01X975642Y516658D02*
X975805Y516495D01*
G01X975642Y537707D02*
Y516658D01*
G01X1002500Y520400D02*
Y577000D01*
G01X1002000Y519900D02*
X1002500Y520400D01*
G01X1002000Y517400D02*
Y519900D01*
G01X1002800Y516600D02*
X1002000Y517400D01*
G01X1002800Y514500D02*
Y516600D01*
G01X1002100Y513800D02*
X1002800Y514500D01*
G01X1002100Y511600D02*
Y513800D01*
G01X1002664Y511036D02*
X1002100Y511600D01*
G01X1002664Y509330D02*
Y511036D01*
G01X1001433Y508099D02*
X1002664Y509330D01*
G01X1001433Y506908D02*
Y508099D01*
G01X1002723Y505618D02*
X1001433Y506908D01*
G01X1003772Y505618D02*
X1002723D01*
G01X1005006Y506852D02*
X1003772Y505618D01*
G01X1006041Y506852D02*
X1005006D01*
G01X1007309Y505584D02*
X1006041Y506852D01*
G01X1007309Y504629D02*
Y505584D01*
G01X1005815Y503135D02*
X1007309Y504629D01*
G01X1005815Y501838D02*
Y503135D01*
G01X1006946Y500707D02*
X1005815Y501838D01*
G01X1007913Y500707D02*
X1006946D01*
G01X1008972Y501766D02*
X1007913Y500707D01*
G01X1010145Y501766D02*
X1008972D01*
G01X1011276Y500635D02*
X1010145Y501766D01*
G01X1011276Y499544D02*
Y500635D01*
G01X1010011Y498279D02*
X1011276Y499544D01*
G01X1010011Y497147D02*
Y498279D01*
G01X1011400Y495758D02*
X1010011Y497147D01*
G01X972351Y526449D02*
Y530351D01*
G01X972700Y526100D02*
X972351Y526449D01*
G01X972700Y517000D02*
Y526100D01*
G01X972100Y516400D02*
X972700Y517000D01*
G01X972100Y514300D02*
Y516400D01*
G01X972600Y513800D02*
X972100Y514300D01*
G01X972600Y511500D02*
Y513800D01*
G01X972100Y511000D02*
X972600Y511500D01*
G01X972100Y509200D02*
Y511000D01*
G01X978700Y502600D02*
X972100Y509200D01*
G01X978700Y494329D02*
Y502600D01*
G01X993400Y479629D02*
X978700Y494329D01*
G01X1028800Y493570D02*
X1042400Y507170D01*
G01X986700Y501528D02*
X1001400Y486828D01*
G01X986700Y508154D02*
Y501528D01*
G01X985500Y509354D02*
X986700Y508154D01*
G01X985500Y511100D02*
Y509354D01*
G01X985900Y511500D02*
X985500Y511100D01*
G01X985900Y513900D02*
Y511500D01*
G01X985400Y514400D02*
X985900Y513900D01*
G01X985400Y516300D02*
Y514400D01*
G01X986300Y517200D02*
X985400Y516300D01*
G01X986300Y524800D02*
Y517200D01*
G01X985692Y525408D02*
X986300Y524800D01*
G01X985692Y549292D02*
Y525408D01*
G01X979080Y516780D02*
Y531596D01*
G01X978800Y516500D02*
X979080Y516780D01*
G01X978800Y514400D02*
Y516500D01*
G01X979400Y513800D02*
X978800Y514400D01*
G01X979400Y511700D02*
Y513800D01*
G01X978908Y511208D02*
X979400Y511700D01*
G01X978908Y509492D02*
Y511208D01*
G01X982700Y505700D02*
X978908Y509492D01*
G01X982700Y496100D02*
Y505700D01*
G01X997400Y481400D02*
X982700Y496100D01*
G01X997851Y487548D02*
X999400Y485999D01*
G01X996719Y487548D02*
X997851D01*
G01X995966Y486795D02*
X996719Y487548D01*
G01X994834Y486795D02*
X995966D01*
G01X993703Y487926D02*
X994834Y486795D01*
G01X993703Y489058D02*
Y487926D01*
G01X994456Y489811D02*
X993703Y489058D01*
G01X994456Y490943D02*
Y489811D01*
G01X993325Y492074D02*
X994456Y490943D01*
G01X992193Y492074D02*
X993325D01*
G01X991544Y491425D02*
X992193Y492074D01*
G01X990425Y491425D02*
X991544D01*
G01X989294Y492556D02*
X990425Y491425D01*
G01X989294Y493701D02*
Y492556D01*
G01X989930Y494337D02*
X989294Y493701D01*
G01X989930Y495469D02*
Y494337D01*
G01X984700Y500699D02*
X989930Y495469D01*
G01X984700Y507324D02*
Y500699D01*
G01X982700Y509324D02*
X984700Y507324D01*
G01X982700Y511200D02*
Y509324D01*
G01X982200Y511700D02*
X982700Y511200D01*
G01X982200Y514000D02*
Y511700D01*
G01X982600Y514400D02*
X982200Y514000D01*
G01X982600Y516300D02*
Y514400D01*
G01X982000Y516900D02*
X982600Y516300D01*
G01X982000Y525800D02*
Y516900D01*
G01X982400Y526200D02*
X982000Y525800D01*
G01X982400Y530300D02*
Y526200D01*
G01X989114Y521714D02*
Y535686D01*
G01X988200Y520800D02*
X989114Y521714D01*
G01X988200Y517700D02*
Y520800D01*
G01X989400Y516500D02*
X988200Y517700D01*
G01X989400Y514300D02*
Y516500D01*
G01X988800Y513700D02*
X989400Y514300D01*
G01X988800Y511700D02*
Y513700D01*
G01X989300Y511200D02*
X988800Y511700D01*
G01X989300Y502302D02*
Y511200D01*
G01X990828Y500774D02*
X989300Y502302D01*
G01X992204Y500774D02*
X990828D01*
G01X994000Y498978D02*
X992204Y500774D01*
G01X994000Y497058D02*
Y498978D01*
G01X994810Y496248D02*
X994000Y497058D01*
G01X995942Y496248D02*
X994810D01*
G01X996596Y496902D02*
X995942Y496248D01*
G01X997742Y496902D02*
X996596D01*
G01X998873Y495771D02*
X997742Y496902D01*
G01X998873Y494653D02*
Y495771D01*
G01X998195Y493975D02*
X998873Y494653D01*
G01X998195Y493043D02*
Y493975D01*
G01X999505Y491733D02*
X998195Y493043D01*
G01X1000479Y491733D02*
X999505D01*
G01X1001329Y492583D02*
X1000479Y491733D01*
G01X1002445Y492583D02*
X1001329D01*
G01X1003400Y491628D02*
X1002445Y492583D01*
G01X1030800Y492741D02*
X1045700Y507641D01*
G01X1032800Y491912D02*
X1033800Y492912D01*
G01X1009223Y556903D02*
Y527647D01*
G01X1005761Y560365D02*
X1009223Y556903D01*
G01X1005761Y567961D02*
Y560365D01*
G01X1005365Y568357D02*
X1005761Y567961D01*
G01X1005365Y573617D02*
Y568357D01*
G01X1005764Y574016D02*
X1005365Y573617D01*
G01X1005764Y577336D02*
Y574016D01*
G01X1002499Y580601D02*
X1005764Y577336D01*
G01X1002499Y587201D02*
Y580601D01*
G01X1002200Y587500D02*
X1002499Y587201D01*
G01X1002200Y591723D02*
Y587500D01*
G01X996100Y533400D02*
X995727Y533027D01*
G01X996100Y535400D02*
Y533400D01*
G01X995815Y535685D02*
X996100Y535400D01*
G01X995815Y551835D02*
Y535685D01*
G01X995725Y551925D02*
X995815Y551835D01*
G01X995725Y570925D02*
Y551925D01*
G01X995799Y570999D02*
X995725Y570925D01*
G01X995799Y576901D02*
Y570999D01*
G01X992479Y580221D02*
X995799Y576901D01*
G01X992479Y592042D02*
Y580221D01*
G01X994094Y587894D02*
X996100Y589900D01*
G01X994094Y585722D02*
Y587894D01*
G01X999076Y532924D02*
X999163Y532837D01*
G01X999076Y554576D02*
Y532924D01*
G01X999150Y554650D02*
X999076Y554576D01*
G01X999150Y573344D02*
Y554650D01*
G01X999047Y573447D02*
X999150Y573344D01*
G01X999047Y577153D02*
Y573447D01*
G01X994094Y582106D02*
X999047Y577153D01*
G01X994094Y585722D02*
Y582106D01*
G01X989027Y580473D02*
Y589527D01*
G01X992479Y577021D02*
X989027Y580473D01*
G01X992479Y535779D02*
Y577021D01*
G01X992376Y535676D02*
X992479Y535779D01*
G01X974380Y538969D02*
X975642Y537707D01*
G01X974380Y540441D02*
Y538969D01*
G01X974990Y541051D02*
X974380Y540441D01*
G01X976199Y541051D02*
X974990D01*
G01X976753Y541605D02*
X976199Y541051D01*
G01X976753Y543140D02*
Y541605D01*
G01X976087Y543806D02*
X976753Y543140D01*
G01X975060Y543806D02*
X976087D01*
G01X974422Y544444D02*
X975060Y543806D01*
G01X974422Y545624D02*
Y544444D01*
G01X975642Y546844D02*
X974422Y545624D01*
G01X975642Y570942D02*
Y546844D01*
G01X975657Y570957D02*
X975642Y570942D01*
G01X975657Y576843D02*
Y570957D01*
G01X999061Y580439D02*
Y591931D01*
G01X1002500Y577000D02*
X999061Y580439D01*
G01X972395Y572089D02*
Y576605D01*
G01X972700Y571784D02*
X972395Y572089D01*
G01X972700Y568500D02*
Y571784D01*
G01X972395Y568195D02*
X972700Y568500D01*
G01X972395Y564905D02*
Y568195D01*
G01X972306Y564816D02*
X972395Y564905D01*
G01X972306Y553886D02*
Y564816D01*
G01X972439Y553753D02*
X972306Y553886D01*
G01X972439Y549439D02*
Y553753D01*
G01X972395Y549395D02*
X972439Y549439D01*
G01X972395Y545405D02*
Y549395D01*
G01X972410Y545390D02*
X972395Y545405D01*
G01X972410Y534329D02*
Y545390D01*
G01X972894Y533845D02*
X972410Y534329D01*
G01X972894Y530894D02*
Y533845D01*
G01X972351Y530351D02*
X972894Y530894D01*
G01X981915Y587853D02*
Y591761D01*
G01X984054Y585714D02*
X981915Y587853D01*
G01X986100Y549700D02*
X985692Y549292D01*
G01X986100Y552376D02*
Y549700D01*
G01X985676Y552800D02*
X986100Y552376D01*
G01X985676Y568176D02*
Y552800D01*
G01X986100Y568600D02*
X985676Y568176D01*
G01X986100Y572048D02*
Y568600D01*
G01X985765Y572383D02*
X986100Y572048D01*
G01X985765Y575835D02*
Y572383D01*
G01X984054Y577546D02*
X985765Y575835D01*
G01X984054Y585714D02*
Y577546D01*
G01X972395Y583905D02*
Y588948D01*
G01X978991Y577309D02*
X972395Y583905D01*
G01X978991Y571009D02*
Y577309D01*
G01X979094Y570906D02*
X978991Y571009D01*
G01X979094Y554694D02*
Y570906D01*
G01X978992Y554592D02*
X979094Y554694D01*
G01X978992Y538430D02*
Y554592D01*
G01X978977Y538415D02*
X978992Y538430D01*
G01X978977Y531699D02*
Y538415D01*
G01X979080Y531596D02*
X978977Y531699D01*
G01X974015Y587677D02*
X976159Y589821D01*
G01X974015Y585714D02*
Y587677D01*
G01X982100Y530600D02*
X982400Y530300D01*
G01X982100Y534397D02*
Y530600D01*
G01X982415Y534712D02*
X982100Y534397D01*
G01X982415Y549185D02*
Y534712D01*
G01X981900Y549700D02*
X982415Y549185D01*
G01X981900Y552622D02*
Y549700D01*
G01X982385Y553107D02*
X981900Y552622D01*
G01X982385Y558015D02*
Y553107D01*
G01X981800Y558600D02*
X982385Y558015D01*
G01X981800Y564400D02*
Y558600D01*
G01X982342Y564942D02*
X981800Y564400D01*
G01X982342Y568158D02*
Y564942D01*
G01X981800Y568700D02*
X982342Y568158D01*
G01X981800Y572742D02*
Y568700D01*
G01X982429Y573371D02*
X981800Y572742D01*
G01X982429Y577300D02*
Y573371D01*
G01X974015Y585714D02*
X982429Y577300D01*
G01X986600Y586515D02*
Y591572D01*
G01X987401Y585714D02*
X986600Y586515D01*
G01X987401Y577899D02*
Y585714D01*
G01X989012Y576288D02*
X987401Y577899D01*
G01X989012Y568188D02*
Y576288D01*
G01X989136Y568064D02*
X989012Y568188D01*
G01X989136Y551160D02*
Y568064D01*
G01X989019Y551043D02*
X989136Y551160D01*
G01X989019Y535781D02*
Y551043D01*
G01X989114Y535686D02*
X989019Y535781D01*
G01X1004134Y593657D02*
Y607292D01*
G01Y593657D02*
X1002200Y591723D01*
G01X992908Y605800D02*
X994094Y604614D01*
G01X991988Y605800D02*
X992908D01*
G01X990985Y604797D02*
X991988Y605800D01*
G01X990985Y602316D02*
Y604797D01*
G01X991592Y601709D02*
X990985Y602316D01*
G01X995454Y601709D02*
X991592D01*
G01X996008Y601155D02*
X995454Y601709D01*
G01X996008Y599613D02*
Y601155D01*
G01X995494Y599099D02*
X996008Y599613D01*
G01X989836Y599099D02*
X995494D01*
G01X989239Y598502D02*
X989836Y599099D01*
G01X989239Y596865D02*
Y598502D01*
G01X989757Y596347D02*
X989239Y596865D01*
G01X993362Y596347D02*
X989757D01*
G01X994094Y595615D02*
X993362Y596347D01*
G01X994094Y593657D02*
Y595615D01*
G01Y593657D02*
X992479Y592042D01*
G01X995519Y606425D02*
X994094Y609864D01*
G01X997763Y604181D02*
X995519Y606425D01*
G01X997763Y596597D02*
Y604181D01*
G01X995725Y594559D02*
X997763Y596597D01*
G01X995725Y592675D02*
Y594559D01*
G01X996100Y592300D02*
X995725Y592675D01*
G01X996100Y589900D02*
Y592300D01*
G01X991600Y608144D02*
X990748Y607292D01*
G01X991600Y610062D02*
Y608144D01*
G01X991100Y610562D02*
X991600Y610062D01*
G01X989800Y610562D02*
X991100D01*
G01X989300Y610062D02*
X989800Y610562D01*
G01X989300Y609240D02*
Y610062D01*
G01X988031Y607971D02*
X989300Y609240D01*
G01X988031Y606415D02*
Y607971D01*
G01X989201Y605245D02*
X988031Y606415D01*
G01X989201Y603753D02*
Y605245D01*
G01X987601Y602153D02*
X989201Y603753D01*
G01X987601Y595994D02*
Y602153D01*
G01X989938Y593657D02*
X987601Y595994D01*
G01X990748Y593657D02*
X989938D01*
G01X990748Y591248D02*
Y593657D01*
G01X989027Y589527D02*
X990748Y591248D01*
G01X1002361Y602925D02*
X1000787Y604499D01*
G01X1002361Y600662D02*
Y602925D01*
G01X1001751Y600052D02*
X1002361Y600662D01*
G01X1000126Y600052D02*
X1001751D01*
G01X999516Y599442D02*
X1000126Y600052D01*
G01X999516Y598052D02*
Y599442D01*
G01X1000126Y597442D02*
X999516Y598052D01*
G01X1001751Y597442D02*
X1000126D01*
G01X1002361Y596832D02*
X1001751Y597442D01*
G01X1002361Y595231D02*
Y596832D01*
G01X1000787Y593657D02*
X1002361Y595231D01*
G01X999061Y591931D02*
X1000787Y593657D01*
G01X984055Y610355D02*
Y612457D01*
G01X982200Y608500D02*
X984055Y610355D01*
G01X982200Y606100D02*
Y608500D01*
G01X982700Y605600D02*
X982200Y606100D01*
G01X982700Y599700D02*
Y605600D01*
G01X982326Y599326D02*
X982700Y599700D01*
G01X982326Y592172D02*
Y599326D01*
G01X981915Y591761D02*
X982326Y592172D01*
G01X974015Y603046D02*
Y604499D01*
G01X973405Y602436D02*
X974015Y603046D01*
G01X972062Y602436D02*
X973405D01*
G01Y600226D02*
X972062D01*
G01X974015Y599616D02*
X973405Y600226D01*
G01X974015Y598626D02*
Y599616D01*
G01X973405Y598016D02*
X974015Y598626D01*
G01X972480Y598016D02*
X973405D01*
G01X971870Y596416D02*
Y597406D01*
G01X973405Y595806D02*
X972480D01*
G01X974015Y595196D02*
X973405Y595806D01*
G01X974015Y593657D02*
Y595196D01*
G01Y590568D02*
Y593657D01*
G01X972395Y588948D02*
X974015Y590568D01*
G01Y607685D02*
Y609864D01*
G01X976147Y605553D02*
X974015Y607685D01*
G01X976147Y595291D02*
Y605553D01*
G01X975657Y594801D02*
X976147Y595291D01*
G01X975657Y592743D02*
Y594801D01*
G01X976159Y592241D02*
X975657Y592743D01*
G01X976159Y589821D02*
Y592241D01*
G01X985855Y608318D02*
X987401Y609864D01*
G01X985855Y605853D02*
Y608318D01*
G01X985601Y605599D02*
X985855Y605853D01*
G01X985601Y594679D02*
Y605599D01*
G01X985676Y594604D02*
X985601Y594679D01*
G01X985676Y592496D02*
Y594604D01*
G01X986600Y591572D02*
X985676Y592496D01*
G01X1095427Y10061D02*
X1094488Y9122D01*
G01X1081102Y-7202D02*
Y-9901D01*
G01X1079300Y-5400D02*
X1081102Y-7202D01*
G01X1079300Y-3400D02*
Y-5400D01*
G01X1079700Y-3000D02*
X1079300Y-3400D01*
G01X1079700Y-100D02*
Y-3000D01*
G01X1079365Y235D02*
X1079700Y-100D01*
G01X1079365Y12435D02*
Y235D01*
G01X1076016Y15784D02*
X1079365Y12435D01*
G01X1076016Y19325D02*
Y15784D01*
G01X1072678Y22663D02*
X1076016Y19325D01*
G01X1072678Y29380D02*
Y22663D01*
G01X1073399Y30101D02*
X1072678Y29380D01*
G01X1073399Y33457D02*
Y30101D01*
G01X1086109Y31893D02*
Y38176D01*
G01X1086643Y31359D02*
X1086109Y31893D01*
G01X1086643Y29959D02*
Y31359D01*
G01X1086192Y29508D02*
X1086643Y29959D01*
G01X1086192Y21907D02*
Y29508D01*
G01X1089427Y18672D02*
X1086192Y21907D01*
G01X1089427Y-373D02*
Y18672D01*
G01X1089200Y-600D02*
X1089427Y-373D01*
G01X1089200Y-2744D02*
Y-600D01*
G01X1094488Y-8032D02*
X1089200Y-2744D01*
G01X1094488Y-9786D02*
Y-8032D01*
G01X1073628Y17823D02*
X1074409Y17042D01*
G01X1073628Y18883D02*
Y17823D01*
G01X1069424Y23087D02*
X1073628Y18883D01*
G01X1069424Y29006D02*
Y23087D01*
G01X1068362Y30068D02*
X1069424Y29006D01*
G01X1068362Y33520D02*
Y30068D01*
G01X1054330Y-7430D02*
Y-9901D01*
G01X1052400Y-5500D02*
X1054330Y-7430D01*
G01X1052400Y-3400D02*
Y-5500D01*
G01X1053000Y-2800D02*
X1052400Y-3400D01*
G01X1053000Y600D02*
Y-2800D01*
G01X1052673Y927D02*
X1053000Y600D01*
G01X1052673Y10373D02*
Y927D01*
G01X1053200Y10900D02*
X1052673Y10373D01*
G01X1053200Y15926D02*
Y10900D01*
G01X1054331Y17057D02*
X1053200Y15926D01*
G01X1049346Y22042D02*
X1054331Y17057D01*
G01X1049346Y53513D02*
Y22042D01*
G01X1094488Y5612D02*
Y-4536D01*
G01X1092864Y7236D02*
X1094488Y5612D01*
G01X1092864Y18636D02*
Y7236D01*
G01X1089427Y22073D02*
X1092864Y18636D01*
G01X1089427Y29375D02*
Y22073D01*
G01X1089143Y29659D02*
X1089427Y29375D01*
G01X1089143Y31659D02*
Y29659D01*
G01X1089743Y32259D02*
X1089143Y31659D01*
G01X1089743Y34559D02*
Y32259D01*
G01X1047637Y-7583D02*
Y-9901D01*
G01X1049665Y-5555D02*
X1047637Y-7583D01*
G01X1049665Y-3365D02*
Y-5555D01*
G01X1049033Y-2733D02*
X1049665Y-3365D01*
G01X1049033Y333D02*
Y-2733D01*
G01X1049349Y649D02*
X1049033Y333D01*
G01X1049349Y10051D02*
Y649D01*
G01X1047637Y11763D02*
X1049349Y10051D01*
G01X1047637Y17042D02*
Y11763D01*
G01X1047000Y17679D02*
X1047637Y17042D01*
G01X1047000Y25900D02*
Y17679D01*
G01X1045692Y27208D02*
X1047000Y25900D01*
G01X1045692Y28959D02*
Y27208D01*
G01X1045911Y29178D02*
X1045692Y28959D01*
G01X1045911Y37804D02*
Y29178D01*
G01X1087795Y-7695D02*
Y-9786D01*
G01X1082616Y-2516D02*
X1087795Y-7695D01*
G01X1082616Y316D02*
Y-2516D01*
G01X1082841Y541D02*
X1082616Y316D01*
G01X1082841Y10052D02*
Y541D01*
G01X1081241Y11652D02*
X1082841Y10052D01*
G01X1081241Y14811D02*
Y11652D01*
G01X1082715Y16285D02*
X1081241Y14811D01*
G01X1082715Y18285D02*
Y16285D01*
G01X1079372Y21628D02*
X1082715Y18285D01*
G01X1079372Y53689D02*
Y21628D01*
G01X1080000Y18144D02*
X1081102Y17042D01*
G01X1080000Y18170D02*
Y18144D01*
G01X1076124Y22046D02*
X1080000Y18170D01*
G01X1076124Y36846D02*
Y22046D01*
G01X1082843Y22011D02*
X1087795Y17059D01*
G01X1082843Y28973D02*
Y22011D01*
G01X1081381Y30435D02*
X1082843Y28973D01*
G01X1081381Y33325D02*
Y30435D01*
G01X1044291Y-1141D02*
Y-2200D01*
G01X1044290Y-1140D02*
X1044291Y-1141D01*
G01X1044290Y11792D02*
Y-1140D01*
G01Y13410D02*
Y11792D01*
G01X1042300Y15400D02*
X1044290Y13410D01*
G01X1042300Y97932D02*
Y15400D01*
G01X1094488Y21012D02*
Y17059D01*
G01X1092852Y22648D02*
X1094488Y21012D01*
G01X1092852Y31824D02*
Y22648D01*
G01X1092865Y31837D02*
X1092852Y31824D01*
G01X1092865Y38491D02*
Y31837D01*
G01X1060506Y-7108D02*
X1064369D01*
G01X1059100Y-5702D02*
X1060506Y-7108D01*
G01X1059100Y-3400D02*
Y-5702D01*
G01X1059476Y-3024D02*
X1059100Y-3400D01*
G01X1059476Y1817D02*
Y-3024D01*
G01X1060276Y2617D02*
X1059476Y1817D01*
G01X1061390Y2617D02*
X1060276D01*
G01X1062176Y3403D02*
X1061390Y2617D01*
G01X1062176Y5003D02*
Y3403D01*
G01X1061362Y5817D02*
X1062176Y5003D01*
G01X1060019Y5817D02*
X1061362D01*
G01X1059409Y6427D02*
X1060019Y5817D01*
G01X1059409Y10124D02*
Y6427D01*
G01X1060375Y11090D02*
X1059409Y10124D01*
G01X1060375Y14066D02*
Y11090D01*
G01X1059295Y15146D02*
X1060375Y14066D01*
G01X1059295Y18605D02*
Y15146D01*
G01X1055939Y21961D02*
X1059295Y18605D01*
G01X1055939Y29105D02*
Y21961D01*
G01X1055285Y29759D02*
X1055939Y29105D01*
G01X1055285Y31459D02*
Y29759D01*
G01X1055960Y32134D02*
X1055285Y31459D01*
G01X1055960Y37734D02*
Y32134D01*
G01X1064369Y9120D02*
X1064371Y9122D01*
G01X1064369Y7799D02*
Y9120D01*
G01X1064979Y7189D02*
X1064369Y7799D01*
G01X1068179Y7189D02*
X1064979D01*
G01X1068789Y6579D02*
X1068179Y7189D01*
G01X1068789Y115D02*
Y6579D01*
G01X1068151Y-523D02*
X1068789Y115D01*
G01X1067161Y-523D02*
X1068151D01*
G01X1066579Y59D02*
X1067161Y-523D01*
G01X1066579Y4249D02*
Y59D01*
G01X1065969Y4859D02*
X1066579Y4249D01*
G01X1064979Y4859D02*
X1065969D01*
G01X1064369Y4249D02*
X1064979Y4859D01*
G01X1064369Y-1743D02*
Y4249D01*
G01Y9124D02*
X1064371Y9122D01*
G01X1064369Y14169D02*
Y9124D01*
G01X1065994Y15794D02*
X1064369Y14169D01*
G01X1065994Y20858D02*
Y15794D01*
G01X1062746Y24106D02*
X1065994Y20858D01*
G01X1062746Y29284D02*
Y24106D01*
G01X1062371Y29659D02*
X1062746Y29284D01*
G01X1062371Y31659D02*
Y29659D01*
G01X1062971Y32259D02*
X1062371Y31659D01*
G01X1062971Y34559D02*
Y32259D01*
G01X1056450Y-5882D02*
X1057676Y-7108D01*
G01X1056450Y-3650D02*
Y-5882D01*
G01X1055800Y-3000D02*
X1056450Y-3650D01*
G01X1055800Y-1072D02*
Y-3000D01*
G01X1055971Y-901D02*
X1055800Y-1072D01*
G01X1055971Y10029D02*
Y-901D01*
G01X1055800Y10200D02*
X1055971Y10029D01*
G01X1055800Y15165D02*
Y10200D01*
G01X1057677Y17042D02*
X1055800Y15165D01*
G01X1052664Y22055D02*
X1057677Y17042D01*
G01X1052664Y29238D02*
Y22055D01*
G01X1052985Y29559D02*
X1052664Y29238D01*
G01X1052985Y31559D02*
Y29559D01*
G01X1051883Y32661D02*
X1052985Y31559D01*
G01X1051883Y34157D02*
Y32661D01*
G01X1059406Y22022D02*
X1064371Y17057D01*
G01X1059406Y29494D02*
Y22022D01*
G01X1059871Y29959D02*
X1059406Y29494D01*
G01X1059871Y33213D02*
Y29959D01*
G01X1074409Y-7711D02*
Y-9786D01*
G01X1072682Y-5984D02*
X1074409Y-7711D01*
G01X1072682Y-3338D02*
Y-5984D01*
G01X1073099Y-2921D02*
X1072682Y-3338D01*
G01X1073099Y1294D02*
Y-2921D01*
G01X1072682Y1711D02*
X1073099Y1294D01*
G01X1072682Y9918D02*
Y1711D01*
G01X1071650Y10950D02*
X1072682Y9918D01*
G01X1070428Y10950D02*
X1071650D01*
G01X1068910Y12468D02*
X1070428Y10950D01*
G01X1068910Y14431D02*
Y12468D01*
G01X1069423Y14944D02*
X1068910Y14431D01*
G01X1069423Y20259D02*
Y14944D01*
G01X1065978Y23704D02*
X1069423Y20259D01*
G01X1065978Y31930D02*
Y23704D01*
G01X1065989Y31941D02*
X1065978Y31930D01*
G01X1065989Y75711D02*
Y31941D01*
G01X1072673Y34183D02*
X1073399Y33457D01*
G01X1072673Y47990D02*
Y34183D01*
G01X1072776Y48093D02*
X1072673Y47990D01*
G01X1072776Y57358D02*
Y48093D01*
G01X1072683Y57451D02*
X1072776Y57358D01*
G01X1072683Y67185D02*
Y57451D01*
G01X1073257Y67759D02*
X1072683Y67185D01*
G01X1073257Y71035D02*
Y67759D01*
G01X1072684Y71608D02*
X1073257Y71035D01*
G01X1072684Y75015D02*
Y71608D01*
G01X1072457Y75242D02*
X1072684Y75015D01*
G01X1072457Y85574D02*
Y75242D01*
G01X1073057Y86174D02*
X1072457Y85574D01*
G01X1073057Y88374D02*
Y86174D01*
G01X1072457Y88974D02*
X1073057Y88374D01*
G01X1072457Y90974D02*
Y88974D01*
G01X1073057Y91574D02*
X1072457Y90974D01*
G01X1073057Y93342D02*
Y91574D01*
G01X1067000Y99399D02*
X1073057Y93342D01*
G01X1086443Y91574D02*
Y95656D01*
G01X1085843Y90974D02*
X1086443Y91574D01*
G01X1085843Y88974D02*
Y90974D01*
G01X1086443Y88374D02*
X1085843Y88974D01*
G01X1086443Y86174D02*
Y88374D01*
G01X1085843Y85574D02*
X1086443Y86174D01*
G01X1085843Y83774D02*
Y85574D01*
G01X1086157Y83460D02*
X1085843Y83774D01*
G01X1086157Y72473D02*
Y83460D01*
G01X1085843Y72159D02*
X1086157Y72473D01*
G01X1085843Y69959D02*
Y72159D01*
G01X1086643Y69159D02*
X1085843Y69959D01*
G01X1086643Y67759D02*
Y69159D01*
G01X1086190Y67306D02*
X1086643Y67759D01*
G01X1086190Y53521D02*
Y67306D01*
G01X1085843Y53174D02*
X1086190Y53521D01*
G01X1085843Y51174D02*
Y53174D01*
G01X1086443Y50574D02*
X1085843Y51174D01*
G01X1086443Y48374D02*
Y50574D01*
G01X1086173Y48104D02*
X1086443Y48374D01*
G01X1086173Y45644D02*
Y48104D01*
G01X1086443Y45374D02*
X1086173Y45644D01*
G01X1086443Y38983D02*
Y45374D01*
G01X1086109Y38176D02*
X1086443Y38983D01*
G01X1069446Y34604D02*
X1068362Y33520D01*
G01X1069446Y41454D02*
Y34604D01*
G01X1068604Y42296D02*
X1069446Y41454D01*
G01X1068604Y44064D02*
Y42296D01*
G01X1069446Y44906D02*
X1068604Y44064D01*
G01X1069446Y47899D02*
Y44906D01*
G01X1068410Y48935D02*
X1069446Y47899D01*
G01X1068410Y52699D02*
Y48935D01*
G01X1069428Y53717D02*
X1068410Y52699D01*
G01X1069428Y56336D02*
Y53717D01*
G01X1070255Y57163D02*
X1069428Y56336D01*
G01X1070255Y58724D02*
Y57163D01*
G01X1069429Y59550D02*
X1070255Y58724D01*
G01X1069429Y61334D02*
Y59550D01*
G01X1069987Y61892D02*
X1069429Y61334D01*
G01X1069987Y64174D02*
Y61892D01*
G01X1069428Y64733D02*
X1069987Y64174D01*
G01X1069428Y66802D02*
Y64733D01*
G01X1068671Y67559D02*
X1069428Y66802D01*
G01X1068671Y70959D02*
Y67559D01*
G01X1069439Y71727D02*
X1068671Y70959D01*
G01X1069439Y75627D02*
Y71727D01*
G01X1070474Y76662D02*
X1069439Y75627D01*
G01X1070474Y79103D02*
Y76662D01*
G01X1069864Y79713D02*
X1070474Y79103D01*
G01X1068608Y79713D02*
X1069864D01*
G01X1067998Y80323D02*
X1068608Y79713D01*
G01X1067998Y81713D02*
Y80323D01*
G01X1068608Y82323D02*
X1067998Y81713D01*
G01X1069864Y82323D02*
X1068608D01*
G01X1070474Y82933D02*
X1069864Y82323D01*
G01X1070474Y84671D02*
Y82933D01*
G01X1068671Y86474D02*
X1070474Y84671D01*
G01X1068671Y88224D02*
Y86474D01*
G01X1069671Y89224D02*
X1068671Y88224D01*
G01X1069671Y91274D02*
Y89224D01*
G01X1068671Y92274D02*
X1069671Y91274D01*
G01X1068671Y94829D02*
Y92274D01*
G01X1049266Y53593D02*
X1049346Y53513D01*
G01X1049266Y57358D02*
Y53593D01*
G01X1049370Y57462D02*
X1049266Y57358D01*
G01X1049370Y67074D02*
Y57462D01*
G01X1048985Y67459D02*
X1049370Y67074D01*
G01X1048985Y69459D02*
Y67459D01*
G01X1049585Y70059D02*
X1048985Y69459D01*
G01X1049585Y72359D02*
Y70059D01*
G01X1049347Y72597D02*
X1049585Y72359D01*
G01X1049347Y75121D02*
Y72597D01*
G01X1049749Y75523D02*
X1049347Y75121D01*
G01X1049749Y77625D02*
Y75523D01*
G01X1049249Y78125D02*
X1049749Y77625D01*
G01X1048455Y78125D02*
X1049249D01*
G01X1047821Y78759D02*
X1048455Y78125D01*
G01X1047821Y80659D02*
Y78759D01*
G01X1048407Y81245D02*
X1047821Y80659D01*
G01X1049237Y81245D02*
X1048407D01*
G01X1050041Y82049D02*
X1049237Y81245D01*
G01X1050041Y85218D02*
Y82049D01*
G01X1049095Y86164D02*
X1050041Y85218D01*
G01X1049095Y88284D02*
Y86164D01*
G01X1049459Y88648D02*
X1049095Y88284D01*
G01X1049459Y91200D02*
Y88648D01*
G01X1048985Y91674D02*
X1049459Y91200D01*
G01X1048985Y96907D02*
Y91674D01*
G01X1089433Y34869D02*
X1089743Y34559D01*
G01X1089433Y37249D02*
Y34869D01*
G01X1089743Y37559D02*
X1089433Y37249D01*
G01X1089743Y43644D02*
Y37559D01*
G01X1089421Y43966D02*
X1089743Y43644D01*
G01X1089421Y50418D02*
Y43966D01*
G01X1089843Y50840D02*
X1089421Y50418D01*
G01X1089843Y53174D02*
Y50840D01*
G01X1089422Y53595D02*
X1089843Y53174D01*
G01X1089422Y67180D02*
Y53595D01*
G01X1089143Y67459D02*
X1089422Y67180D01*
G01X1089143Y69459D02*
Y67459D01*
G01X1089743Y70059D02*
X1089143Y69459D01*
G01X1089743Y72359D02*
Y70059D01*
G01X1089411Y72691D02*
X1089743Y72359D01*
G01X1089411Y75027D02*
Y72691D01*
G01X1089743Y75359D02*
X1089411Y75027D01*
G01X1089743Y85674D02*
Y75359D01*
G01X1089143Y86274D02*
X1089743Y85674D01*
G01X1089143Y88174D02*
Y86274D01*
G01X1089843Y88874D02*
X1089143Y88174D01*
G01X1089843Y90974D02*
Y88874D01*
G01X1089143Y91674D02*
X1089843Y90974D01*
G01X1089143Y95956D02*
Y91674D01*
G01X1046258Y38151D02*
X1045911Y37804D01*
G01X1046258Y43323D02*
Y38151D01*
G01X1045692Y43889D02*
X1046258Y43323D01*
G01X1045692Y48074D02*
Y43889D01*
G01X1046192Y48574D02*
X1045692Y48074D01*
G01X1046192Y50474D02*
Y48574D01*
G01X1045853Y50813D02*
X1046192Y50474D01*
G01X1045853Y63247D02*
Y50813D01*
G01X1045692Y63408D02*
X1045853Y63247D01*
G01X1045692Y66759D02*
Y63408D01*
G01X1046292Y67359D02*
X1045692Y66759D01*
G01X1046292Y69357D02*
Y67359D01*
G01X1045692Y69957D02*
X1046292Y69357D01*
G01X1045692Y85874D02*
Y69957D01*
G01X1046192Y86374D02*
X1045692Y85874D01*
G01X1046192Y88274D02*
Y86374D01*
G01X1045492Y88974D02*
X1046192Y88274D01*
G01X1045492Y91074D02*
Y88974D01*
G01X1046223Y91805D02*
X1045492Y91074D01*
G01X1046223Y96839D02*
Y91805D01*
G01X1079489Y53806D02*
X1079372Y53689D01*
G01X1079489Y57276D02*
Y53806D01*
G01X1079384Y57381D02*
X1079489Y57276D01*
G01X1079384Y69732D02*
Y57381D01*
G01X1079157Y69959D02*
X1079384Y69732D01*
G01X1079157Y72459D02*
Y69959D01*
G01X1079372Y72674D02*
X1079157Y72459D01*
G01X1079372Y83727D02*
Y72674D01*
G01X1079157Y83942D02*
X1079372Y83727D01*
G01X1079157Y85874D02*
Y83942D01*
G01X1079657Y86374D02*
X1079157Y85874D01*
G01X1079657Y88274D02*
Y86374D01*
G01X1078957Y88974D02*
X1079657Y88274D01*
G01X1078957Y91074D02*
Y88974D01*
G01X1079688Y91805D02*
X1078957Y91074D01*
G01X1079688Y95012D02*
Y91805D01*
G01X1077074Y37796D02*
X1076124Y36846D01*
G01X1077074Y39572D02*
Y37796D01*
G01X1076464Y40182D02*
X1077074Y39572D01*
G01X1075245Y40182D02*
X1076464D01*
G01X1074635Y40792D02*
X1075245Y40182D01*
G01X1074635Y42182D02*
Y40792D01*
G01X1075245Y42792D02*
X1074635Y42182D01*
G01X1076464Y42792D02*
X1075245D01*
G01X1077074Y43402D02*
X1076464Y42792D01*
G01X1077074Y45076D02*
Y43402D01*
G01X1076149Y46001D02*
X1077074Y45076D01*
G01X1076149Y48082D02*
Y46001D01*
G01X1075757Y48474D02*
X1076149Y48082D01*
G01X1075757Y50374D02*
Y48474D01*
G01X1076457Y51074D02*
X1075757Y50374D01*
G01X1076457Y53174D02*
Y51074D01*
G01X1076037Y53594D02*
X1076457Y53174D01*
G01X1076037Y57357D02*
Y53594D01*
G01X1076129Y57449D02*
X1076037Y57357D01*
G01X1076129Y67087D02*
Y57449D01*
G01X1075757Y67459D02*
X1076129Y67087D01*
G01X1075757Y69459D02*
Y67459D01*
G01X1076357Y70059D02*
X1075757Y69459D01*
G01X1076357Y72359D02*
Y70059D01*
G01X1076119Y72597D02*
X1076357Y72359D01*
G01X1076119Y74625D02*
Y72597D01*
G01X1076928Y75434D02*
X1076119Y74625D01*
G01X1076928Y78568D02*
Y75434D01*
G01X1076318Y79178D02*
X1076928Y78568D01*
G01X1075039Y79178D02*
X1076318D01*
G01X1074466Y79751D02*
X1075039Y79178D01*
G01X1074466Y81141D02*
Y79751D01*
G01X1075113Y81788D02*
X1074466Y81141D01*
G01X1076318Y81788D02*
X1075113D01*
G01X1076928Y82398D02*
X1076318Y81788D01*
G01X1076928Y85103D02*
Y82398D01*
G01X1075757Y86274D02*
X1076928Y85103D01*
G01X1075757Y88174D02*
Y86274D01*
G01X1076457Y88874D02*
X1075757Y88174D01*
G01X1076457Y90974D02*
Y88874D01*
G01X1075900Y91531D02*
X1076457Y90974D01*
G01X1075900Y95700D02*
Y91531D01*
G01X1082836Y34780D02*
X1081381Y33325D01*
G01X1082836Y47895D02*
Y34780D01*
G01X1081356Y49375D02*
X1082836Y47895D01*
G01X1081356Y52465D02*
Y49375D01*
G01X1082711Y53820D02*
X1081356Y52465D01*
G01X1082711Y57731D02*
Y53820D01*
G01X1082830Y57850D02*
X1082711Y57731D01*
G01X1082830Y66786D02*
Y57850D01*
G01X1081331Y68285D02*
X1082830Y66786D01*
G01X1081331Y70985D02*
Y68285D01*
G01X1082818Y72472D02*
X1081331Y70985D01*
G01X1082818Y85713D02*
Y72472D01*
G01X1082057Y86474D02*
X1082818Y85713D01*
G01X1082057Y88224D02*
Y86474D01*
G01X1083057Y89224D02*
X1082057Y88224D01*
G01X1083057Y91274D02*
Y89224D01*
G01X1082100Y92231D02*
X1083057Y91274D01*
G01X1082100Y95599D02*
Y92231D01*
G01X1093109Y38735D02*
X1092865Y38491D01*
G01X1093109Y43323D02*
Y38735D01*
G01X1092846Y43586D02*
X1093109Y43323D01*
G01X1092846Y50433D02*
Y43586D01*
G01X1092343Y50936D02*
X1092846Y50433D01*
G01X1092343Y52742D02*
Y50936D01*
G01X1092857Y53256D02*
X1092343Y52742D01*
G01X1092857Y55822D02*
Y53256D01*
G01X1091722Y56957D02*
X1092857Y55822D01*
G01X1091722Y58435D02*
Y56957D01*
G01X1092438Y59151D02*
X1091722Y58435D01*
G01X1094023Y59151D02*
X1092438D01*
G01X1094633Y59761D02*
X1094023Y59151D01*
G01X1094633Y61151D02*
Y59761D01*
G01X1094023Y61761D02*
X1094633Y61151D01*
G01X1092536Y61761D02*
X1094023D01*
G01X1091837Y62460D02*
X1092536Y61761D01*
G01X1091837Y63896D02*
Y62460D01*
G01X1092857Y64916D02*
X1091837Y63896D01*
G01X1092857Y67860D02*
Y64916D01*
G01X1091965Y68752D02*
X1092857Y67860D01*
G01X1091965Y71227D02*
Y68752D01*
G01X1092857Y72119D02*
X1091965Y71227D01*
G01X1092857Y75443D02*
Y72119D01*
G01X1092543Y75757D02*
X1092857Y75443D01*
G01X1092543Y85874D02*
Y75757D01*
G01X1093043Y86374D02*
X1092543Y85874D01*
G01X1093043Y88274D02*
Y86374D01*
G01X1092343Y88974D02*
X1093043Y88274D01*
G01X1092343Y91074D02*
Y88974D01*
G01X1094531Y93262D02*
X1092343Y91074D01*
G01X1094531Y96828D02*
Y93262D01*
G01X1056689Y38463D02*
X1055960Y37734D01*
G01X1056689Y42749D02*
Y38463D01*
G01X1055952Y43486D02*
X1056689Y42749D01*
G01X1055952Y48007D02*
Y43486D01*
G01X1055285Y48674D02*
X1055952Y48007D01*
G01X1055285Y53162D02*
Y48674D01*
G01X1055941Y53818D02*
X1055285Y53162D01*
G01X1055941Y66903D02*
Y53818D01*
G01X1055285Y67559D02*
X1055941Y66903D01*
G01X1055285Y69259D02*
Y67559D01*
G01X1055940Y69914D02*
X1055285Y69259D01*
G01X1055940Y75514D02*
Y69914D01*
G01X1056285Y75859D02*
X1055940Y75514D01*
G01X1056285Y85474D02*
Y75859D01*
G01X1055285Y86474D02*
X1056285Y85474D01*
G01X1055285Y88224D02*
Y86474D01*
G01X1056590Y89529D02*
X1055285Y88224D01*
G01X1056590Y90969D02*
Y89529D01*
G01X1055285Y92274D02*
X1056590Y90969D01*
G01X1055285Y96267D02*
Y92274D01*
G01X1062766Y34764D02*
X1062971Y34559D01*
G01X1062766Y48079D02*
Y34764D01*
G01X1062371Y48474D02*
X1062766Y48079D01*
G01X1062371Y50374D02*
Y48474D01*
G01X1063071Y51074D02*
X1062371Y50374D01*
G01X1063071Y53174D02*
Y51074D01*
G01X1062730Y53515D02*
X1063071Y53174D01*
G01X1062730Y67100D02*
Y53515D01*
G01X1062971Y67341D02*
X1062730Y67100D01*
G01X1062971Y72359D02*
Y67341D01*
G01X1062695Y72635D02*
X1062971Y72359D01*
G01X1062695Y75083D02*
Y72635D01*
G01X1062971Y75359D02*
X1062695Y75083D01*
G01X1062971Y85674D02*
Y75359D01*
G01X1062371Y86274D02*
X1062971Y85674D01*
G01X1062371Y88174D02*
Y86274D01*
G01X1063071Y88874D02*
X1062371Y88174D01*
G01X1063071Y90974D02*
Y88874D01*
G01X1061874Y92171D02*
X1063071Y90974D01*
G01X1061874Y95898D02*
Y92171D01*
G01X1052706Y34980D02*
X1051883Y34157D01*
G01X1052706Y48395D02*
Y34980D01*
G01X1052885Y48574D02*
X1052706Y48395D01*
G01X1052885Y50474D02*
Y48574D01*
G01X1051956Y51403D02*
X1052885Y50474D01*
G01X1051956Y53045D02*
Y51403D01*
G01X1052717Y53806D02*
X1051956Y53045D01*
G01X1052717Y67091D02*
Y53806D01*
G01X1052985Y67359D02*
X1052717Y67091D01*
G01X1052985Y69359D02*
Y67359D01*
G01X1052101Y70243D02*
X1052985Y69359D01*
G01X1052101Y72175D02*
Y70243D01*
G01X1052622Y72696D02*
X1052101Y72175D01*
G01X1052622Y76878D02*
Y72696D01*
G01X1052385Y77115D02*
X1052622Y76878D01*
G01X1052385Y85874D02*
Y77115D01*
G01X1052885Y86374D02*
X1052385Y85874D01*
G01X1052885Y88274D02*
Y86374D01*
G01X1052079Y89080D02*
X1052885Y88274D01*
G01X1052079Y90968D02*
Y89080D01*
G01X1052916Y91805D02*
X1052079Y90968D01*
G01X1052916Y95806D02*
Y91805D01*
G01X1059384Y33700D02*
X1059871Y33213D01*
G01X1059384Y48087D02*
Y33700D01*
G01X1059671Y48374D02*
X1059384Y48087D01*
G01X1059671Y52746D02*
Y48374D01*
G01X1059315Y53102D02*
X1059671Y52746D01*
G01X1059315Y62352D02*
Y53102D01*
G01X1059383Y62420D02*
X1059315Y62352D01*
G01X1059383Y67271D02*
Y62420D01*
G01X1059871Y67759D02*
X1059383Y67271D01*
G01X1059871Y71787D02*
Y67759D01*
G01X1059399Y72259D02*
X1059871Y71787D01*
G01X1059399Y83446D02*
Y72259D01*
G01X1059071Y83774D02*
X1059399Y83446D01*
G01X1059071Y85574D02*
Y83774D01*
G01X1059671Y86174D02*
X1059071Y85574D01*
G01X1059671Y88374D02*
Y86174D01*
G01X1059071Y88974D02*
X1059671Y88374D01*
G01X1059071Y90974D02*
Y88974D01*
G01X1059774Y91677D02*
X1059071Y90974D01*
G01X1059774Y95168D02*
Y91677D01*
G01X1065771Y75929D02*
X1065989Y75711D01*
G01X1065771Y85874D02*
Y75929D01*
G01X1066271Y86374D02*
X1065771Y85874D01*
G01X1066271Y88274D02*
Y86374D01*
G01X1065853Y88692D02*
X1066271Y88274D01*
G01X1065853Y91356D02*
Y88692D01*
G01X1066302Y91805D02*
X1065853Y91356D01*
G01X1066302Y94299D02*
Y91805D01*
G01X1060627Y99974D02*
X1066302Y94299D01*
G01X1062348Y131840D02*
X1096443Y97745D01*
G01X1062348Y188712D02*
Y131840D01*
G01X1067000Y107381D02*
Y99399D01*
G01X1048240Y126141D02*
X1067000Y107381D01*
G01X1048240Y191296D02*
Y126141D01*
G01X1087800Y155300D02*
X1122400Y120700D01*
G01X1087800Y186200D02*
Y155300D01*
G01X1056240Y129461D02*
Y189743D01*
G01X1079800Y105901D02*
X1056240Y129461D01*
G01X1079800Y102299D02*
Y105901D01*
G01X1086443Y95656D02*
X1079800Y102299D01*
G01X1062627Y100873D02*
X1068671Y94829D01*
G01X1062627Y108924D02*
Y100873D01*
G01X1046240Y125311D02*
X1062627Y108924D01*
G01X1046240Y191585D02*
Y125311D01*
G01X1044600Y101292D02*
X1048985Y96907D01*
G01X1044600Y106170D02*
Y101292D01*
G01X1038564Y112206D02*
X1044600Y106170D01*
G01X1038564Y113338D02*
Y112206D01*
G01X1039247Y114021D02*
X1038564Y113338D01*
G01X1039247Y115153D02*
Y114021D01*
G01X1038116Y116284D02*
X1039247Y115153D01*
G01X1036984Y116284D02*
X1038116D01*
G01X1036301Y115601D02*
X1036984Y116284D01*
G01X1035169Y115601D02*
X1036301D01*
G01X1034240Y116530D02*
X1035169Y115601D01*
G01X1034240Y190071D02*
Y116530D01*
G01X1092100Y143199D02*
X1116999Y118300D01*
G01X1092100Y145000D02*
Y143199D01*
G01X1089190Y147910D02*
X1092100Y145000D01*
G01X1087389Y147910D02*
X1089190D01*
G01X1085900Y149399D02*
X1087389Y147910D01*
G01X1085900Y185900D02*
Y149399D01*
G01X1081900Y103199D02*
X1089143Y95956D01*
G01X1081900Y106630D02*
Y103199D01*
G01X1058240Y130290D02*
X1081900Y106630D01*
G01X1058240Y189343D02*
Y130290D01*
G01X1042600Y100462D02*
X1046223Y96839D01*
G01X1042600Y105340D02*
Y100462D01*
G01X1089905Y116195D02*
X1104400Y101700D01*
G01X1089905Y117057D02*
Y116195D01*
G01X1091343Y118495D02*
X1089905Y117057D01*
G01X1091343Y119357D02*
Y118495D01*
G01X1090359Y120341D02*
X1091343Y119357D01*
G01X1089497Y120341D02*
X1090359D01*
G01X1088059Y118903D02*
X1089497Y120341D01*
G01X1087197Y118903D02*
X1088059D01*
G01X1086213Y119887D02*
X1087197Y118903D01*
G01X1086213Y120749D02*
Y119887D01*
G01X1087651Y122187D02*
X1086213Y120749D01*
G01X1087651Y123049D02*
Y122187D01*
G01X1086667Y124033D02*
X1087651Y123049D01*
G01X1085805Y124033D02*
X1086667D01*
G01X1084367Y122595D02*
X1085805Y124033D01*
G01X1083505Y122595D02*
X1084367D01*
G01X1082521Y123579D02*
X1083505Y122595D01*
G01X1082521Y124441D02*
Y123579D01*
G01X1083959Y125879D02*
X1082521Y124441D01*
G01X1083959Y126741D02*
Y125879D01*
G01X1082975Y127725D02*
X1083959Y126741D01*
G01X1082113Y127725D02*
X1082975D01*
G01X1080675Y126287D02*
X1082113Y127725D01*
G01X1079813Y126287D02*
X1080675D01*
G01X1074300Y131800D02*
X1079813Y126287D01*
G01X1074300Y185300D02*
Y131800D01*
G01X1073100Y101600D02*
X1079688Y95012D01*
G01X1073100Y106941D02*
Y101600D01*
G01X1052240Y127801D02*
X1073100Y106941D01*
G01X1052240Y190520D02*
Y127801D01*
G01X1066800Y133299D02*
X1104299Y95800D01*
G01X1066800Y155406D02*
Y133299D01*
G01X1067410Y156016D02*
X1066800Y155406D01*
G01X1068590Y156016D02*
X1067410D01*
G01X1069200Y156626D02*
X1068590Y156016D01*
G01X1073088Y98512D02*
X1075900Y95700D01*
G01X1071324Y98512D02*
X1073088D01*
G01X1069206Y100630D02*
X1071324Y98512D01*
G01X1069206Y108005D02*
Y100630D01*
G01X1050240Y126971D02*
X1069206Y108005D01*
G01X1050240Y190799D02*
Y126971D01*
G01X1089700Y157500D02*
X1124000Y123200D01*
G01X1075200Y102499D02*
X1082100Y95599D01*
G01X1075200Y107671D02*
Y102499D01*
G01X1054240Y128631D02*
X1075200Y107671D01*
G01X1054240Y190277D02*
Y128631D01*
G01X1040600Y99632D02*
X1042300Y97932D01*
G01X1040600Y104510D02*
Y99632D01*
G01X1093577Y97782D02*
X1094531Y96828D01*
G01X1092447Y97782D02*
X1093577D01*
G01X1091899Y97234D02*
X1092447Y97782D01*
G01X1090768Y97234D02*
X1091899D01*
G01X1089635Y98367D02*
X1090768Y97234D01*
G01X1089635Y99497D02*
Y98367D01*
G01X1090184Y100045D02*
X1089635Y99497D01*
G01X1090184Y101175D02*
Y100045D01*
G01X1089051Y102308D02*
X1090184Y101175D01*
G01X1087921Y102308D02*
X1089051D01*
G01X1087373Y101760D02*
X1087921Y102308D01*
G01X1086242Y101760D02*
X1087373D01*
G01X1085109Y102893D02*
X1086242Y101760D01*
G01X1085109Y104023D02*
Y102893D01*
G01X1085658Y104571D02*
X1085109Y104023D01*
G01X1085658Y105701D02*
Y104571D01*
G01X1060240Y131119D02*
X1085658Y105701D01*
G01X1060240Y188943D02*
Y131119D01*
G01X1048600Y102952D02*
X1055285Y96267D01*
G01X1048600Y111632D02*
Y102952D01*
G01X1038240Y121992D02*
X1048600Y111632D01*
G01X1038240Y190084D02*
Y121992D01*
G01X1055900Y101872D02*
X1061874Y95898D01*
G01X1055900Y109992D02*
Y101872D01*
G01X1042240Y123652D02*
X1055900Y109992D01*
G01X1042240Y190218D02*
Y123652D01*
G01X1046600Y102122D02*
X1052916Y95806D01*
G01X1046600Y110802D02*
Y102122D01*
G01X1045760Y111642D02*
X1046600Y110802D01*
G01X1044628Y111642D02*
X1045760D01*
G01X1043859Y110873D02*
X1044628Y111642D01*
G01X1042727Y110873D02*
X1043859D01*
G01X1041596Y112004D02*
X1042727Y110873D01*
G01X1041596Y113136D02*
Y112004D01*
G01X1042365Y113905D02*
X1041596Y113136D01*
G01X1042365Y115037D02*
Y113905D01*
G01X1036240Y121162D02*
X1042365Y115037D01*
G01X1036240Y190168D02*
Y121162D01*
G01X1053900Y101042D02*
X1059774Y95168D01*
G01X1053900Y109162D02*
Y101042D01*
G01X1040240Y122822D02*
X1053900Y109162D01*
G01X1040240Y190240D02*
Y122822D01*
G01X1060627Y108094D02*
Y99974D01*
G01X1045360Y123360D02*
X1060627Y108094D01*
G01X1044240Y124481D02*
X1045360Y123360D01*
G01X1044240Y190266D02*
Y124481D01*
G01X1076200Y140800D02*
X1100664Y116336D01*
G01X1076200Y184999D02*
Y140800D01*
G01X1071300Y131700D02*
X1104900Y98100D01*
G01X1071300Y184700D02*
Y131700D01*
G01X1095160Y170526D02*
X1096640D01*
G01X1094600Y171086D02*
X1095160Y170526D01*
G01X1094600Y172526D02*
Y171086D01*
G01X1095160Y173086D02*
X1094600Y172526D01*
G01X1096640Y173086D02*
X1095160D01*
G01X1094700Y177471D02*
X1095310Y176861D01*
G01X1094700Y178861D02*
Y177471D01*
G01X1095310Y179471D02*
X1094700Y178861D01*
G01Y182691D02*
X1095310Y182081D01*
G01X1094700Y184081D02*
Y182691D01*
G01X1095310Y184691D02*
X1094700Y184081D01*
G01Y187911D02*
X1095310Y187301D01*
G01X1094700Y191310D02*
Y187911D01*
G01X1096826Y193436D02*
X1094700Y191310D01*
G01X1091600Y159800D02*
X1125400Y126000D01*
G01X1091600Y187097D02*
Y159800D01*
G01X1069200Y158016D02*
Y156626D01*
G01X1068590Y158626D02*
X1069200Y158016D01*
G01X1067410Y158626D02*
X1068590D01*
G01X1066800Y159236D02*
X1067410Y158626D01*
G01X1066800Y160626D02*
Y159236D01*
G01X1067410Y161236D02*
X1066800Y160626D01*
G01X1068590Y161236D02*
X1067410D01*
G01X1069200Y161846D02*
X1068590Y161236D01*
G01X1069200Y163236D02*
Y161846D01*
G01X1068590Y163846D02*
X1069200Y163236D01*
G01X1067410Y163846D02*
X1068590D01*
G01X1066800Y164456D02*
X1067410Y163846D01*
G01X1066800Y165846D02*
Y164456D01*
G01X1067410Y166456D02*
X1066800Y165846D01*
G01X1068590Y166456D02*
X1067410D01*
G01X1069200Y167066D02*
X1068590Y166456D01*
G01X1069200Y168456D02*
Y167066D01*
G01X1068590Y169066D02*
X1069200Y168456D01*
G01X1067410Y169066D02*
X1068590D01*
G01X1066800Y169676D02*
X1067410Y169066D01*
G01X1066800Y171066D02*
Y169676D01*
G01X1067410Y171676D02*
X1066800Y171066D01*
G01X1068590Y171676D02*
X1067410D01*
G01X1069200Y172286D02*
X1068590Y171676D01*
G01X1069200Y173676D02*
Y172286D01*
G01X1068590Y174286D02*
X1069200Y173676D01*
G01X1067410Y174286D02*
X1068590D01*
G01X1066800Y174896D02*
X1067410Y174286D01*
G01X1066800Y176286D02*
Y174896D01*
G01X1067410Y176896D02*
X1066800Y176286D01*
G01X1068590Y176896D02*
X1067410D01*
G01X1069200Y177506D02*
X1068590Y176896D01*
G01X1069200Y185535D02*
Y177506D01*
G01X1089700Y186600D02*
Y157500D01*
G01X1058100Y397100D02*
Y404200D01*
G01X1056600Y395600D02*
X1058100Y397100D01*
G01X1056600Y384300D02*
Y395600D01*
G01X1054600Y382300D02*
X1056600Y384300D01*
G01X1054600Y374845D02*
Y382300D01*
G01X1052664Y372909D02*
X1054600Y374845D01*
G01X1051800Y402300D02*
Y404200D01*
G01X1050700Y401200D02*
X1051800Y402300D01*
G01X1050700Y391800D02*
Y401200D01*
G01X1051300Y391200D02*
X1050700Y391800D01*
G01X1051300Y389700D02*
Y391200D01*
G01X1050634Y389034D02*
X1051300Y389700D01*
G01X1050634Y387966D02*
Y389034D01*
G01X1051200Y387400D02*
X1050634Y387966D01*
G01X1051200Y385800D02*
Y387400D01*
G01X1049900Y384500D02*
X1051200Y385800D01*
G01X1048500Y384500D02*
X1049900D01*
G01X1047300Y383300D02*
X1048500Y384500D01*
G01X1047300Y381900D02*
Y383300D01*
G01X1047800Y381400D02*
X1047300Y381900D01*
G01X1047800Y380000D02*
Y381400D01*
G01X1047300Y379500D02*
X1047800Y380000D01*
G01X1047300Y378100D02*
Y379500D01*
G01X1047800Y377600D02*
X1047300Y378100D01*
G01X1047800Y376100D02*
Y377600D01*
G01X1047400Y375700D02*
X1047800Y376100D01*
G01X1047400Y374100D02*
Y375700D01*
G01X1047800Y373700D02*
X1047400Y374100D01*
G01X1047800Y372100D02*
Y373700D01*
G01X1047400Y371700D02*
X1047800Y372100D01*
G01X1047400Y370200D02*
Y371700D01*
G01X1047800Y369800D02*
X1047400Y370200D01*
G01X1047800Y368200D02*
Y369800D01*
G01X1047266Y367666D02*
X1047800Y368200D01*
G01X1047266Y366534D02*
Y367666D01*
G01X1047800Y366000D02*
X1047266Y366534D01*
G01X1047800Y364400D02*
Y366000D01*
G01X1045904Y362504D02*
X1047800Y364400D01*
G01X1045904Y361209D02*
Y362504D01*
G01X1060100Y396310D02*
Y405016D01*
G01X1058700Y394910D02*
X1060100Y396310D01*
G01X1058700Y383300D02*
Y394910D01*
G01X1056500Y381100D02*
X1058700Y383300D01*
G01X1056500Y372846D02*
Y381100D01*
G01X1052664Y369010D02*
X1056500Y372846D01*
G01X1054000Y403000D02*
X1055000Y404000D01*
G01X1054000Y401600D02*
Y403000D01*
G01X1054600Y401000D02*
X1054000Y401600D01*
G01X1054600Y385200D02*
Y401000D01*
G01X1050800Y381400D02*
X1054600Y385200D01*
G01X1050800Y380000D02*
Y381400D01*
G01X1051200Y379600D02*
X1050800Y380000D01*
G01X1051200Y378000D02*
Y379600D01*
G01X1050800Y377600D02*
X1051200Y378000D01*
G01X1050800Y376100D02*
Y377600D01*
G01X1051300Y375600D02*
X1050800Y376100D01*
G01X1051300Y374100D02*
Y375600D01*
G01X1050800Y373600D02*
X1051300Y374100D01*
G01X1050800Y372200D02*
Y373600D01*
G01X1051400Y371600D02*
X1050800Y372200D01*
G01X1051400Y370300D02*
Y371600D01*
G01X1050800Y369700D02*
X1051400Y370300D01*
G01X1050800Y368576D02*
Y369700D01*
G01X1049284Y367060D02*
X1050800Y368576D01*
G01X1062493Y381693D02*
Y405453D01*
G01X1061400Y380600D02*
X1062493Y381693D01*
G01X1059900Y380600D02*
X1061400D01*
G01X1058500Y379200D02*
X1059900Y380600D01*
G01X1058500Y371800D02*
Y379200D01*
G01X1053800Y367100D02*
X1058500Y371800D01*
G01X1052000Y367100D02*
X1053800D01*
G01X1050450Y365550D02*
X1052000Y367100D01*
G01X1050450Y364326D02*
Y365550D01*
G01X1049284Y363160D02*
X1050450Y364326D01*
G01X1057000Y405300D02*
Y473258D01*
G01X1058100Y404200D02*
X1057000Y405300D01*
G01X1036800Y405200D02*
Y485434D01*
G01X1095036Y451925D02*
X1103557Y460446D01*
G01X1095036Y417407D02*
Y451925D01*
G01X1052900Y405300D02*
Y474816D01*
G01X1051800Y404200D02*
X1052900Y405300D01*
G01X1044900Y406265D02*
Y482218D01*
G01X1050900Y407111D02*
Y475645D01*
G01X1073556Y458156D02*
X1081216Y465816D01*
G01X1073556Y417187D02*
Y458156D01*
G01X1059000Y406116D02*
Y472429D01*
G01X1060100Y405016D02*
X1059000Y406116D01*
G01X1078656Y456056D02*
X1107059Y484459D01*
G01X1078656Y417287D02*
Y456056D01*
G01X1092106Y455006D02*
X1121944Y484844D01*
G01X1092106Y417467D02*
Y455006D01*
G01X1046900Y406829D02*
Y481389D01*
G01X1038800Y405821D02*
Y484605D01*
G01X1034800Y405100D02*
Y486263D01*
G01X1042900Y483047D02*
Y405741D01*
G01X1055000Y404000D02*
Y474087D01*
G01X1076106Y457106D02*
X1093993Y474993D01*
G01X1076106Y417287D02*
Y457106D01*
G01X1070657Y463457D02*
X1099522Y492322D01*
G01X1070657Y417187D02*
Y463457D01*
G01X1061000Y406946D02*
Y471600D01*
G01X1062493Y405453D02*
X1061000Y406946D01*
G01X1048900Y407111D02*
Y476474D01*
G01X1040866Y405606D02*
Y483842D01*
G01X1089200Y517000D02*
Y527700D01*
G01X1089600Y516600D02*
X1089200Y517000D01*
G01X1089600Y514600D02*
Y516600D01*
G01X1088800Y513800D02*
X1089600Y514600D01*
G01X1088800Y512000D02*
Y513800D01*
G01X1089595Y511205D02*
X1088800Y512000D01*
G01X1089595Y509367D02*
Y511205D01*
G01X1088562Y508334D02*
X1089595Y509367D01*
G01X1088063Y508334D02*
X1088562D01*
G01X1071389Y491660D02*
X1088063Y508334D01*
G01X1071389Y487647D02*
Y491660D01*
G01X1057000Y473258D02*
X1071389Y487647D01*
G01X1055949Y526349D02*
Y533049D01*
G01X1055400Y525800D02*
X1055949Y526349D01*
G01X1055400Y517400D02*
Y525800D01*
G01X1056095Y516705D02*
X1055400Y517400D01*
G01X1056095Y514195D02*
Y516705D01*
G01X1055761Y513861D02*
X1056095Y514195D01*
G01X1055761Y512139D02*
Y513861D01*
G01X1056122Y511778D02*
X1055761Y512139D01*
G01X1056122Y509222D02*
Y511778D01*
G01X1047300Y500400D02*
X1056122Y509222D01*
G01X1047300Y495960D02*
Y500400D01*
G01X1046481Y495141D02*
X1047300Y495960D01*
G01X1045377Y495141D02*
X1046481D01*
G01X1044140Y496378D02*
X1045377Y495141D01*
G01X1043218Y496378D02*
X1044140D01*
G01X1041988Y495148D02*
X1043218Y496378D01*
G01X1041988Y494004D02*
Y495148D01*
G01X1043113Y492879D02*
X1041988Y494004D01*
G01X1043113Y491747D02*
Y492879D01*
G01X1036800Y485434D02*
X1043113Y491747D01*
G01X1082821Y520621D02*
Y530555D01*
G01X1082600Y520400D02*
X1082821Y520621D01*
G01X1082600Y517000D02*
Y520400D01*
G01X1083000Y516600D02*
X1082600Y517000D01*
G01X1083000Y514700D02*
Y516600D01*
G01X1082500Y514200D02*
X1083000Y514700D01*
G01X1082500Y511700D02*
Y514200D01*
G01X1082900Y511300D02*
X1082500Y511700D01*
G01X1082900Y508900D02*
Y511300D01*
G01X1067389Y493389D02*
X1082900Y508900D01*
G01X1067389Y489305D02*
Y493389D01*
G01X1052900Y474816D02*
X1067389Y489305D01*
G01X1069436Y520536D02*
Y530064D01*
G01X1069100Y520200D02*
X1069436Y520536D01*
G01X1069100Y516900D02*
Y520200D01*
G01X1069989Y516011D02*
X1069100Y516900D01*
G01X1069989Y514321D02*
Y516011D01*
G01X1069000Y513332D02*
X1069989Y514321D01*
G01X1069000Y511700D02*
Y513332D01*
G01X1070579Y510121D02*
X1069000Y511700D01*
G01X1070579Y507897D02*
Y510121D01*
G01X1069462Y506780D02*
X1070579Y507897D01*
G01X1068330Y506780D02*
X1069462D01*
G01X1067871Y507239D02*
X1068330Y506780D01*
G01X1066739Y507239D02*
X1067871D01*
G01X1065608Y506108D02*
X1066739Y507239D01*
G01X1065608Y504976D02*
Y506108D01*
G01X1066067Y504517D02*
X1065608Y504976D01*
G01X1066067Y503385D02*
Y504517D01*
G01X1064936Y502254D02*
X1066067Y503385D01*
G01X1063804Y502254D02*
X1064936D01*
G01X1063345Y502713D02*
X1063804Y502254D01*
G01X1062213Y502713D02*
X1063345D01*
G01X1061082Y501582D02*
X1062213Y502713D01*
G01X1061082Y500450D02*
Y501582D01*
G01X1061541Y499991D02*
X1061082Y500450D01*
G01X1061541Y498859D02*
Y499991D01*
G01X1044900Y482218D02*
X1061541Y498859D01*
G01X1079800Y517100D02*
Y527300D01*
G01X1078917Y516217D02*
X1079800Y517100D01*
G01X1078917Y514483D02*
Y516217D01*
G01X1079886Y513514D02*
X1078917Y514483D01*
G01X1079886Y511886D02*
Y513514D01*
G01X1079000Y511000D02*
X1079886Y511886D01*
G01X1079000Y507830D02*
Y511000D01*
G01X1065389Y494219D02*
X1079000Y507830D01*
G01X1065389Y490134D02*
Y494219D01*
G01X1050900Y475645D02*
X1065389Y490134D01*
G01X1084494Y473694D02*
X1103854Y493054D01*
G01X1084494Y472736D02*
Y473694D01*
G01X1085749Y471481D02*
X1084494Y472736D01*
G01X1085749Y470349D02*
Y471481D01*
G01X1084611Y469211D02*
X1085749Y470349D01*
G01X1083479Y469211D02*
X1084611D01*
G01X1081885Y470805D02*
X1083479Y469211D01*
G01X1080731Y470805D02*
X1081885D01*
G01X1079600Y469674D02*
X1080731Y470805D01*
G01X1079600Y468564D02*
Y469674D01*
G01X1081216Y466948D02*
X1079600Y468564D01*
G01X1081216Y465816D02*
Y466948D01*
G01X1093300Y526100D02*
X1092856Y526544D01*
G01X1093300Y517100D02*
Y526100D01*
G01X1092400Y516200D02*
X1093300Y517100D01*
G01X1092400Y514800D02*
Y516200D01*
G01X1093300Y513900D02*
X1092400Y514800D01*
G01X1093300Y512000D02*
Y513900D01*
G01X1092600Y511300D02*
X1093300Y512000D01*
G01X1092600Y509154D02*
Y511300D01*
G01X1089813Y506367D02*
X1092600Y509154D01*
G01X1088925Y506367D02*
X1089813D01*
G01X1079426Y496868D02*
X1088925Y506367D01*
G01X1079426Y496006D02*
Y496868D01*
G01X1080359Y495073D02*
X1079426Y496006D01*
G01X1080359Y494211D02*
Y495073D01*
G01X1079375Y493227D02*
X1080359Y494211D01*
G01X1078513Y493227D02*
X1079375D01*
G01X1077580Y494160D02*
X1078513Y493227D01*
G01X1076718Y494160D02*
X1077580D01*
G01X1073389Y490831D02*
X1076718Y494160D01*
G01X1073389Y486818D02*
Y490831D01*
G01X1059000Y472429D02*
X1073389Y486818D01*
G01X1073300Y525900D02*
X1072669Y526531D01*
G01X1073300Y517600D02*
Y525900D01*
G01X1072642Y516942D02*
X1073300Y517600D01*
G01X1072642Y514358D02*
Y516942D01*
G01X1072925Y514075D02*
X1072642Y514358D01*
G01X1072925Y511625D02*
Y514075D01*
G01X1072400Y511100D02*
X1072925Y511625D01*
G01X1072400Y506889D02*
Y511100D01*
G01X1046900Y481389D02*
X1072400Y506889D01*
G01X1042400Y507170D02*
Y586502D01*
G01X1059416Y516516D02*
Y530616D01*
G01X1059100Y516200D02*
X1059416Y516516D01*
G01X1059100Y514400D02*
Y516200D01*
G01X1059900Y513600D02*
X1059100Y514400D01*
G01X1059900Y512000D02*
Y513600D01*
G01X1058900Y511000D02*
X1059900Y512000D01*
G01X1058900Y509171D02*
Y511000D01*
G01X1049300Y499571D02*
X1058900Y509171D01*
G01X1049300Y495105D02*
Y499571D01*
G01X1038800Y484605D02*
X1049300Y495105D01*
G01X1052658Y520542D02*
Y530158D01*
G01X1052800Y520400D02*
X1052658Y520542D01*
G01X1052800Y517000D02*
Y520400D01*
G01X1052400Y516600D02*
X1052800Y517000D01*
G01X1052400Y514500D02*
Y516600D01*
G01X1053200Y513700D02*
X1052400Y514500D01*
G01X1053200Y511900D02*
Y513700D01*
G01X1052400Y511100D02*
X1053200Y511900D01*
G01X1052400Y508683D02*
Y511100D01*
G01X1040368Y496651D02*
X1052400Y508683D01*
G01X1040368Y491831D02*
Y496651D01*
G01X1034800Y486263D02*
X1040368Y491831D01*
G01X1058700Y498847D02*
X1042900Y483047D01*
G01X1058700Y502415D02*
Y498847D01*
G01X1064950Y508665D02*
X1058700Y502415D01*
G01X1064950Y510686D02*
Y508665D01*
G01X1066259Y511995D02*
X1064950Y510686D01*
G01X1066259Y513841D02*
Y511995D01*
G01X1065700Y514400D02*
X1066259Y513841D01*
G01X1065700Y516300D02*
Y514400D01*
G01X1067000Y517600D02*
X1065700Y516300D01*
G01X1067000Y526200D02*
Y517600D01*
G01X1065999Y527201D02*
X1067000Y526200D01*
G01X1086499Y526301D02*
X1086082Y526718D01*
G01X1086499Y517399D02*
Y526301D01*
G01X1086017Y516917D02*
X1086499Y517399D01*
G01X1086017Y514083D02*
Y516917D01*
G01X1086258Y513842D02*
X1086017Y514083D01*
G01X1086258Y511858D02*
Y513842D01*
G01X1085900Y511500D02*
X1086258Y511858D01*
G01X1085900Y509000D02*
Y511500D01*
G01X1069389Y492489D02*
X1085900Y509000D01*
G01X1069389Y488476D02*
Y492489D01*
G01X1055000Y474087D02*
X1069389Y488476D01*
G01X1095088Y479556D02*
X1096256Y478388D01*
G01X1093956Y479556D02*
X1095088D01*
G01X1092825Y478425D02*
X1093956Y479556D01*
G01X1092825Y477293D02*
Y478425D01*
G01X1093993Y476125D02*
X1092825Y477293D01*
G01X1093993Y474993D02*
Y476125D01*
G01X1045915Y516515D02*
Y529791D01*
G01X1045748Y516348D02*
X1045915Y516515D01*
G01X1045748Y514352D02*
Y516348D01*
G01X1046151Y513949D02*
X1045748Y514352D01*
G01X1046151Y511363D02*
Y513949D01*
G01X1045700Y510912D02*
X1046151Y511363D01*
G01X1045700Y507641D02*
Y510912D01*
G01X1049100Y517100D02*
Y526700D01*
G01X1049494Y516706D02*
X1049100Y517100D01*
G01X1049494Y514186D02*
Y516706D01*
G01X1049010Y513702D02*
X1049494Y514186D01*
G01X1049010Y511590D02*
Y513702D01*
G01X1049466Y511134D02*
X1049010Y511590D01*
G01X1049466Y508578D02*
Y511134D01*
G01X1037195Y496307D02*
X1049466Y508578D01*
G01X1037195Y495175D02*
Y496307D01*
G01X1038318Y494052D02*
X1037195Y495175D01*
G01X1038318Y492920D02*
Y494052D01*
G01X1037187Y491789D02*
X1038318Y492920D01*
G01X1036055Y491789D02*
X1037187D01*
G01X1034932Y492912D02*
X1036055Y491789D01*
G01X1033800Y492912D02*
X1034932D01*
G01X1061000Y471600D02*
X1096351Y506951D01*
G01X1076152Y521552D02*
Y530248D01*
G01X1075700Y521100D02*
X1076152Y521552D01*
G01X1075700Y517200D02*
Y521100D01*
G01X1076300Y516600D02*
X1075700Y517200D01*
G01X1076300Y514500D02*
Y516600D01*
G01X1075600Y513800D02*
X1076300Y514500D01*
G01X1075600Y512000D02*
Y513800D01*
G01X1076300Y511300D02*
X1075600Y512000D01*
G01X1076300Y507960D02*
Y511300D01*
G01X1062418Y494078D02*
X1076300Y507960D01*
G01X1062418Y493092D02*
Y494078D01*
G01X1063389Y492121D02*
X1062418Y493092D01*
G01X1063389Y490989D02*
Y492121D01*
G01X1062141Y489741D02*
X1063389Y490989D01*
G01X1061243Y489741D02*
X1062141D01*
G01X1059889Y491095D02*
X1061243Y489741D01*
G01X1059020Y491095D02*
X1059889D01*
G01X1057632Y489707D02*
X1059020Y491095D01*
G01X1057632Y488826D02*
Y489707D01*
G01X1058863Y487595D02*
X1057632Y488826D01*
G01X1058863Y486463D02*
Y487595D01*
G01X1057663Y485263D02*
X1058863Y486463D01*
G01X1056669Y485263D02*
X1057663D01*
G01X1055405Y486527D02*
X1056669Y485263D01*
G01X1054349Y486527D02*
X1055405D01*
G01X1053069Y485247D02*
X1054349Y486527D01*
G01X1053069Y484337D02*
Y485247D01*
G01X1054384Y483022D02*
X1053069Y484337D01*
G01X1054384Y481930D02*
Y483022D01*
G01X1053195Y480741D02*
X1054384Y481930D01*
G01X1052139Y480741D02*
X1053195D01*
G01X1051196Y481684D02*
X1052139Y480741D01*
G01X1050044Y481684D02*
X1051196D01*
G01X1048901Y480541D02*
X1050044Y481684D01*
G01X1048901Y476475D02*
Y480541D01*
G01X1048900Y476474D02*
X1048901Y476475D01*
G01X1063734Y526266D02*
X1062649Y527351D01*
G01X1063734Y520534D02*
Y526266D01*
G01X1062585Y519385D02*
X1063734Y520534D01*
G01X1062585Y516615D02*
Y519385D01*
G01X1062881Y516319D02*
X1062585Y516615D01*
G01X1062881Y514281D02*
Y516319D01*
G01X1062522Y513922D02*
X1062881Y514281D01*
G01X1062522Y511578D02*
Y513922D01*
G01X1062761Y511339D02*
X1062522Y511578D01*
G01X1062761Y509305D02*
Y511339D01*
G01X1056700Y503244D02*
X1062761Y509305D01*
G01X1056700Y499717D02*
Y503244D01*
G01X1055927Y498944D02*
X1056700Y499717D01*
G01X1054782Y498944D02*
X1055927D01*
G01X1053930Y499796D02*
X1054782Y498944D01*
G01X1052824Y499796D02*
X1053930D01*
G01X1051693Y498665D02*
X1052824Y499796D01*
G01X1051693Y497507D02*
Y498665D01*
G01X1052546Y496654D02*
X1051693Y497507D01*
G01X1052546Y495522D02*
Y496654D01*
G01X1040866Y483842D02*
X1052546Y495522D01*
G01X1093400Y587500D02*
Y589876D01*
G01X1092856Y586956D02*
X1093400Y587500D01*
G01X1092856Y580056D02*
Y586956D01*
G01X1089418Y576618D02*
X1092856Y580056D01*
G01X1089418Y557436D02*
Y576618D01*
G01X1089427Y557427D02*
X1089418Y557436D01*
G01X1089427Y552127D02*
Y557427D01*
G01X1089418Y552118D02*
X1089427Y552127D01*
G01X1089418Y527918D02*
Y552118D01*
G01X1089200Y527700D02*
X1089418Y527918D01*
G01X1059401Y582977D02*
Y588867D01*
G01X1055964Y579540D02*
X1059401Y582977D01*
G01X1055964Y570664D02*
Y579540D01*
G01X1055953Y570653D02*
X1055964Y570664D01*
G01X1055953Y558105D02*
Y570653D01*
G01X1055979Y558079D02*
X1055953Y558105D01*
G01X1055979Y551879D02*
Y558079D01*
G01X1055963Y551863D02*
X1055979Y551879D01*
G01X1055963Y533063D02*
Y551863D01*
G01X1055949Y533049D02*
X1055963Y533063D01*
G01X1086127Y586827D02*
X1087795Y588495D01*
G01X1086127Y580227D02*
Y586827D01*
G01X1082822Y576922D02*
X1086127Y580227D01*
G01X1082822Y573530D02*
Y576922D01*
G01X1081350Y572058D02*
X1082822Y573530D01*
G01X1081350Y569022D02*
Y572058D01*
G01X1082823Y567549D02*
X1081350Y569022D01*
G01X1082823Y562323D02*
Y567549D01*
G01X1082733Y562233D02*
X1082823Y562323D01*
G01X1082733Y554467D02*
Y562233D01*
G01X1081381Y553115D02*
X1082733Y554467D01*
G01X1081381Y550419D02*
Y553115D01*
G01X1082822Y548978D02*
X1081381Y550419D01*
G01X1082822Y535678D02*
Y548978D01*
G01X1081278Y534134D02*
X1082822Y535678D01*
G01X1081278Y532098D02*
Y534134D01*
G01X1082821Y530555D02*
X1081278Y532098D01*
G01X1072683Y586883D02*
X1074409Y588609D01*
G01X1072683Y580883D02*
Y586883D01*
G01X1069437Y577637D02*
X1072683Y580883D01*
G01X1069437Y573563D02*
Y577637D01*
G01X1068900Y573026D02*
X1069437Y573563D01*
G01X1068900Y568500D02*
Y573026D01*
G01X1069451Y567949D02*
X1068900Y568500D01*
G01X1069451Y554819D02*
Y567949D01*
G01X1068908Y554276D02*
X1069451Y554819D01*
G01X1068908Y549992D02*
Y554276D01*
G01X1069422Y549478D02*
X1068908Y549992D01*
G01X1069422Y535678D02*
Y549478D01*
G01X1068908Y535164D02*
X1069422Y535678D01*
G01X1068908Y530592D02*
Y535164D01*
G01X1069436Y530064D02*
X1068908Y530592D01*
G01X1082836Y586900D02*
X1086185Y590249D01*
G01X1082836Y580136D02*
Y586900D01*
G01X1079377Y576677D02*
X1082836Y580136D01*
G01X1079377Y559429D02*
Y576677D01*
G01X1079471Y559335D02*
X1079377Y559429D01*
G01X1079471Y554571D02*
Y559335D01*
G01X1079369Y554469D02*
X1079471Y554571D01*
G01X1079369Y527731D02*
Y554469D01*
G01X1079800Y527300D02*
X1079369Y527731D01*
G01X1094488Y578288D02*
Y585722D01*
G01X1092856Y576656D02*
X1094488Y578288D01*
G01X1092856Y526544D02*
Y576656D01*
G01X1076136Y580836D02*
Y589536D01*
G01X1072684Y577384D02*
X1076136Y580836D01*
G01X1072684Y568284D02*
Y577384D01*
G01X1072669Y568269D02*
X1072684Y568284D01*
G01X1072669Y565031D02*
Y568269D01*
G01X1072757Y564943D02*
X1072669Y565031D01*
G01X1072757Y549157D02*
Y564943D01*
G01X1072698Y549098D02*
X1072757Y549157D01*
G01X1072698Y530498D02*
Y549098D01*
G01X1072669Y530469D02*
X1072698Y530498D01*
G01X1072669Y526531D02*
Y530469D01*
G01X1042400Y586502D02*
X1044290Y588392D01*
G01X1062707Y583009D02*
Y588857D01*
G01X1059388Y579690D02*
X1062707Y583009D01*
G01X1059388Y573992D02*
Y579690D01*
G01X1059653Y573727D02*
X1059388Y573992D01*
G01X1059653Y568753D02*
Y573727D01*
G01X1059416Y568516D02*
X1059653Y568753D01*
G01X1059416Y563984D02*
Y568516D01*
G01X1059314Y563882D02*
X1059416Y563984D01*
G01X1059314Y553385D02*
Y563882D01*
G01X1059500Y553199D02*
X1059314Y553385D01*
G01X1059500Y549400D02*
Y553199D01*
G01X1059401Y549301D02*
X1059500Y549400D01*
G01X1059401Y545699D02*
Y549301D01*
G01X1059800Y545300D02*
X1059401Y545699D01*
G01X1059800Y539358D02*
Y545300D01*
G01X1059401Y538959D02*
X1059800Y539358D01*
G01X1059401Y534375D02*
Y538959D01*
G01X1059600Y534176D02*
X1059401Y534375D01*
G01X1059600Y530800D02*
Y534176D01*
G01X1059416Y530616D02*
X1059600Y530800D01*
G01X1055949Y582881D02*
Y591914D01*
G01X1052643Y579575D02*
X1055949Y582881D01*
G01X1052643Y570657D02*
Y579575D01*
G01X1052687Y570613D02*
X1052643Y570657D01*
G01X1052687Y563813D02*
Y570613D01*
G01X1053000Y563500D02*
X1052687Y563813D01*
G01X1053000Y558048D02*
Y563500D01*
G01X1052717Y557765D02*
X1053000Y558048D01*
G01X1052717Y549317D02*
Y557765D01*
G01X1052629Y549229D02*
X1052717Y549317D01*
G01X1052629Y532871D02*
Y549229D01*
G01X1052800Y532700D02*
X1052629Y532871D01*
G01X1052800Y530300D02*
Y532700D01*
G01X1052658Y530158D02*
X1052800Y530300D01*
G01X1065999Y549199D02*
Y527201D01*
G01X1065984Y549214D02*
X1065999Y549199D01*
G01X1065984Y556598D02*
Y549214D01*
G01X1067100Y557714D02*
X1065984Y556598D01*
G01X1067100Y563700D02*
Y557714D01*
G01X1065999Y564801D02*
X1067100Y563700D01*
G01X1065999Y577999D02*
Y564801D01*
G01X1069400Y581400D02*
X1065999Y577999D01*
G01X1069400Y586348D02*
Y581400D01*
G01X1072690Y589638D02*
X1069400Y586348D01*
G01X1089433Y587067D02*
X1091283Y588917D01*
G01X1089433Y579833D02*
Y587067D01*
G01X1086127Y576527D02*
X1089433Y579833D01*
G01X1086127Y573627D02*
Y576527D01*
G01X1086070Y573570D02*
X1086127Y573627D01*
G01X1086070Y559030D02*
Y573570D01*
G01X1086156Y558944D02*
X1086070Y559030D01*
G01X1086156Y529856D02*
Y558944D01*
G01X1086082Y529782D02*
X1086156Y529856D01*
G01X1086082Y526718D02*
Y529782D01*
G01X1045914Y587014D02*
X1047637Y588737D01*
G01X1045914Y571086D02*
Y587014D01*
G01X1046105Y570895D02*
X1045914Y571086D01*
G01X1046105Y568305D02*
Y570895D01*
G01X1045802Y568002D02*
X1046105Y568305D01*
G01X1045802Y563978D02*
Y568002D01*
G01X1046017Y563763D02*
X1045802Y563978D01*
G01X1046017Y549517D02*
Y563763D01*
G01X1045800Y549300D02*
X1046017Y549517D01*
G01X1045800Y546200D02*
Y549300D01*
G01X1045929Y546071D02*
X1045800Y546200D01*
G01X1045929Y529805D02*
Y546071D01*
G01X1045915Y529791D02*
X1045929Y529805D01*
G01X1052607Y587207D02*
X1054331Y588931D01*
G01X1052607Y583079D02*
Y587207D01*
G01X1049352Y579824D02*
X1052607Y583079D01*
G01X1049352Y563408D02*
Y579824D01*
G01X1049949Y562811D02*
X1049352Y563408D01*
G01X1049949Y557649D02*
Y562811D01*
G01X1049264Y556964D02*
X1049949Y557649D01*
G01X1049264Y554436D02*
Y556964D01*
G01X1049355Y554345D02*
X1049264Y554436D01*
G01X1049355Y533055D02*
Y554345D01*
G01X1049352Y533052D02*
X1049355Y533055D01*
G01X1049352Y526952D02*
Y533052D01*
G01X1049100Y526700D02*
X1049352Y526952D01*
G01X1080400Y588000D02*
Y590262D01*
G01X1079385Y586985D02*
X1080400Y588000D01*
G01X1079385Y580385D02*
Y586985D01*
G01X1076136Y577136D02*
X1079385Y580385D01*
G01X1076136Y558636D02*
Y577136D01*
G01X1076048Y558548D02*
X1076136Y558636D01*
G01X1076048Y552048D02*
Y558548D01*
G01X1076122Y551974D02*
X1076048Y552048D01*
G01X1076122Y530278D02*
Y551974D01*
G01X1076152Y530248D02*
X1076122Y530278D01*
G01X1066006Y587357D02*
Y597094D01*
G01X1064371Y585722D02*
X1066006Y587357D01*
G01X1064371Y584116D02*
Y585722D01*
G01X1064981Y583506D02*
X1064371Y584116D01*
G01X1066253Y583506D02*
X1064981D01*
G01X1066889Y582870D02*
X1066253Y583506D01*
G01X1066889Y581480D02*
Y582870D01*
G01X1066305Y580896D02*
X1066889Y581480D01*
G01X1064108Y580896D02*
X1066305D01*
G01X1062678Y579466D02*
X1064108Y580896D01*
G01X1062678Y570478D02*
Y579466D01*
G01X1062708Y570448D02*
X1062678Y570478D01*
G01X1062708Y562471D02*
Y570448D01*
G01X1063469Y561710D02*
X1062708Y562471D01*
G01X1064473Y561710D02*
X1063469D01*
G01X1065125Y561058D02*
X1064473Y561710D01*
G01X1065125Y559144D02*
Y561058D01*
G01X1064491Y558510D02*
X1065125Y559144D01*
G01X1063557Y558510D02*
X1064491D01*
G01X1062751Y557704D02*
X1063557Y558510D01*
G01X1062751Y551651D02*
Y557704D01*
G01X1062737Y551637D02*
X1062751Y551651D01*
G01X1062737Y539537D02*
Y551637D01*
G01X1062649Y539449D02*
X1062737Y539537D01*
G01X1062649Y527351D02*
Y539449D01*
G01X1094488Y590964D02*
Y593659D01*
G01X1093400Y589876D02*
X1094488Y590964D01*
G01X1063500Y606423D02*
X1064369Y607292D01*
G01X1063500Y596166D02*
Y606423D01*
G01X1062751Y595417D02*
X1063500Y596166D01*
G01X1062751Y592217D02*
Y595417D01*
G01X1059401Y588867D02*
X1062751Y592217D01*
G01X1087795Y588495D02*
Y593659D01*
G01X1074409Y588609D02*
Y593642D01*
G01X1086185Y603004D02*
X1087795Y604614D01*
G01X1086185Y590249D02*
Y603004D01*
G01X1079486Y602883D02*
X1081102Y604499D01*
G01X1079486Y592886D02*
Y602883D01*
G01X1076136Y589536D02*
X1079486Y592886D01*
G01X1044290Y612657D02*
X1044291Y612658D01*
G01X1044290Y610010D02*
Y612657D01*
G01X1046017Y608283D02*
X1044290Y610010D01*
G01X1046017Y606417D02*
Y608283D01*
G01X1045665Y606065D02*
X1046017Y606417D01*
G01X1045665Y597097D02*
Y606065D01*
G01X1044290Y595722D02*
X1045665Y597097D01*
G01X1044290Y588392D02*
Y595722D01*
G01X1064371Y590521D02*
Y593657D01*
G01X1062707Y588857D02*
X1064371Y590521D01*
G01X1056382Y605998D02*
X1057676Y607292D01*
G01X1056382Y603487D02*
Y605998D01*
G01X1057274Y602595D02*
X1056382Y603487D01*
G01X1061079Y602595D02*
X1057274D01*
G01X1061724Y601950D02*
X1061079Y602595D01*
G01X1061724Y600462D02*
Y601950D01*
G01X1060969Y599707D02*
X1061724Y600462D01*
G01X1056162Y599707D02*
X1060969D01*
G01X1055426Y598971D02*
X1056162Y599707D01*
G01X1055426Y597065D02*
Y598971D01*
G01X1056143Y596348D02*
X1055426Y597065D01*
G01X1057177Y596348D02*
X1056143D01*
G01X1057677Y595848D02*
X1057177Y596348D01*
G01X1057677Y593642D02*
Y595848D01*
G01X1055949Y591914D02*
X1057677Y593642D01*
G01X1072690Y595793D02*
Y589638D01*
G01X1074409Y597512D02*
X1072690Y595793D01*
G01X1074409Y604614D02*
Y597512D01*
G01X1092857Y602983D02*
X1094488Y604614D01*
G01X1092857Y592857D02*
Y602983D01*
G01X1091283Y591283D02*
X1092857Y592857D01*
G01X1091283Y588917D02*
Y591283D01*
G01X1048139Y603997D02*
X1047637Y604499D01*
G01X1048139Y594144D02*
Y603997D01*
G01X1047637Y593642D02*
X1048139Y594144D01*
G01X1047637Y588737D02*
Y593642D01*
G01X1053751Y603920D02*
X1054330Y604499D01*
G01X1053751Y594237D02*
Y603920D01*
G01X1054331Y593657D02*
X1053751Y594237D01*
G01X1054331Y588931D02*
Y593657D01*
G01X1094488Y607312D02*
Y609864D01*
G01X1096700Y605100D02*
X1094488Y607312D01*
G01X1081102Y590964D02*
Y593642D01*
G01X1080400Y590262D02*
X1081102Y590964D01*
G01X1064369Y610061D02*
Y612657D01*
G01X1066169Y608261D02*
X1064369Y610061D01*
G01X1066169Y605769D02*
Y608261D01*
G01X1065916Y605516D02*
X1066169Y605769D01*
G01X1065916Y597184D02*
Y605516D01*
G01X1066006Y597094D02*
X1065916Y597184D01*
G01X1095427Y14911D02*
Y10061D01*
G01X1096600Y16084D02*
X1095427Y14911D01*
G01X1096600Y26258D02*
Y16084D01*
G01X1096097Y26761D02*
X1096600Y26258D01*
G01X1096097Y51894D02*
Y26761D01*
G01X1096443Y52240D02*
X1096097Y51894D01*
G01X1096443Y97745D02*
Y52240D01*
G01X1107874Y67821D02*
Y65699D01*
G01X1109753Y69700D02*
X1107874Y67821D01*
G01X1111153Y69700D02*
X1109753D01*
G01X1112609Y71156D02*
X1111153Y69700D01*
G01X1112609Y72500D02*
Y71156D01*
G01X1111993Y73116D02*
X1112609Y72500D01*
G01X1111993Y86241D02*
Y73116D01*
G01X1110520Y87714D02*
X1111993Y86241D01*
G01X1101181Y67253D02*
Y65699D01*
G01X1103428Y69500D02*
X1101181Y67253D01*
G01X1104652Y69500D02*
X1103428D01*
G01X1106228Y71076D02*
X1104652Y69500D01*
G01X1106228Y72700D02*
Y71076D01*
G01X1105453Y73475D02*
X1106228Y72700D01*
G01X1105453Y86488D02*
Y73475D01*
G01X1104227Y87714D02*
X1105453Y86488D01*
G01X1133078Y73467D02*
X1134645Y71900D01*
G01X1133078Y74668D02*
Y73467D01*
G01X1131720Y76026D02*
X1133078Y74668D01*
G01X1131720Y77399D02*
Y76026D01*
G01X1132920Y78599D02*
X1131720Y77399D01*
G01X1132920Y79725D02*
Y78599D01*
G01X1131720Y80925D02*
X1132920Y79725D01*
G01X1131720Y82500D02*
Y80925D01*
G01X1133520Y84300D02*
X1131720Y82500D01*
G01X1133520Y85358D02*
Y84300D01*
G01X1130178Y88700D02*
X1133520Y85358D01*
G01X1130178Y91636D02*
Y88700D01*
G01X1131299Y92757D02*
X1130178Y91636D01*
G01X1146464Y72367D02*
X1147331Y71500D01*
G01X1146464Y74668D02*
Y72367D01*
G01X1144831Y76301D02*
X1146464Y74668D01*
G01X1144831Y77600D02*
Y76301D01*
G01X1146181Y78950D02*
X1144831Y77600D01*
G01X1146181Y79850D02*
Y78950D01*
G01X1144931Y81100D02*
X1146181Y79850D01*
G01X1144931Y82299D02*
Y81100D01*
G01X1146464Y83832D02*
X1144931Y82299D01*
G01X1146464Y85800D02*
Y83832D01*
G01X1143564Y88700D02*
X1146464Y85800D01*
G01X1143564Y91636D02*
Y88700D01*
G01X1144685Y92757D02*
X1143564Y91636D01*
G01X1144685Y95515D02*
Y92757D01*
G01X1126478Y73374D02*
X1127952Y71900D01*
G01X1126478Y74468D02*
Y73374D01*
G01X1125045Y75901D02*
X1126478Y74468D01*
G01X1125045Y77124D02*
Y75901D01*
G01X1126545Y78624D02*
X1125045Y77124D01*
G01X1126545Y79976D02*
Y78624D01*
G01X1125045Y81476D02*
X1126545Y79976D01*
G01X1125045Y82599D02*
Y81476D01*
G01X1126720Y84274D02*
X1125045Y82599D01*
G01X1126720Y85659D02*
Y84274D01*
G01X1123678Y88701D02*
X1126720Y85659D01*
G01X1123678Y91829D02*
Y88701D01*
G01X1124606Y92757D02*
X1123678Y91829D01*
G01X1109653Y72367D02*
X1110520Y71500D01*
G01X1109653Y74668D02*
Y72367D01*
G01X1108020Y76301D02*
X1109653Y74668D01*
G01X1108020Y77600D02*
Y76301D01*
G01X1109370Y78950D02*
X1108020Y77600D01*
G01X1109370Y79850D02*
Y78950D01*
G01X1108120Y81100D02*
X1109370Y79850D01*
G01X1108120Y82299D02*
Y81100D01*
G01X1109653Y83832D02*
X1108120Y82299D01*
G01X1109653Y85800D02*
Y83832D01*
G01X1106753Y88700D02*
X1109653Y85800D01*
G01X1106753Y91636D02*
Y88700D01*
G01X1107874Y92757D02*
X1106753Y91636D01*
G01X1139864Y72588D02*
X1140952Y71500D01*
G01X1139864Y74468D02*
Y72588D01*
G01X1138431Y75901D02*
X1139864Y74468D01*
G01X1138431Y77100D02*
Y75901D01*
G01X1139931Y78600D02*
X1138431Y77100D01*
G01X1139931Y79800D02*
Y78600D01*
G01X1138481Y81250D02*
X1139931Y79800D01*
G01X1138481Y82649D02*
Y81250D01*
G01X1139864Y84032D02*
X1138481Y82649D01*
G01X1139864Y85901D02*
Y84032D01*
G01X1137064Y88701D02*
X1139864Y85901D01*
G01X1137064Y91829D02*
Y88701D01*
G01X1137992Y92757D02*
X1137064Y91829D01*
G01X1137975Y92774D02*
X1137992Y92757D01*
G01X1133961Y92774D02*
X1137975D01*
G01X1132178Y94557D02*
X1133961Y92774D01*
G01X1127964Y95800D02*
X1129207Y94557D01*
G01X1131299Y66953D02*
Y65699D01*
G01X1133846Y69500D02*
X1131299Y66953D01*
G01X1134846Y69500D02*
X1133846D01*
G01X1136646Y71300D02*
X1134846Y69500D01*
G01X1136646Y72700D02*
Y71300D01*
G01X1136034Y73312D02*
X1136646Y72700D01*
G01X1136034Y86325D02*
Y73312D01*
G01X1134645Y87714D02*
X1136034Y86325D01*
G01X1144685Y67821D02*
Y65699D01*
G01X1146564Y69700D02*
X1144685Y67821D01*
G01X1147964Y69700D02*
X1146564D01*
G01X1149420Y71156D02*
X1147964Y69700D01*
G01X1149420Y72500D02*
Y71156D01*
G01X1148804Y73116D02*
X1149420Y72500D01*
G01X1148804Y86241D02*
Y73116D01*
G01X1147331Y87714D02*
X1148804Y86241D01*
G01X1145424Y89621D02*
X1147331Y87714D01*
G01X1145424Y90924D02*
Y89621D01*
G01X1146674Y92174D02*
X1145424Y90924D01*
G01X1146674Y97026D02*
Y92174D01*
G01X1124606Y66953D02*
Y65699D01*
G01X1127153Y69500D02*
X1124606Y66953D01*
G01X1128153Y69500D02*
X1127153D01*
G01X1129953Y71300D02*
X1128153Y69500D01*
G01X1129953Y72700D02*
Y71300D01*
G01X1129341Y73312D02*
X1129953Y72700D01*
G01X1129341Y86325D02*
Y73312D01*
G01X1127952Y87714D02*
X1129341Y86325D01*
G01X1103053Y72588D02*
X1104141Y71500D01*
G01X1103053Y74468D02*
Y72588D01*
G01X1101620Y75901D02*
X1103053Y74468D01*
G01X1101620Y77100D02*
Y75901D01*
G01X1103120Y78600D02*
X1101620Y77100D01*
G01X1103120Y79800D02*
Y78600D01*
G01X1101670Y81250D02*
X1103120Y79800D01*
G01X1101670Y82649D02*
Y81250D01*
G01X1103053Y84032D02*
X1101670Y82649D01*
G01X1103053Y85901D02*
Y84032D01*
G01X1100253Y88701D02*
X1103053Y85901D01*
G01X1100253Y91829D02*
Y88701D01*
G01X1101181Y92757D02*
X1100253Y91829D01*
G01X1137992Y67253D02*
Y65699D01*
G01X1140239Y69500D02*
X1137992Y67253D01*
G01X1141463Y69500D02*
X1140239D01*
G01X1143039Y71076D02*
X1141463Y69500D01*
G01X1143039Y72700D02*
Y71076D01*
G01X1142264Y73475D02*
X1143039Y72700D01*
G01X1142264Y86488D02*
Y73475D01*
G01X1141038Y87714D02*
X1142264Y86488D01*
G01X1139188Y89564D02*
X1141038Y87714D01*
G01X1139188Y91238D02*
Y89564D01*
G01X1141274Y93324D02*
X1139188Y91238D01*
G01X1141274Y94174D02*
Y93324D01*
G01X1140774Y94674D02*
X1141274Y94174D01*
G01X1155900Y120700D02*
X1163462Y113138D01*
G01X1122400Y120700D02*
X1155900D01*
G01X1130401Y129100D02*
X1161000D01*
G01X1097200Y162301D02*
X1130401Y129100D01*
G01X1154500Y136700D02*
X1160000D01*
G01X1153300Y137900D02*
X1154500Y136700D01*
G01X1135400Y137900D02*
X1153300D01*
G01X1104476Y168824D02*
X1135400Y137900D01*
G01X1133601Y132500D02*
X1160699D01*
G01X1122550Y143551D02*
X1133601Y132500D01*
G01X1118950Y143551D02*
X1122550D01*
G01X1099200Y163301D02*
X1118950Y143551D01*
G01X1141900Y149900D02*
X1177400D01*
G01X1118166Y173634D02*
X1141900Y149900D01*
G01X1154764Y118300D02*
X1159500Y113564D01*
G01X1116999Y118300D02*
X1154764D01*
G01X1143726Y96474D02*
X1144685Y95515D01*
G01X1135353Y96474D02*
X1143726D01*
G01X1133670Y98157D02*
X1135353Y96474D01*
G01X1132679Y98157D02*
X1133670D01*
G01X1129136Y101700D02*
X1132679Y98157D01*
G01X1104400Y101700D02*
X1129136D01*
G01X1142999Y152000D02*
X1182056D01*
G01X1120716Y174283D02*
X1142999Y152000D01*
G01X1125400Y126000D02*
X1157674D01*
G01X1134498Y134600D02*
X1163100D01*
G01X1120814Y148284D02*
X1134498Y134600D01*
G01X1119952Y148284D02*
X1120814D01*
G01X1119031Y147363D02*
X1119952Y148284D01*
G01X1118238Y147363D02*
X1119031D01*
G01X1117185Y148416D02*
X1118238Y147363D01*
G01X1117185Y149209D02*
Y148416D01*
G01X1118106Y150130D02*
X1117185Y149209D01*
G01X1118106Y150992D02*
Y150130D01*
G01X1117122Y151976D02*
X1118106Y150992D01*
G01X1116260Y151976D02*
X1117122D01*
G01X1115324Y151039D02*
X1116260Y151976D01*
G01X1114462Y151039D02*
X1115324D01*
G01X1113478Y152023D02*
X1114462Y151039D01*
G01X1113478Y152885D02*
Y152023D01*
G01X1114414Y153822D02*
X1113478Y152885D01*
G01X1114414Y154684D02*
Y153822D01*
G01X1113430Y155668D02*
X1114414Y154684D01*
G01X1112568Y155668D02*
X1113430D01*
G01X1111632Y154731D02*
X1112568Y155668D01*
G01X1110770Y154731D02*
X1111632D01*
G01X1109786Y155715D02*
X1110770Y154731D01*
G01X1109786Y156577D02*
Y155715D01*
G01X1129207Y94557D02*
X1132178D01*
G01X1104299Y95800D02*
X1127964D01*
G01X1156937Y123200D02*
X1166125Y114012D01*
G01X1124000Y123200D02*
X1156937D01*
G01X1144199Y154200D02*
X1184100D01*
G01X1123266Y175133D02*
X1144199Y154200D01*
G01X1145400Y98300D02*
X1146674Y97026D01*
G01X1136073Y98300D02*
X1145400D01*
G01X1129473Y104900D02*
X1136073Y98300D01*
G01X1112100Y104900D02*
X1129473D01*
G01X1110756Y106244D02*
X1112100Y104900D01*
G01X1109894Y106244D02*
X1110756D01*
G01X1108506Y104856D02*
X1109894Y106244D01*
G01X1107644Y104856D02*
X1108506D01*
G01X1106660Y105840D02*
X1107644Y104856D01*
G01X1106660Y106702D02*
Y105840D01*
G01X1108048Y108090D02*
X1106660Y106702D01*
G01X1108048Y108952D02*
Y108090D01*
G01X1103372Y113628D02*
X1108048Y108952D01*
G01X1102172Y113628D02*
X1103372D01*
G01X1100664Y115136D02*
X1102172Y113628D01*
G01X1100664Y116336D02*
Y115136D01*
G01X1141200Y147900D02*
X1172499D01*
G01X1115616Y173484D02*
X1141200Y147900D01*
G01X1134607Y94674D02*
X1140774D01*
G01X1132924Y96357D02*
X1134607Y94674D01*
G01X1130943Y96357D02*
X1132924D01*
G01X1129200Y98100D02*
X1130943Y96357D01*
G01X1125801Y98100D02*
X1129200D01*
G01X1124201Y99700D02*
X1125801Y98100D01*
G01X1122399Y99700D02*
X1124201D01*
G01X1120799Y98100D02*
X1122399Y99700D01*
G01X1119401Y98100D02*
X1120799D01*
G01X1117801Y99700D02*
X1119401Y98100D01*
G01X1116399Y99700D02*
X1117801D01*
G01X1114799Y98100D02*
X1116399Y99700D01*
G01X1113109Y98100D02*
X1114799D01*
G01X1112209Y99000D02*
X1113109Y98100D01*
G01X1109799Y99000D02*
X1112209D01*
G01X1108899Y98100D02*
X1109799Y99000D01*
G01X1104900Y98100D02*
X1108899D01*
G01X1155242Y178859D02*
X1169801Y164300D01*
G01X1139241Y178859D02*
X1155242D01*
G01X1137900Y180200D02*
X1139241Y178859D01*
G01X1137900Y181201D02*
Y180200D01*
G01X1138460Y181761D02*
X1137900Y181201D01*
G01X1140540Y181761D02*
X1138460D01*
G01X1141100Y182321D02*
X1140540Y181761D01*
G01X1141100Y183761D02*
Y182321D01*
G01X1140540Y184321D02*
X1141100Y183761D01*
G01X1138460Y184321D02*
X1140540D01*
G01X1137900Y184881D02*
X1138460Y184321D01*
G01X1137900Y186654D02*
Y184881D01*
G01X1138510Y187264D02*
X1137900Y186654D01*
G01X1140090Y187264D02*
X1138510D01*
G01X1140700Y187874D02*
X1140090Y187264D01*
G01X1140700Y189264D02*
Y187874D01*
G01X1140090Y189874D02*
X1140700Y189264D01*
G01X1138510Y189874D02*
X1140090D01*
G01X1137900Y190484D02*
X1138510Y189874D01*
G01X1137900Y192801D02*
Y190484D01*
G01X1133000Y197701D02*
X1137900Y192801D01*
G01X1097200Y169966D02*
Y162301D01*
G01X1096640Y170526D02*
X1097200Y169966D01*
G01Y173646D02*
X1096640Y173086D01*
G01X1097200Y176251D02*
Y173646D01*
G01X1096590Y176861D02*
X1097200Y176251D01*
G01X1095310Y176861D02*
X1096590D01*
G01Y179471D02*
X1095310D01*
G01X1097200Y180081D02*
X1096590Y179471D01*
G01X1097200Y181471D02*
Y180081D01*
G01X1096590Y182081D02*
X1097200Y181471D01*
G01X1095310Y182081D02*
X1096590D01*
G01Y184691D02*
X1095310D01*
G01X1097200Y185301D02*
X1096590Y184691D01*
G01X1097200Y186691D02*
Y185301D01*
G01X1096590Y187301D02*
X1097200Y186691D01*
G01X1095310Y187301D02*
X1096590D01*
G01X1104476Y188936D02*
Y168824D01*
G01X1099200Y193260D02*
Y163301D01*
G01X1099376Y193436D02*
X1099200Y193260D01*
G01X1150705Y205294D02*
X1161344Y194655D01*
G01X1118166Y190596D02*
Y173634D01*
G01X1120716Y193596D02*
Y174283D01*
G01X1152601Y174800D02*
X1168901Y158500D01*
G01X1132601Y174800D02*
X1152601D01*
G01X1129300Y178101D02*
X1132601Y174800D01*
G01X1129300Y182107D02*
Y178101D01*
G01X1129910Y182717D02*
X1129300Y182107D01*
G01X1132690Y182717D02*
X1129910D01*
G01X1133300Y183327D02*
X1132690Y182717D01*
G01X1133300Y184717D02*
Y183327D01*
G01X1132690Y185327D02*
X1133300Y184717D01*
G01X1127510Y185327D02*
X1132690D01*
G01X1126900Y185937D02*
X1127510Y185327D01*
G01X1126900Y187327D02*
Y185937D01*
G01X1127510Y187937D02*
X1126900Y187327D01*
G01X1132890Y187937D02*
X1127510D01*
G01X1133500Y188547D02*
X1132890Y187937D01*
G01X1133500Y189937D02*
Y188547D01*
G01X1132890Y190547D02*
X1133500Y189937D01*
G01X1129910Y190547D02*
X1132890D01*
G01X1129300Y191157D02*
X1129910Y190547D01*
G01X1129300Y194501D02*
Y191157D01*
G01X1110722Y157514D02*
X1109786Y156577D01*
G01X1110722Y158376D02*
Y157514D01*
G01X1109738Y159360D02*
X1110722Y158376D01*
G01X1108876Y159360D02*
X1109738D01*
G01X1107940Y158423D02*
X1108876Y159360D01*
G01X1107078Y158423D02*
X1107940D01*
G01X1106094Y159407D02*
X1107078Y158423D01*
G01X1106094Y160269D02*
Y159407D01*
G01X1107030Y161206D02*
X1106094Y160269D01*
G01X1107030Y162068D02*
Y161206D01*
G01X1106046Y163052D02*
X1107030Y162068D01*
G01X1105184Y163052D02*
X1106046D01*
G01X1104248Y162115D02*
X1105184Y163052D01*
G01X1103386Y162115D02*
X1104248D01*
G01X1101926Y163575D02*
X1103386Y162115D01*
G01X1101926Y188936D02*
Y163575D01*
G01X1123266Y193596D02*
Y175133D01*
G01X1159684Y191216D02*
X1147000Y203900D01*
G01X1156857Y180744D02*
X1168201Y169400D01*
G01X1152756Y180744D02*
X1156857D01*
G01X1134600Y198900D02*
X1152756Y180744D01*
G01X1134600Y198962D02*
Y198900D01*
G01X1145200Y202900D02*
X1159500Y188600D01*
G01X1153726Y176974D02*
X1169000Y161700D01*
G01X1136927Y176974D02*
X1153726D01*
G01X1135500Y178401D02*
X1136927Y176974D01*
G01X1135500Y191601D02*
Y178401D01*
G01X1130800Y196301D02*
X1135500Y191601D01*
G01X1115616Y190596D02*
Y173484D01*
G01X1155484Y203316D02*
X1151900Y206900D01*
G01X1189700Y193500D02*
X1155484Y203316D01*
G01X1156812Y450762D02*
X1164024Y443550D01*
G01X1144084Y450762D02*
X1156812D01*
G01X1136725Y443403D02*
X1144084Y450762D01*
G01X1136725Y434725D02*
Y443403D01*
G01X1129200Y427200D02*
X1136725Y434725D01*
G01X1129200Y418777D02*
Y427200D01*
G01X1128700Y418277D02*
X1129200Y418777D01*
G01X1141598Y456461D02*
X1160363D01*
G01X1128900Y443763D02*
X1141598Y456461D01*
G01X1128900Y440100D02*
Y443763D01*
G01X1121276Y432476D02*
X1128900Y440100D01*
G01X1121276Y418391D02*
Y432476D01*
G01X1122888Y464619D02*
X1122019Y465487D01*
G01X1122888Y463489D02*
Y464619D01*
G01X1121755Y462356D02*
X1122888Y463489D01*
G01X1120625Y462356D02*
X1121755D01*
G01X1119756Y463224D02*
X1120625Y462356D01*
G01X1118626Y463224D02*
X1119756D01*
G01X1117493Y462091D02*
X1118626Y463224D01*
G01X1117493Y460961D02*
Y462091D01*
G01X1118362Y460093D02*
X1117493Y460961D01*
G01X1118362Y458963D02*
Y460093D01*
G01X1103676Y444277D02*
X1118362Y458963D01*
G01X1103676Y414736D02*
Y444277D01*
G01X1143160Y452691D02*
X1157795D01*
G01X1133400Y442931D02*
X1143160Y452691D01*
G01X1133400Y435700D02*
Y442931D01*
G01X1127122Y429422D02*
X1133400Y435700D01*
G01X1127122Y420136D02*
Y429422D01*
G01X1106682Y463581D02*
X1108083Y464982D01*
G01X1105820Y463581D02*
X1106682D01*
G01X1105232Y464169D02*
X1105820Y463581D01*
G01X1104370Y464169D02*
X1105232D01*
G01X1102969Y462768D02*
X1104370Y464169D01*
G01X1102969Y461906D02*
Y462768D01*
G01X1103557Y461318D02*
X1102969Y461906D01*
G01X1103557Y460446D02*
Y461318D01*
G01X1117850Y450649D02*
X1135545Y468344D01*
G01X1117850Y445851D02*
Y450649D01*
G01X1108776Y436777D02*
X1117850Y445851D01*
G01X1108776Y415450D02*
Y436777D01*
G01X1154400Y429100D02*
X1160000Y434700D01*
G01X1147200Y429100D02*
X1154400D01*
G01X1141600Y423500D02*
X1147200Y429100D01*
G01X1156745Y423445D02*
X1161600Y428300D01*
G01X1150957Y423445D02*
X1156745D01*
G01X1147062Y419550D02*
X1150957Y423445D01*
G01X1113937Y450937D02*
X1133844Y470844D01*
G01X1113937Y449687D02*
Y450937D01*
G01X1115749Y447875D02*
X1113937Y449687D01*
G01X1115749Y447013D02*
Y447875D01*
G01X1114348Y445612D02*
X1115749Y447013D01*
G01X1113486Y445612D02*
X1114348D01*
G01X1111150Y447948D02*
X1113486Y445612D01*
G01X1110244Y447948D02*
X1111150D01*
G01X1108508Y446212D02*
X1110244Y447948D01*
G01X1108508Y445439D02*
Y446212D01*
G01X1110500Y443447D02*
X1108508Y445439D01*
G01X1110500Y442194D02*
Y443447D01*
G01X1106226Y437920D02*
X1110500Y442194D01*
G01X1106226Y414706D02*
Y437920D01*
G01X1097700Y451899D02*
X1125645Y479844D01*
G01X1097700Y417141D02*
Y451899D01*
G01X1120000Y449100D02*
X1136744Y465844D01*
G01X1120000Y444800D02*
Y449100D01*
G01X1111326Y436126D02*
X1120000Y444800D01*
G01X1111326Y415485D02*
Y436126D01*
G01X1155964Y425330D02*
X1160834Y430200D01*
G01X1149580Y425330D02*
X1155964D01*
G01X1145400Y421150D02*
X1149580Y425330D01*
G01X1155182Y427215D02*
X1160167Y432200D01*
G01X1148565Y427215D02*
X1155182D01*
G01X1143300Y421950D02*
X1148565Y427215D01*
G01X1113498Y464134D02*
Y464996D01*
G01X1113885Y463746D02*
X1113498Y464134D01*
G01X1113885Y462884D02*
Y463746D01*
G01X1112484Y461483D02*
X1113885Y462884D01*
G01X1111623Y461483D02*
X1112484D01*
G01X1111235Y461871D02*
X1111623Y461483D01*
G01X1110373Y461871D02*
X1111235D01*
G01X1108972Y460470D02*
X1110373Y461871D01*
G01X1108972Y459608D02*
Y460470D01*
G01X1109359Y459220D02*
X1108972Y459608D01*
G01X1109359Y458358D02*
Y459220D01*
G01X1107958Y456957D02*
X1109359Y458358D01*
G01X1107097Y456957D02*
X1107958D01*
G01X1106709Y457345D02*
X1107097Y456957D01*
G01X1105847Y457345D02*
X1106709D01*
G01X1103693Y455191D02*
X1105847Y457345D01*
G01X1103693Y454329D02*
Y455191D01*
G01X1104991Y453031D02*
X1103693Y454329D01*
G01X1104991Y452169D02*
Y453031D01*
G01X1104007Y451185D02*
X1104991Y452169D01*
G01X1103145Y451185D02*
X1104007D01*
G01X1101847Y452483D02*
X1103145Y451185D01*
G01X1100985Y452483D02*
X1101847D01*
G01X1100274Y451772D02*
X1100985Y452483D01*
G01X1100274Y417141D02*
Y451772D01*
G01X1142379Y454576D02*
X1158904D01*
G01X1131000Y443197D02*
X1142379Y454576D01*
G01X1131000Y437600D02*
Y443197D01*
G01X1123826Y430426D02*
X1131000Y437600D01*
G01X1123826Y419224D02*
Y430426D01*
G01X1122901Y519862D02*
X1124606Y518157D01*
G01X1122901Y530049D02*
Y519862D01*
G01X1110432Y513114D02*
X1110520D01*
G01X1108746Y514800D02*
X1110432Y513114D01*
G01X1108746Y516492D02*
Y514800D01*
G01X1109653Y517399D02*
X1108746Y516492D01*
G01X1109653Y518992D02*
Y517399D01*
G01X1108509Y520136D02*
X1109653Y518992D01*
G01X1108509Y521556D02*
Y520136D01*
G01X1109353Y522400D02*
X1108509Y521556D01*
G01X1109353Y524100D02*
Y522400D01*
G01X1108509Y524944D02*
X1109353Y524100D01*
G01X1108509Y526156D02*
Y524944D01*
G01X1109453Y527100D02*
X1108509Y526156D01*
G01X1132743Y473344D02*
X1164244D01*
G01X1130807Y471408D02*
X1132743Y473344D01*
G01X1129677Y471408D02*
X1130807D01*
G01X1128808Y472276D02*
X1129677Y471408D01*
G01X1127678Y472276D02*
X1128808D01*
G01X1126545Y471143D02*
X1127678Y472276D01*
G01X1126545Y470013D02*
Y471143D01*
G01X1127414Y469145D02*
X1126545Y470013D01*
G01X1127414Y468015D02*
Y469145D01*
G01X1126281Y466882D02*
X1127414Y468015D01*
G01X1125151Y466882D02*
X1126281D01*
G01X1124282Y467750D02*
X1125151Y466882D01*
G01X1123152Y467750D02*
X1124282D01*
G01X1122019Y466617D02*
X1123152Y467750D01*
G01X1122019Y465487D02*
Y466617D01*
G01X1106169Y519862D02*
X1107874Y518157D01*
G01X1106169Y531515D02*
Y519862D01*
G01X1104139Y513114D02*
X1104227D01*
G01X1102453Y514800D02*
X1104139Y513114D01*
G01X1102453Y517000D02*
Y514800D01*
G01X1102953Y517500D02*
X1102453Y517000D01*
G01X1102953Y519399D02*
Y517500D01*
G01X1101816Y520536D02*
X1102953Y519399D01*
G01X1101816Y521864D02*
Y520536D01*
G01X1102753Y522801D02*
X1101816Y521864D01*
G01X1102753Y524199D02*
Y522801D01*
G01X1101816Y525136D02*
X1102753Y524199D01*
G01X1101816Y526364D02*
Y525136D01*
G01X1102853Y527401D02*
X1101816Y526364D01*
G01X1122545Y482344D02*
X1160243D01*
G01X1121073Y480872D02*
X1122545Y482344D01*
G01X1121073Y480010D02*
Y480872D01*
G01X1121661Y479422D02*
X1121073Y480010D01*
G01X1121661Y478560D02*
Y479422D01*
G01X1120260Y477159D02*
X1121661Y478560D01*
G01X1119398Y477159D02*
X1120260D01*
G01X1118810Y477747D02*
X1119398Y477159D01*
G01X1117948Y477747D02*
X1118810D01*
G01X1116547Y476346D02*
X1117948Y477747D01*
G01X1116547Y475484D02*
Y476346D01*
G01X1117135Y474896D02*
X1116547Y475484D01*
G01X1117135Y474034D02*
Y474896D01*
G01X1115734Y472633D02*
X1117135Y474034D01*
G01X1114872Y472633D02*
X1115734D01*
G01X1114284Y473221D02*
X1114872Y472633D01*
G01X1113422Y473221D02*
X1114284D01*
G01X1112021Y471820D02*
X1113422Y473221D01*
G01X1112021Y470958D02*
Y471820D01*
G01X1112609Y470370D02*
X1112021Y470958D01*
G01X1112609Y469508D02*
Y470370D01*
G01X1111208Y468107D02*
X1112609Y469508D01*
G01X1110346Y468107D02*
X1111208D01*
G01X1109758Y468695D02*
X1110346Y468107D01*
G01X1108896Y468695D02*
X1109758D01*
G01X1107495Y467294D02*
X1108896Y468695D01*
G01X1107495Y466432D02*
Y467294D01*
G01X1108083Y465844D02*
X1107495Y466432D01*
G01X1108083Y464982D02*
Y465844D01*
G01X1135545Y468344D02*
X1175960D01*
G01X1138627Y526364D02*
X1139664Y527401D01*
G01X1138627Y525136D02*
Y526364D01*
G01X1139564Y524199D02*
X1138627Y525136D01*
G01X1139564Y522801D02*
Y524199D01*
G01X1138627Y521864D02*
X1139564Y522801D01*
G01X1138627Y520536D02*
Y521864D01*
G01X1139764Y519399D02*
X1138627Y520536D01*
G01X1139764Y517500D02*
Y519399D01*
G01X1139264Y517000D02*
X1139764Y517500D01*
G01X1139264Y514800D02*
Y517000D01*
G01X1140950Y513114D02*
X1139264Y514800D01*
G01X1141038Y513114D02*
X1140950D01*
G01X1140400Y512476D02*
X1141038Y513114D01*
G01X1140400Y509114D02*
Y512476D01*
G01X1139600Y508314D02*
X1140400Y509114D01*
G01X1130214Y508314D02*
X1139600D01*
G01X1125100Y503200D02*
X1130214Y508314D01*
G01X1114000Y503200D02*
X1125100D01*
G01X1111775Y500975D02*
X1114000Y503200D01*
G01X1110643Y500975D02*
X1111775D01*
G01X1109124Y502494D02*
X1110643Y500975D01*
G01X1107992Y502494D02*
X1109124D01*
G01X1106861Y501363D02*
X1107992Y502494D01*
G01X1106861Y500231D02*
Y501363D01*
G01X1108380Y498712D02*
X1106861Y500231D01*
G01X1108380Y497580D02*
Y498712D01*
G01X1107249Y496449D02*
X1108380Y497580D01*
G01X1106117Y496449D02*
X1107249D01*
G01X1104356Y498210D02*
X1106117Y496449D01*
G01X1103224Y498210D02*
X1104356D01*
G01X1102093Y497079D02*
X1103224Y498210D01*
G01X1102093Y495947D02*
Y497079D01*
G01X1103854Y494186D02*
X1102093Y495947D01*
G01X1103854Y493054D02*
Y494186D01*
G01X1145320Y526156D02*
X1146264Y527100D01*
G01X1145320Y524944D02*
Y526156D01*
G01X1146164Y524100D02*
X1145320Y524944D01*
G01X1146164Y522400D02*
Y524100D01*
G01X1145320Y521556D02*
X1146164Y522400D01*
G01X1145320Y520136D02*
Y521556D01*
G01X1146464Y518992D02*
X1145320Y520136D01*
G01X1146464Y517399D02*
Y518992D01*
G01X1145557Y516492D02*
X1146464Y517399D01*
G01X1145557Y514800D02*
Y516492D01*
G01X1147243Y513114D02*
X1145557Y514800D01*
G01X1147331Y513114D02*
X1147243D01*
G01X1147650D02*
X1147331D01*
G01X1148800Y511964D02*
X1147650Y513114D01*
G01X1148800Y510832D02*
Y511964D01*
G01X1148000Y510032D02*
X1148800Y510832D01*
G01X1146800Y510032D02*
X1148000D01*
G01X1146100Y509332D02*
X1146800Y510032D01*
G01X1146100Y508200D02*
Y509332D01*
G01X1146900Y507400D02*
X1146100Y508200D01*
G01X1150100Y507400D02*
X1146900D01*
G01X1150680Y506820D02*
X1150100Y507400D01*
G01X1150680Y505280D02*
Y506820D01*
G01X1150114Y504714D02*
X1150680Y505280D01*
G01X1134113Y504714D02*
X1150114D01*
G01X1127499Y498100D02*
X1134113Y504714D01*
G01X1115974Y498100D02*
X1127499D01*
G01X1114891Y497017D02*
X1115974Y498100D01*
G01X1114891Y495863D02*
Y497017D01*
G01X1116555Y494199D02*
X1114891Y495863D01*
G01X1116555Y493067D02*
Y494199D01*
G01X1115424Y491936D02*
X1116555Y493067D01*
G01X1114292Y491936D02*
X1115424D01*
G01X1112606Y493622D02*
X1114292Y491936D01*
G01X1111474Y493622D02*
X1112606D01*
G01X1110343Y492491D02*
X1111474Y493622D01*
G01X1110343Y491359D02*
Y492491D01*
G01X1111897Y489805D02*
X1110343Y491359D01*
G01X1111897Y488673D02*
Y489805D01*
G01X1110766Y487542D02*
X1111897Y488673D01*
G01X1109634Y487542D02*
X1110766D01*
G01X1108014Y489162D02*
X1109634Y487542D01*
G01X1106882Y489162D02*
X1108014D01*
G01X1105751Y488031D02*
X1106882Y489162D01*
G01X1105751Y486899D02*
Y488031D01*
G01X1107059Y485591D02*
X1105751Y486899D01*
G01X1107059Y484459D02*
Y485591D01*
G01X1121944Y484844D02*
X1159144D01*
G01X1133844Y470844D02*
X1165345D01*
G01X1125645Y479844D02*
X1161343D01*
G01X1136744Y465844D02*
X1176944D01*
G01X1125846Y477344D02*
X1162543D01*
G01X1122550Y474048D02*
X1125846Y477344D01*
G01X1122550Y473186D02*
Y474048D01*
G01X1122937Y472798D02*
X1122550Y473186D01*
G01X1122937Y471936D02*
Y472798D01*
G01X1121536Y470535D02*
X1122937Y471936D01*
G01X1120675Y470535D02*
X1121536D01*
G01X1120287Y470923D02*
X1120675Y470535D01*
G01X1119425Y470923D02*
X1120287D01*
G01X1118024Y469522D02*
X1119425Y470923D01*
G01X1118024Y468660D02*
Y469522D01*
G01X1118411Y468272D02*
X1118024Y468660D01*
G01X1118411Y467410D02*
Y468272D01*
G01X1117010Y466009D02*
X1118411Y467410D01*
G01X1116149Y466009D02*
X1117010D01*
G01X1115761Y466397D02*
X1116149Y466009D01*
G01X1114899Y466397D02*
X1115761D01*
G01X1113498Y464996D02*
X1114899Y466397D01*
G01X1129594Y519862D02*
X1131299Y518157D01*
G01X1129594Y530049D02*
Y519862D01*
G01X1099476D02*
X1101181Y518157D01*
G01X1099476Y529835D02*
Y519862D01*
G01X1142980D02*
Y531515D01*
G01X1144685Y518157D02*
X1142980Y519862D01*
G01X1144001Y518157D02*
X1144685D01*
G01X1143200Y517356D02*
X1144001Y518157D01*
G01X1143200Y511975D02*
Y517356D01*
G01X1142400Y511175D02*
X1143200Y511975D01*
G01X1142400Y507800D02*
Y511175D01*
G01X1141114Y506514D02*
X1142400Y507800D01*
G01X1132113Y506514D02*
X1141114D01*
G01X1126199Y500600D02*
X1132113Y506514D01*
G01X1115300Y500600D02*
X1126199D01*
G01X1102027Y487327D02*
X1115300Y500600D01*
G01X1102027Y486195D02*
Y487327D01*
G01X1102995Y485227D02*
X1102027Y486195D01*
G01X1102995Y484095D02*
Y485227D01*
G01X1101864Y482964D02*
X1102995Y484095D01*
G01X1100732Y482964D02*
X1101864D01*
G01X1099714Y483982D02*
X1100732Y482964D01*
G01X1098582Y483982D02*
X1099714D01*
G01X1097451Y482851D02*
X1098582Y483982D01*
G01X1097451Y481719D02*
Y482851D01*
G01X1098519Y480651D02*
X1097451Y481719D01*
G01X1098519Y479519D02*
Y480651D01*
G01X1097388Y478388D02*
X1098519Y479519D01*
G01X1096256Y478388D02*
X1097388D01*
G01X1136287Y519862D02*
Y529835D01*
G01X1137992Y518157D02*
X1136287Y519862D01*
G01X1137200Y517365D02*
X1137992Y518157D01*
G01X1137200Y512800D02*
Y517365D01*
G01X1135452Y511052D02*
X1137200Y512800D01*
G01X1133174Y511052D02*
X1135452D01*
G01X1132274Y511952D02*
X1133174Y511052D01*
G01X1130374Y511952D02*
X1132274D01*
G01X1123522Y505100D02*
X1130374Y511952D01*
G01X1121094Y505100D02*
X1123522D01*
G01X1120484Y505710D02*
X1121094Y505100D01*
G01X1120484Y507807D02*
Y505710D01*
G01X1119896Y508395D02*
X1120484Y507807D01*
G01X1118506Y508395D02*
X1119896D01*
G01X1117874Y507763D02*
X1118506Y508395D01*
G01X1117874Y505710D02*
Y507763D01*
G01X1117264Y505100D02*
X1117874Y505710D01*
G01X1115874Y505100D02*
X1117264D01*
G01X1115264Y505710D02*
X1115874Y505100D01*
G01X1115264Y506970D02*
Y505710D01*
G01X1114654Y507580D02*
X1115264Y506970D01*
G01X1113264Y507580D02*
X1114654D01*
G01X1112654Y506970D02*
X1113264Y507580D01*
G01X1112654Y505710D02*
Y506970D01*
G01X1112044Y505100D02*
X1112654Y505710D01*
G01X1107294Y505100D02*
X1112044D01*
G01X1099522Y497328D02*
X1107294Y505100D01*
G01X1099522Y492322D02*
Y497328D01*
G01X1127864Y513114D02*
X1127952D01*
G01X1126178Y514800D02*
X1127864Y513114D01*
G01X1126178Y516492D02*
Y514800D01*
G01X1126353Y516667D02*
X1126178Y516492D01*
G01X1126353Y519300D02*
Y516667D01*
G01X1125241Y520412D02*
X1126353Y519300D01*
G01X1125241Y521488D02*
Y520412D01*
G01X1126253Y522500D02*
X1125241Y521488D01*
G01X1126253Y523700D02*
Y522500D01*
G01X1125241Y524712D02*
X1126253Y523700D01*
G01X1125241Y525788D02*
Y524712D01*
G01X1126378Y526925D02*
X1125241Y525788D01*
G01X1096093Y517607D02*
Y533293D01*
G01X1096500Y517200D02*
X1096093Y517607D01*
G01X1096500Y514700D02*
Y517200D01*
G01X1095574Y513774D02*
X1096500Y514700D01*
G01X1095574Y511826D02*
Y513774D01*
G01X1096351Y511049D02*
X1095574Y511826D01*
G01X1096351Y506951D02*
Y511049D01*
G01X1134557Y513114D02*
X1134645D01*
G01X1132871Y514800D02*
X1134557Y513114D01*
G01X1132871Y516492D02*
Y514800D01*
G01X1133046Y516667D02*
X1132871Y516492D01*
G01X1133046Y519300D02*
Y516667D01*
G01X1131934Y520412D02*
X1133046Y519300D01*
G01X1131934Y521488D02*
Y520412D01*
G01X1132946Y522500D02*
X1131934Y521488D01*
G01X1132946Y523700D02*
Y522500D01*
G01X1131934Y524712D02*
X1132946Y523700D01*
G01X1131934Y525788D02*
Y524712D01*
G01X1133071Y526925D02*
X1131934Y525788D01*
G01X1127952Y535100D02*
X1122901Y530049D01*
G01X1109453Y528300D02*
Y527100D01*
G01X1108854Y528899D02*
X1109453Y528300D01*
G01X1107874Y528899D02*
X1108854D01*
G01X1109354Y534700D02*
X1106169Y531515D01*
G01X1110520Y534700D02*
X1109354D01*
G01X1102853Y528299D02*
Y527401D01*
G01X1102253Y528899D02*
X1102853Y528299D01*
G01X1101181Y528899D02*
X1102253D01*
G01X1139064D02*
X1137992D01*
G01X1139664Y528299D02*
X1139064Y528899D01*
G01X1139664Y527401D02*
Y528299D01*
G01X1145665Y528899D02*
X1144685D01*
G01X1146264Y528300D02*
X1145665Y528899D01*
G01X1146264Y527100D02*
Y528300D01*
G01X1134645Y535100D02*
X1129594Y530049D01*
G01X1100098Y530457D02*
X1099476Y529835D01*
G01X1100098Y531645D02*
Y530457D01*
G01X1103153Y534700D02*
X1100098Y531645D01*
G01X1104141Y534700D02*
X1103153D01*
G01X1146165D02*
X1147331D01*
G01X1142980Y531515D02*
X1146165Y534700D01*
G01X1139964D02*
X1140952D01*
G01X1136909Y531645D02*
X1139964Y534700D01*
G01X1136909Y530457D02*
Y531645D01*
G01X1136287Y529835D02*
X1136909Y530457D01*
G01X1126378Y528199D02*
Y526925D01*
G01X1125678Y528899D02*
X1126378Y528199D01*
G01X1124606Y528899D02*
X1125678D01*
G01X1095400Y587500D02*
Y589000D01*
G01X1096353Y586547D02*
X1095400Y587500D01*
G01X1096353Y576553D02*
Y586547D01*
G01X1096118Y576318D02*
X1096353Y576553D01*
G01X1096118Y571118D02*
Y576318D01*
G01X1095815Y570815D02*
X1096118Y571118D01*
G01X1095815Y568385D02*
Y570815D01*
G01X1096110Y568090D02*
X1095815Y568385D01*
G01X1096110Y548890D02*
Y568090D01*
G01X1096300Y548700D02*
X1096110Y548890D01*
G01X1096300Y533500D02*
Y548700D01*
G01X1096093Y533293D02*
X1096300Y533500D01*
G01X1133071Y528199D02*
Y526925D01*
G01X1132371Y528899D02*
X1133071Y528199D01*
G01X1131299Y528899D02*
X1132371D01*
G01X1096700Y602900D02*
Y605100D01*
G01X1096400Y602600D02*
X1096700Y602900D01*
G01X1096400Y590000D02*
Y602600D01*
G01X1095400Y589000D02*
X1096400Y590000D01*
G01X1218453Y76301D02*
X1220086Y74668D01*
G01X1218453Y77600D02*
Y76301D01*
G01X1219803Y78950D02*
X1218453Y77600D01*
G01X1218553Y81100D02*
X1219803Y79850D01*
G01X1218553Y82299D02*
Y81100D01*
G01X1220086Y83832D02*
X1218553Y82299D01*
G01X1217186Y88700D02*
X1220086Y85800D01*
G01X1217186Y91636D02*
Y88700D01*
G01X1218307Y92757D02*
X1217186Y91636D01*
G01X1217392Y93672D02*
X1218307Y92757D01*
G01X1217392Y97891D02*
Y93672D01*
G01X1161417Y66953D02*
Y65699D01*
G01X1163964Y69500D02*
X1161417Y66953D01*
G01X1164964Y69500D02*
X1163964D01*
G01X1166764Y71300D02*
X1164964Y69500D01*
G01X1166764Y72700D02*
Y71300D01*
G01X1166152Y73312D02*
X1166764Y72700D01*
G01X1166152Y86325D02*
Y73312D01*
G01X1164763Y87714D02*
X1166152Y86325D01*
G01X1162900Y89577D02*
X1164763Y87714D01*
G01X1162900Y91300D02*
Y89577D01*
G01X1164300Y92700D02*
X1162900Y91300D01*
G01X1164300Y104546D02*
Y92700D01*
G01X1176675Y72588D02*
X1177763Y71500D01*
G01X1176675Y74468D02*
Y72588D01*
G01X1175242Y75901D02*
X1176675Y74468D01*
G01X1175242Y77100D02*
Y75901D01*
G01X1176742Y78600D02*
X1175242Y77100D01*
G01X1176742Y79800D02*
Y78600D01*
G01X1175292Y81250D02*
X1176742Y79800D01*
G01X1175292Y82649D02*
Y81250D01*
G01X1176675Y84032D02*
X1175292Y82649D01*
G01X1176675Y85901D02*
Y84032D01*
G01X1173875Y88701D02*
X1176675Y85901D01*
G01X1173875Y91829D02*
Y88701D01*
G01X1174803Y92757D02*
X1173875Y91829D01*
G01X1174803Y94067D02*
Y92757D01*
G01X1175392Y94656D02*
X1174803Y94067D01*
G01X1182174Y89682D02*
X1184142Y87714D01*
G01X1182174Y90974D02*
Y89682D01*
G01X1183674Y92474D02*
X1182174Y90974D01*
G01X1183674Y100338D02*
Y92474D01*
G01X1181496Y67821D02*
Y65699D01*
G01X1183375Y69700D02*
X1181496Y67821D01*
G01X1184775Y69700D02*
X1183375D01*
G01X1186231Y71156D02*
X1184775Y69700D01*
G01X1186231Y72500D02*
Y71156D01*
G01X1185615Y73116D02*
X1186231Y72500D01*
G01X1185615Y86241D02*
Y73116D01*
G01X1184142Y87714D02*
X1185615Y86241D01*
G01X1174803Y67253D02*
Y65699D01*
G01X1177050Y69500D02*
X1174803Y67253D01*
G01X1178274Y69500D02*
X1177050D01*
G01X1179850Y71076D02*
X1178274Y69500D01*
G01X1179850Y72700D02*
Y71076D01*
G01X1179075Y73475D02*
X1179850Y72700D01*
G01X1179075Y86488D02*
Y73475D01*
G01X1177849Y87714D02*
X1179075Y86488D01*
G01X1175874Y89689D02*
X1177849Y87714D01*
G01X1175874Y90974D02*
Y89689D01*
G01X1177099Y92199D02*
X1175874Y90974D01*
G01X1177099Y93363D02*
Y92199D01*
G01X1177692Y93956D02*
X1177099Y93363D01*
G01X1178706Y93956D02*
X1177692D01*
G01X1179474Y94724D02*
X1178706Y93956D01*
G01X1198228Y66953D02*
Y65699D01*
G01X1200775Y69500D02*
X1198228Y66953D01*
G01X1201775Y69500D02*
X1200775D01*
G01X1203575Y71300D02*
X1201775Y69500D01*
G01X1203575Y72700D02*
Y71300D01*
G01X1202963Y73312D02*
X1203575Y72700D01*
G01X1202963Y86325D02*
Y73312D01*
G01X1201574Y87714D02*
X1202963Y86325D01*
G01X1199700Y89588D02*
X1201574Y87714D01*
G01X1199700Y91600D02*
Y89588D01*
G01X1200200Y92100D02*
X1199700Y91600D01*
G01X1200200Y95838D02*
Y92100D01*
G01X1163289Y73374D02*
X1164763Y71900D01*
G01X1163289Y74468D02*
Y73374D01*
G01X1161856Y75901D02*
X1163289Y74468D01*
G01X1161856Y77124D02*
Y75901D01*
G01X1163356Y78624D02*
X1161856Y77124D01*
G01X1163356Y79976D02*
Y78624D01*
G01X1161856Y81476D02*
X1163356Y79976D01*
G01X1161856Y82599D02*
Y81476D01*
G01X1163531Y84274D02*
X1161856Y82599D01*
G01X1163531Y85659D02*
Y84274D01*
G01X1160489Y88701D02*
X1163531Y85659D01*
G01X1160489Y91829D02*
Y88701D01*
G01X1161417Y92757D02*
X1160489Y91829D01*
G01X1161417Y92761D02*
Y92757D01*
G01X1162100Y93444D02*
X1161417Y92761D01*
G01X1162100Y96001D02*
Y93444D01*
G01X1206700Y73467D02*
X1208267Y71900D01*
G01X1206700Y74668D02*
Y73467D01*
G01X1205342Y76026D02*
X1206700Y74668D01*
G01X1205342Y77399D02*
Y76026D01*
G01X1206542Y78599D02*
X1205342Y77399D01*
G01X1206542Y79725D02*
Y78599D01*
G01X1205342Y80925D02*
X1206542Y79725D01*
G01X1205342Y82500D02*
Y80925D01*
G01X1207142Y84300D02*
X1205342Y82500D01*
G01X1207142Y85358D02*
Y84300D01*
G01X1203800Y88700D02*
X1207142Y85358D01*
G01X1203800Y91636D02*
Y88700D01*
G01X1204921Y92757D02*
X1203800Y91636D01*
G01X1204921Y96021D02*
Y92757D01*
G01X1213486Y72588D02*
X1214574Y71500D01*
G01X1213486Y74468D02*
Y72588D01*
G01X1212053Y75901D02*
X1213486Y74468D01*
G01X1212053Y77100D02*
Y75901D01*
G01X1213553Y78600D02*
X1212053Y77100D01*
G01X1213553Y79800D02*
Y78600D01*
G01X1212103Y81250D02*
X1213553Y79800D01*
G01X1212103Y82649D02*
Y81250D01*
G01X1213486Y84032D02*
X1212103Y82649D01*
G01X1213486Y85901D02*
Y84032D01*
G01X1210686Y88701D02*
X1213486Y85901D01*
G01X1210686Y91829D02*
Y88701D01*
G01X1211614Y92757D02*
X1210686Y91829D01*
G01X1212774Y93917D02*
X1211614Y92757D01*
G01X1212774Y99773D02*
Y93917D01*
G01X1168110Y66953D02*
Y65699D01*
G01X1170657Y69500D02*
X1168110Y66953D01*
G01X1171657Y69500D02*
X1170657D01*
G01X1173457Y71300D02*
X1171657Y69500D01*
G01X1173457Y72700D02*
Y71300D01*
G01X1172845Y73312D02*
X1173457Y72700D01*
G01X1172845Y86325D02*
Y73312D01*
G01X1171456Y87714D02*
X1172845Y86325D01*
G01X1169374Y89796D02*
X1171456Y87714D01*
G01X1169374Y91274D02*
Y89796D01*
G01X1172474Y94374D02*
X1169374Y91274D01*
G01X1172474Y105174D02*
Y94374D01*
G01X1183275Y72367D02*
X1184142Y71500D01*
G01X1183275Y74668D02*
Y72367D01*
G01X1181642Y76301D02*
X1183275Y74668D01*
G01X1181642Y77600D02*
Y76301D01*
G01X1182992Y78950D02*
X1181642Y77600D01*
G01X1182992Y79850D02*
Y78950D01*
G01X1181742Y81100D02*
X1182992Y79850D01*
G01X1181742Y82299D02*
Y81100D01*
G01X1183275Y83832D02*
X1181742Y82299D01*
G01X1183275Y85800D02*
Y83832D01*
G01X1180375Y88700D02*
X1183275Y85800D01*
G01X1180375Y91636D02*
Y88700D01*
G01X1181496Y92757D02*
X1180375Y91636D01*
G01X1181496Y101560D02*
Y92757D01*
G01X1169889Y73467D02*
X1171456Y71900D01*
G01X1169889Y74668D02*
Y73467D01*
G01X1168531Y76026D02*
X1169889Y74668D01*
G01X1168531Y77399D02*
Y76026D01*
G01X1169731Y78599D02*
X1168531Y77399D01*
G01X1169731Y79725D02*
Y78599D01*
G01X1168531Y80925D02*
X1169731Y79725D01*
G01X1168531Y82500D02*
Y80925D01*
G01X1170331Y84300D02*
X1168531Y82500D01*
G01X1170331Y85358D02*
Y84300D01*
G01X1166989Y88700D02*
X1170331Y85358D01*
G01X1166989Y91636D02*
Y88700D01*
G01X1168110Y92757D02*
X1166989Y91636D01*
G01X1166900Y93967D02*
X1168110Y92757D01*
G01X1166900Y95600D02*
Y93967D01*
G01X1204921Y66953D02*
Y65699D01*
G01X1207468Y69500D02*
X1204921Y66953D01*
G01X1208468Y69500D02*
X1207468D01*
G01X1210268Y71300D02*
X1208468Y69500D01*
G01X1210268Y72700D02*
Y71300D01*
G01X1209656Y73312D02*
X1210268Y72700D01*
G01X1209656Y86325D02*
Y73312D01*
G01X1208267Y87714D02*
X1209656Y86325D01*
G01X1206500Y89481D02*
X1208267Y87714D01*
G01X1206500Y91665D02*
Y89481D01*
G01X1210174Y95339D02*
X1206500Y91665D01*
G01X1218307Y67821D02*
Y65699D01*
G01X1220186Y69700D02*
X1218307Y67821D01*
G01X1211614Y67253D02*
Y65699D01*
G01X1213861Y69500D02*
X1211614Y67253D01*
G01X1215085Y69500D02*
X1213861D01*
G01X1216661Y71076D02*
X1215085Y69500D01*
G01X1216661Y72700D02*
Y71076D01*
G01X1215886Y73475D02*
X1216661Y72700D01*
G01X1215886Y86488D02*
Y73475D01*
G01X1215000Y87374D02*
X1215886Y86488D01*
G01X1214874Y87374D02*
X1215000D01*
G01X1214660Y87588D02*
X1214874Y87374D01*
G01X1214660Y92646D02*
Y87588D01*
G01X1215274Y93260D02*
X1214660Y92646D01*
G01X1215274Y98875D02*
Y93260D01*
G01X1200100Y73374D02*
X1201574Y71900D01*
G01X1200100Y74468D02*
Y73374D01*
G01X1198667Y75901D02*
X1200100Y74468D01*
G01X1198667Y77124D02*
Y75901D01*
G01X1200167Y78624D02*
X1198667Y77124D01*
G01X1200167Y79976D02*
Y78624D01*
G01X1198667Y81476D02*
X1200167Y79976D01*
G01X1198667Y82599D02*
Y81476D01*
G01X1200342Y84274D02*
X1198667Y82599D01*
G01X1200342Y85659D02*
Y84274D01*
G01X1197300Y88701D02*
X1200342Y85659D01*
G01X1197300Y91829D02*
Y88701D01*
G01X1198228Y92757D02*
X1197300Y91829D01*
G01X1198042Y92942D02*
X1198228Y92757D01*
G01X1196308Y94677D02*
X1198042Y92942D01*
G01X1219174Y99673D02*
X1217392Y97891D01*
G01X1212329Y138472D02*
X1219174D01*
G01X1186501Y164300D02*
X1212329Y138472D01*
G01X1162392Y106454D02*
X1164300Y104546D01*
G01X1162392Y110192D02*
Y106454D01*
G01X1163462Y111262D02*
X1162392Y110192D01*
G01X1163462Y113138D02*
Y111262D01*
G01X1175392Y101756D02*
Y94656D01*
G01X1176874Y103238D02*
X1175392Y101756D01*
G01X1176874Y105374D02*
Y103238D01*
G01X1175974Y106274D02*
X1176874Y105374D01*
G01X1175974Y110774D02*
Y106274D01*
G01X1177174Y111974D02*
X1175974Y110774D01*
G01X1177174Y112926D02*
Y111974D01*
G01X1161000Y129100D02*
X1177174Y112926D01*
G01X1186074Y102738D02*
X1183674Y100338D01*
G01X1186074Y115026D02*
Y102738D01*
G01X1163200Y137900D02*
X1186074Y115026D01*
G01X1161200Y137900D02*
X1163200D01*
G01X1160000Y136700D02*
X1161200Y137900D01*
G01X1179474Y95668D02*
Y94724D01*
G01X1178674Y96468D02*
X1179474Y95668D01*
G01X1178292Y96468D02*
X1178674D01*
G01X1177492Y97268D02*
X1178292Y96468D01*
G01X1177492Y98868D02*
Y97268D01*
G01X1178292Y99668D02*
X1177492Y98868D01*
G01X1178674Y99668D02*
X1178292D01*
G01X1179474Y100468D02*
X1178674Y99668D01*
G01X1179474Y105474D02*
Y100468D01*
G01X1179674Y105674D02*
X1179474Y105474D01*
G01X1179674Y113525D02*
Y105674D01*
G01X1160699Y132500D02*
X1179674Y113525D01*
G01X1201000Y96638D02*
X1200200Y95838D01*
G01X1202074Y96638D02*
X1201000D01*
G01X1202874Y97438D02*
X1202074Y96638D01*
G01X1202874Y104974D02*
Y97438D01*
G01X1203374Y105474D02*
X1202874Y104974D01*
G01X1203374Y111174D02*
Y105474D01*
G01X1202974Y111574D02*
X1203374Y111174D01*
G01X1202974Y113626D02*
Y111574D01*
G01X1201774Y114826D02*
X1202974Y113626D01*
G01X1201774Y125526D02*
Y114826D01*
G01X1177400Y149900D02*
X1201774Y125526D01*
G01X1161545Y96556D02*
X1162100Y96001D01*
G01X1159208Y96556D02*
X1161545D01*
G01X1158408Y97356D02*
X1159208Y96556D01*
G01X1158408Y98956D02*
Y97356D01*
G01X1159308Y99856D02*
X1158408Y98956D01*
G01X1161356Y99856D02*
X1159308D01*
G01X1162000Y100500D02*
X1161356Y99856D01*
G01X1162000Y101400D02*
Y100500D01*
G01X1160500Y102900D02*
X1162000Y101400D01*
G01X1158700Y102900D02*
X1160500D01*
G01X1158200Y103400D02*
X1158700Y102900D01*
G01X1158200Y105447D02*
Y103400D01*
G01X1158900Y106147D02*
X1158200Y105447D01*
G01X1159500Y106147D02*
X1158900D01*
G01X1160300Y106947D02*
X1159500Y106147D01*
G01X1160300Y108547D02*
Y106947D01*
G01X1159500Y109347D02*
X1160300Y108547D01*
G01X1158900Y109347D02*
X1159500D01*
G01X1158200Y110047D02*
X1158900Y109347D01*
G01X1158200Y111200D02*
Y110047D01*
G01X1159500Y112500D02*
X1158200Y111200D01*
G01X1159500Y113564D02*
Y112500D01*
G01X1205356Y96456D02*
X1204921Y96021D01*
G01X1206792Y96456D02*
X1205356D01*
G01X1207892Y97556D02*
X1206792Y96456D01*
G01X1207892Y98456D02*
Y97556D01*
G01X1207092Y99256D02*
X1207892Y98456D01*
G01X1205692Y99256D02*
X1207092D01*
G01X1205092Y99856D02*
X1205692Y99256D01*
G01X1205092Y101056D02*
Y99856D01*
G01X1205892Y101856D02*
X1205092Y101056D01*
G01X1207192Y101856D02*
X1205892D01*
G01X1207892Y102556D02*
X1207192Y101856D01*
G01X1207892Y104556D02*
Y102556D01*
G01X1206274Y106174D02*
X1207892Y104556D01*
G01X1206274Y110874D02*
Y106174D01*
G01X1206774Y111374D02*
X1206274Y110874D01*
G01X1206774Y113774D02*
Y111374D01*
G01X1204274Y116274D02*
X1206774Y113774D01*
G01X1204274Y126525D02*
Y116274D01*
G01X1202063Y128736D02*
X1204274Y126525D01*
G01X1202063Y129598D02*
Y128736D01*
G01X1203100Y130636D02*
X1202063Y129598D01*
G01X1203100Y131498D02*
Y130636D01*
G01X1202116Y132482D02*
X1203100Y131498D01*
G01X1201255Y132482D02*
X1202116D01*
G01X1201132Y132359D02*
X1201255Y132482D01*
G01X1200340Y132359D02*
X1201132D01*
G01X1199172Y133527D02*
X1200340Y132359D01*
G01X1199172Y134884D02*
Y133527D01*
G01X1182056Y152000D02*
X1199172Y134884D01*
G01X1214174Y101173D02*
X1212774Y99773D01*
G01X1214174Y114726D02*
Y101173D01*
G01X1210500Y118400D02*
X1214174Y114726D01*
G01X1210500Y133000D02*
Y118400D01*
G01X1185000Y158500D02*
X1210500Y133000D01*
G01X1172600Y105300D02*
X1172474Y105174D01*
G01X1172600Y111074D02*
Y105300D01*
G01X1157674Y126000D02*
X1172600Y111074D01*
G01X1183174Y103238D02*
X1181496Y101560D01*
G01X1183174Y105074D02*
Y103238D01*
G01X1182174Y106074D02*
X1183174Y105074D01*
G01X1182174Y110474D02*
Y106074D01*
G01X1183400Y111700D02*
X1182174Y110474D01*
G01X1183400Y114300D02*
Y111700D01*
G01X1163100Y134600D02*
X1183400Y114300D01*
G01X1167500Y96200D02*
X1166900Y95600D01*
G01X1169300Y96200D02*
X1167500D01*
G01X1169974Y96874D02*
X1169300Y96200D01*
G01X1169974Y105126D02*
Y96874D01*
G01X1168900Y106200D02*
X1169974Y105126D01*
G01X1168284Y106200D02*
X1168900D01*
G01X1166900Y107584D02*
X1168284Y106200D01*
G01X1166900Y110648D02*
Y107584D01*
G01X1166125Y111423D02*
X1166900Y110648D01*
G01X1166125Y114012D02*
Y111423D01*
G01X1210174Y114036D02*
Y95339D01*
G01X1206992Y117218D02*
X1210174Y114036D01*
G01X1206992Y131308D02*
Y117218D01*
G01X1184100Y154200D02*
X1206992Y131308D01*
G01X1214300Y141300D02*
X1220201D01*
G01X1186200Y169400D02*
X1214300Y141300D01*
G01X1216126Y155574D02*
X1226126D01*
G01X1188100Y183600D02*
X1216126Y155574D01*
G01X1216674Y100275D02*
X1215274Y98875D01*
G01X1216674Y119496D02*
Y100275D01*
G01X1216064Y120106D02*
X1216674Y119496D01*
G01X1214110Y120106D02*
X1216064D01*
G01X1213500Y120716D02*
X1214110Y120106D01*
G01X1213500Y122106D02*
Y120716D01*
G01X1214110Y122716D02*
X1213500Y122106D01*
G01X1216064Y122716D02*
X1214110D01*
G01X1216674Y123326D02*
X1216064Y122716D01*
G01X1216674Y124716D02*
Y123326D01*
G01X1216064Y125326D02*
X1216674Y124716D01*
G01X1214200Y125326D02*
X1216064D01*
G01X1213700Y125826D02*
X1214200Y125326D01*
G01X1213700Y127436D02*
Y125826D01*
G01X1214200Y127936D02*
X1213700Y127436D01*
G01X1216064Y127936D02*
X1214200D01*
G01X1216674Y128546D02*
X1216064Y127936D01*
G01X1216674Y130626D02*
Y128546D01*
G01X1185600Y161700D02*
X1216674Y130626D01*
G01X1196308Y95809D02*
Y94677D01*
G01X1200028Y99529D02*
X1196308Y95809D01*
G01X1200028Y105520D02*
Y99529D01*
G01X1199774Y105774D02*
X1200028Y105520D01*
G01X1199774Y111274D02*
Y105774D01*
G01X1200340Y111840D02*
X1199774Y111274D01*
G01X1200340Y113300D02*
Y111840D01*
G01X1199274Y114366D02*
X1200340Y113300D01*
G01X1199274Y121125D02*
Y114366D01*
G01X1190800Y129599D02*
X1199274Y121125D01*
G01X1190800Y132700D02*
Y129599D01*
G01X1189088Y134412D02*
X1190800Y132700D01*
G01X1185987Y134412D02*
X1189088D01*
G01X1185003Y135396D02*
X1185987Y134412D01*
G01X1185003Y136258D02*
Y135396D01*
G01X1185976Y137231D02*
X1185003Y136258D01*
G01X1185976Y138024D02*
Y137231D01*
G01X1184923Y139077D02*
X1185976Y138024D01*
G01X1184130Y139077D02*
X1184923D01*
G01X1183157Y138104D02*
X1184130Y139077D01*
G01X1182295Y138104D02*
X1183157D01*
G01X1181311Y139088D02*
X1182295Y138104D01*
G01X1181311Y139950D02*
Y139088D01*
G01X1182298Y140938D02*
X1181311Y139950D01*
G01X1182298Y141800D02*
Y140938D01*
G01X1181314Y142784D02*
X1182298Y141800D01*
G01X1180452Y142784D02*
X1181314D01*
G01X1179465Y141796D02*
X1180452Y142784D01*
G01X1178603Y141796D02*
X1179465D01*
G01X1177619Y142780D02*
X1178603Y141796D01*
G01X1177619Y143642D02*
Y142780D01*
G01X1178606Y144630D02*
X1177619Y143642D01*
G01X1178606Y145492D02*
Y144630D01*
G01X1177622Y146476D02*
X1178606Y145492D01*
G01X1176760Y146476D02*
X1177622D01*
G01X1175773Y145488D02*
X1176760Y146476D01*
G01X1174911Y145488D02*
X1175773D01*
G01X1172499Y147900D02*
X1174911Y145488D01*
G01X1169801Y164300D02*
X1186501D01*
G01X1216026Y162874D02*
X1226674D01*
G01X1190600Y188300D02*
X1216026Y162874D01*
G01X1179585Y188300D02*
X1190600D01*
G01X1179025Y188860D02*
X1179585Y188300D01*
G01X1179025Y191740D02*
Y188860D01*
G01X1178465Y192300D02*
X1179025Y191740D01*
G01X1177025Y192300D02*
X1178465D01*
G01X1176465Y191740D02*
X1177025Y192300D01*
G01X1176465Y188860D02*
Y191740D01*
G01X1175905Y188300D02*
X1176465Y188860D01*
G01X1173299Y188300D02*
X1175905D01*
G01X1166944Y194655D02*
X1173299Y188300D01*
G01X1161344Y194655D02*
X1166944D01*
G01X1168901Y158500D02*
X1185000D01*
G01X1166084Y191216D02*
X1159684D01*
G01X1171200Y186100D02*
X1166084Y191216D01*
G01X1189500Y186100D02*
X1171200D01*
G01X1216176Y159424D02*
X1189500Y186100D01*
G01X1226324Y159424D02*
X1216176D01*
G01X1180713Y169400D02*
X1186200D01*
G01X1180103Y168790D02*
X1180713Y169400D01*
G01X1180103Y167510D02*
Y168790D01*
G01X1179493Y166900D02*
X1180103Y167510D01*
G01X1178103Y166900D02*
X1179493D01*
G01X1177493Y167510D02*
X1178103Y166900D01*
G01X1177493Y168790D02*
Y167510D01*
G01X1176883Y169400D02*
X1177493Y168790D01*
G01X1175493Y169400D02*
X1176883D01*
G01X1174883Y168790D02*
X1175493Y169400D01*
G01X1174883Y167510D02*
Y168790D01*
G01X1174273Y166900D02*
X1174883Y167510D01*
G01X1172883Y166900D02*
X1174273D01*
G01X1172273Y167510D02*
X1172883Y166900D01*
G01X1172273Y168790D02*
Y167510D01*
G01X1171663Y169400D02*
X1172273Y168790D01*
G01X1168201Y169400D02*
X1171663D01*
G01X1169100Y183600D02*
X1188100D01*
G01X1164100Y188600D02*
X1169100Y183600D01*
G01X1159500Y188600D02*
X1164100D01*
G01X1169000Y161700D02*
X1185600D01*
G01X1215876Y167324D02*
X1189700Y193500D01*
G01X1225824Y167324D02*
X1215876D01*
G01X1182349Y443550D02*
X1206300Y467501D01*
G01X1177602Y443550D02*
X1182349D01*
G01X1176992Y442940D02*
X1177602Y443550D01*
G01X1176992Y441550D02*
Y442940D01*
G01X1176382Y440940D02*
X1176992Y441550D01*
G01X1174992Y440940D02*
X1176382D01*
G01X1174382Y441550D02*
X1174992Y440940D01*
G01X1174382Y442940D02*
Y441550D01*
G01X1173772Y443550D02*
X1174382Y442940D01*
G01X1172382Y443550D02*
X1173772D01*
G01X1171772Y442940D02*
X1172382Y443550D01*
G01X1171772Y441550D02*
Y442940D01*
G01X1171162Y440940D02*
X1171772Y441550D01*
G01X1169772Y440940D02*
X1171162D01*
G01X1169162Y441550D02*
X1169772Y440940D01*
G01X1169162Y442940D02*
Y441550D01*
G01X1168552Y443550D02*
X1169162Y442940D01*
G01X1164024Y443550D02*
X1168552D01*
G01X1179915Y452216D02*
X1198800Y471101D01*
G01X1164608Y452216D02*
X1179915D01*
G01X1160363Y456461D02*
X1164608Y452216D01*
G01X1180555Y445456D02*
X1203800Y468701D01*
G01X1165030Y445456D02*
X1180555D01*
G01X1157795Y452691D02*
X1165030Y445456D01*
G01X1194683Y414000D02*
X1221383Y440700D01*
G01X1183100Y414000D02*
X1194683D01*
G01X1178600Y409500D02*
X1183100Y414000D01*
G01X1172100Y409500D02*
X1178600D01*
G01X1191811Y418200D02*
X1219795Y446184D01*
G01X1181968Y418200D02*
X1191811D01*
G01X1177868Y414100D02*
X1181968Y418200D01*
G01X1172350Y414100D02*
X1177868D01*
G01X1177899Y434700D02*
X1210400Y467201D01*
G01X1160000Y434700D02*
X1177899D01*
G01X1183764Y428300D02*
X1222695Y467231D01*
G01X1161600Y428300D02*
X1183764D01*
G01X1190099Y420100D02*
X1222403Y452404D01*
G01X1181202Y420100D02*
X1190099D01*
G01X1177102Y416000D02*
X1181202Y420100D01*
G01X1172400Y416000D02*
X1177102D01*
G01X1182128Y430200D02*
X1225474Y473546D01*
G01X1160834Y430200D02*
X1182128D01*
G01X1213044Y464809D02*
X1222974Y474739D01*
G01X1209964Y463362D02*
X1211411Y464809D01*
G01X1209964Y461729D02*
Y463362D01*
G01X1208518Y460283D02*
X1209964Y461729D01*
G01X1206885Y460283D02*
X1208518D01*
G01X1205438Y458836D02*
X1206885Y460283D01*
G01X1205438Y457203D02*
Y458836D01*
G01X1203992Y455757D02*
X1205438Y457203D01*
G01X1202359Y455757D02*
X1203992D01*
G01X1200912Y454310D02*
X1202359Y455757D01*
G01X1200912Y452677D02*
Y454310D01*
G01X1199466Y451231D02*
X1200912Y452677D01*
G01X1197833Y451231D02*
X1199466D01*
G01X1196386Y449784D02*
X1197833Y451231D01*
G01X1196386Y448151D02*
Y449784D01*
G01X1194940Y446705D02*
X1196386Y448151D01*
G01X1193307Y446705D02*
X1194940D01*
G01X1191860Y445258D02*
X1193307Y446705D01*
G01X1191860Y443625D02*
Y445258D01*
G01X1190414Y442179D02*
X1191860Y443625D01*
G01X1188781Y442179D02*
X1190414D01*
G01X1187334Y440732D02*
X1188781Y442179D01*
G01X1187334Y439099D02*
Y440732D01*
G01X1185888Y437653D02*
X1187334Y439099D01*
G01X1184255Y437653D02*
X1185888D01*
G01X1182808Y436206D02*
X1184255Y437653D01*
G01X1182808Y434573D02*
Y436206D01*
G01X1180435Y432200D02*
X1182808Y434573D01*
G01X1160167Y432200D02*
X1180435D01*
G01X1193247Y416100D02*
X1219847Y442700D01*
G01X1182534Y416100D02*
X1193247D01*
G01X1178434Y412000D02*
X1182534Y416100D01*
G01X1172099Y412000D02*
X1178434D01*
G01X1178959Y447460D02*
X1201300Y469801D01*
G01X1177314Y447460D02*
X1178959D01*
G01X1176704Y448070D02*
X1177314Y447460D01*
G01X1176704Y449536D02*
Y448070D01*
G01X1176094Y450146D02*
X1176704Y449536D01*
G01X1174704Y450146D02*
X1176094D01*
G01X1174094Y449536D02*
X1174704Y450146D01*
G01X1174094Y448070D02*
Y449536D01*
G01X1173484Y447460D02*
X1174094Y448070D01*
G01X1172094Y447460D02*
X1173484D01*
G01X1171484Y448070D02*
X1172094Y447460D01*
G01X1171484Y449536D02*
Y448070D01*
G01X1170874Y450146D02*
X1171484Y449536D01*
G01X1169484Y450146D02*
X1170874D01*
G01X1168874Y449536D02*
X1169484Y450146D01*
G01X1168874Y448070D02*
Y449536D01*
G01X1168264Y447460D02*
X1168874Y448070D01*
G01X1166020Y447460D02*
X1168264D01*
G01X1158904Y454576D02*
X1166020Y447460D01*
G01X1205556Y525788D02*
X1206693Y526925D01*
G01X1205556Y524712D02*
Y525788D01*
G01X1206568Y523700D02*
X1205556Y524712D01*
G01X1206568Y522500D02*
Y523700D01*
G01X1205556Y521488D02*
X1206568Y522500D01*
G01X1205556Y520412D02*
Y521488D01*
G01X1206668Y519300D02*
X1205556Y520412D01*
G01X1206668Y516667D02*
Y519300D01*
G01X1206493Y516492D02*
X1206668Y516667D01*
G01X1206493Y514800D02*
Y516492D01*
G01X1208179Y513114D02*
X1206493Y514800D01*
G01X1208267Y513114D02*
X1208179D01*
G01X1208267Y513166D02*
Y513114D01*
G01X1209221Y512212D02*
X1208267Y513166D01*
G01X1209221Y497953D02*
Y512212D01*
G01X1210074Y497100D02*
X1209221Y497953D01*
G01X1210074Y488694D02*
Y497100D01*
G01X1206300Y484920D02*
X1210074Y488694D01*
G01X1206300Y467501D02*
Y484920D01*
G01X1196523Y519862D02*
Y530049D01*
G01X1198228Y518157D02*
X1196523Y519862D01*
G01X1197563Y517492D02*
X1198228Y518157D01*
G01X1197563Y513657D02*
Y517492D01*
G01X1200300Y510920D02*
X1197563Y513657D01*
G01X1200300Y497889D02*
Y510920D01*
G01X1199800Y497389D02*
X1200300Y497889D01*
G01X1199800Y495100D02*
Y497389D01*
G01X1198800Y494100D02*
X1199800Y495100D01*
G01X1198800Y471101D02*
Y494100D01*
G01X1173098Y519862D02*
Y529835D01*
G01X1174803Y518157D02*
X1173098Y519862D01*
G01X1174343Y517697D02*
X1174803Y518157D01*
G01X1174343Y513475D02*
Y517697D01*
G01X1176611Y511207D02*
X1174343Y513475D01*
G01X1176611Y509110D02*
Y511207D01*
G01X1175600Y508099D02*
X1176611Y509110D01*
G01X1175600Y500500D02*
Y508099D01*
G01X1176100Y500000D02*
X1175600Y500500D01*
G01X1176100Y497179D02*
Y500000D01*
G01X1175900Y496979D02*
X1176100Y497179D01*
G01X1175900Y492126D02*
Y496979D01*
G01X1175600Y491826D02*
X1175900Y492126D01*
G01X1175600Y484700D02*
Y491826D01*
G01X1164244Y473344D02*
X1175600Y484700D01*
G01X1203216Y519862D02*
Y530049D01*
G01X1204921Y518157D02*
X1203216Y519862D01*
G01X1203563Y516799D02*
X1204921Y518157D01*
G01X1203563Y514537D02*
Y516799D01*
G01X1206721Y511379D02*
X1203563Y514537D01*
G01X1206721Y497499D02*
Y511379D01*
G01X1206500Y497278D02*
X1206721Y497499D01*
G01X1206500Y491815D02*
Y497278D01*
G01X1206963Y491352D02*
X1206500Y491815D01*
G01X1206963Y489119D02*
Y491352D01*
G01X1203800Y485956D02*
X1206963Y489119D01*
G01X1203800Y468701D02*
Y485956D01*
G01X1162052Y525788D02*
X1163189Y526925D01*
G01X1162052Y524712D02*
Y525788D01*
G01X1163064Y523700D02*
X1162052Y524712D01*
G01X1163064Y522500D02*
Y523700D01*
G01X1162052Y521488D02*
X1163064Y522500D01*
G01X1162052Y520412D02*
Y521488D01*
G01X1163164Y519300D02*
X1162052Y520412D01*
G01X1163164Y516667D02*
Y519300D01*
G01X1162989Y516492D02*
X1163164Y516667D01*
G01X1162989Y514800D02*
Y516492D01*
G01X1164675Y513114D02*
X1162989Y514800D01*
G01X1164763Y513114D02*
X1164675D01*
G01X1164800D02*
X1164763D01*
G01X1165600Y512314D02*
X1164800Y513114D01*
G01X1165600Y508742D02*
Y512314D01*
G01X1166400Y507942D02*
X1165600Y508742D01*
G01X1167400Y507942D02*
X1166400D01*
G01X1168200Y507142D02*
X1167400Y507942D01*
G01X1168200Y505542D02*
Y507142D01*
G01X1167400Y504742D02*
X1168200Y505542D01*
G01X1166600Y504742D02*
X1167400D01*
G01X1165200Y503342D02*
X1166600Y504742D01*
G01X1165200Y495300D02*
Y503342D01*
G01X1166100Y494400D02*
X1165200Y495300D01*
G01X1166100Y488201D02*
Y494400D01*
G01X1160243Y482344D02*
X1166100Y488201D01*
G01X1180641Y517302D02*
X1181496Y518157D01*
G01X1180641Y513565D02*
Y517302D01*
G01X1183300Y510906D02*
X1180641Y513565D01*
G01X1183300Y509100D02*
Y510906D01*
G01X1184232Y508168D02*
X1183300Y509100D01*
G01X1184232Y503576D02*
Y508168D01*
G01X1183400Y502744D02*
X1184232Y503576D01*
G01X1183400Y497578D02*
Y502744D01*
G01X1182274Y496452D02*
X1183400Y497578D01*
G01X1182274Y483974D02*
Y496452D01*
G01X1174252Y475952D02*
X1182274Y483974D01*
G01X1174252Y474863D02*
Y475952D01*
G01X1177712Y471403D02*
X1174252Y474863D01*
G01X1177712Y470096D02*
Y471403D01*
G01X1175960Y468344D02*
X1177712Y470096D01*
G01X1179791Y519862D02*
Y531515D01*
G01X1181496Y518157D02*
X1179791Y519862D01*
G01X1210374Y516917D02*
X1211614Y518157D01*
G01X1210374Y514315D02*
Y516917D01*
G01X1213414Y511275D02*
X1210374Y514315D01*
G01X1213414Y499417D02*
Y511275D01*
G01X1214074Y498757D02*
X1213414Y499417D01*
G01X1214074Y481629D02*
Y498757D01*
G01X1213274Y480829D02*
X1214074Y481629D01*
G01X1211200Y480829D02*
X1213274D01*
G01X1210400Y480029D02*
X1211200Y480829D01*
G01X1210400Y478429D02*
Y480029D01*
G01X1211200Y477629D02*
X1210400Y478429D01*
G01X1217434Y477629D02*
X1211200D01*
G01X1218244Y476819D02*
X1217434Y477629D01*
G01X1218244Y475219D02*
Y476819D01*
G01X1217454Y474429D02*
X1218244Y475219D01*
G01X1211246Y474429D02*
X1217454D01*
G01X1210400Y473583D02*
X1211246Y474429D01*
G01X1210400Y467201D02*
Y473583D01*
G01X1209909Y519862D02*
Y529835D01*
G01X1211614Y518157D02*
X1209909Y519862D01*
G01X1159712D02*
Y530049D01*
G01X1161417Y518157D02*
X1159712Y519862D01*
G01X1160752Y517492D02*
X1161417Y518157D01*
G01X1160752Y513657D02*
Y517492D01*
G01X1163300Y511109D02*
X1160752Y513657D01*
G01X1163300Y504700D02*
Y511109D01*
G01X1163100Y504500D02*
X1163300Y504700D01*
G01X1163100Y495100D02*
Y504500D01*
G01X1161600Y493600D02*
X1163100Y495100D01*
G01X1161600Y487300D02*
Y493600D01*
G01X1159144Y484844D02*
X1161600Y487300D01*
G01X1175438Y526364D02*
X1176475Y527401D01*
G01X1175438Y525136D02*
Y526364D01*
G01X1176375Y524199D02*
X1175438Y525136D01*
G01X1176375Y522801D02*
Y524199D01*
G01X1175438Y521864D02*
X1176375Y522801D01*
G01X1175438Y520536D02*
Y521864D01*
G01X1176575Y519399D02*
X1175438Y520536D01*
G01X1176575Y517500D02*
Y519399D01*
G01X1176075Y517000D02*
X1176575Y517500D01*
G01X1176075Y514800D02*
Y517000D01*
G01X1177761Y513114D02*
X1176075Y514800D01*
G01X1177849Y513114D02*
X1177761D01*
G01X1178600Y512363D02*
X1177849Y513114D01*
G01X1178600Y508571D02*
Y512363D01*
G01X1179400Y507771D02*
X1178600Y508571D01*
G01X1181200Y507771D02*
X1179400D01*
G01X1182000Y506971D02*
X1181200Y507771D01*
G01X1182000Y505371D02*
Y506971D01*
G01X1181200Y504571D02*
X1182000Y505371D01*
G01X1178071Y504571D02*
X1181200D01*
G01X1177500Y504000D02*
X1178071Y504571D01*
G01X1177500Y502200D02*
Y504000D01*
G01X1178300Y501400D02*
X1177500Y502200D01*
G01X1178300Y495500D02*
Y501400D01*
G01X1179675Y494125D02*
X1178300Y495500D01*
G01X1179675Y485173D02*
Y494125D01*
G01X1170709Y476207D02*
X1179675Y485173D01*
G01X1170709Y475079D02*
Y476207D01*
G01X1173168Y472620D02*
X1170709Y475079D01*
G01X1173168Y471666D02*
Y472620D01*
G01X1171974Y470472D02*
X1173168Y471666D01*
G01X1170790Y470472D02*
X1171974D01*
G01X1168447Y472815D02*
X1170790Y470472D01*
G01X1167316Y472815D02*
X1168447D01*
G01X1165345Y470844D02*
X1167316Y472815D01*
G01X1166405Y519862D02*
Y530049D01*
G01X1168110Y518157D02*
X1166405Y519862D01*
G01X1167500Y517547D02*
X1168110Y518157D01*
G01X1167500Y513699D02*
Y517547D01*
G01X1170152Y511047D02*
X1167500Y513699D01*
G01X1170152Y504315D02*
Y511047D01*
G01X1169352Y503515D02*
X1170152Y504315D01*
G01X1169100Y503515D02*
X1169352D01*
G01X1168300Y502715D02*
X1169100Y503515D01*
G01X1168300Y501115D02*
Y502715D01*
G01X1169100Y500315D02*
X1168300Y501115D01*
G01X1169352Y500315D02*
X1169100D01*
G01X1170152Y499515D02*
X1169352Y500315D01*
G01X1170152Y497652D02*
Y499515D01*
G01X1169200Y496700D02*
X1170152Y497652D01*
G01X1169200Y495100D02*
Y496700D01*
G01X1168700Y494600D02*
X1169200Y495100D01*
G01X1168700Y487201D02*
Y494600D01*
G01X1161343Y479844D02*
X1168700Y487201D01*
G01X1182131Y526156D02*
X1183075Y527100D01*
G01X1182131Y524944D02*
Y526156D01*
G01X1182975Y524100D02*
X1182131Y524944D01*
G01X1182975Y522400D02*
Y524100D01*
G01X1182131Y521556D02*
X1182975Y522400D01*
G01X1182131Y520136D02*
Y521556D01*
G01X1183275Y518992D02*
X1182131Y520136D01*
G01X1183275Y517399D02*
Y518992D01*
G01X1182368Y516492D02*
X1183275Y517399D01*
G01X1182368Y514800D02*
Y516492D01*
G01X1184054Y513114D02*
X1182368Y514800D01*
G01X1184142Y513114D02*
X1184054D01*
G01X1184142Y512764D02*
Y513114D01*
G01X1186063Y510843D02*
X1184142Y512764D01*
G01X1186063Y509337D02*
Y510843D01*
G01X1187100Y508300D02*
X1186063Y509337D01*
G01X1187100Y503001D02*
Y508300D01*
G01X1186063Y501964D02*
X1187100Y503001D01*
G01X1186063Y484015D02*
Y501964D01*
G01X1178039Y475991D02*
X1186063Y484015D01*
G01X1178039Y474859D02*
Y475991D01*
G01X1179170Y473728D02*
X1178039Y474859D01*
G01X1180302Y473728D02*
X1179170D01*
G01X1185930Y479356D02*
X1180302Y473728D01*
G01X1186974Y479356D02*
X1185930D01*
G01X1188105Y478225D02*
X1186974Y479356D01*
G01X1188105Y477005D02*
Y478225D01*
G01X1176944Y465844D02*
X1188105Y477005D01*
G01X1216602Y519862D02*
Y531515D01*
G01X1218307Y518157D02*
X1216602Y519862D01*
G01X1216900Y516750D02*
X1218307Y518157D01*
G01X1216900Y514181D02*
Y516750D01*
G01X1220000Y511081D02*
X1216900Y514181D01*
G01X1212249Y526364D02*
X1213086Y527201D01*
G01X1212249Y525136D02*
Y526364D01*
G01X1213100Y524285D02*
X1212249Y525136D01*
G01X1213100Y522715D02*
Y524285D01*
G01X1212249Y521864D02*
X1213100Y522715D01*
G01X1212249Y520536D02*
Y521864D01*
G01X1213386Y519399D02*
X1212249Y520536D01*
G01X1213386Y517500D02*
Y519399D01*
G01X1212886Y517000D02*
X1213386Y517500D01*
G01X1212886Y514762D02*
Y517000D01*
G01X1214874Y512774D02*
X1212886Y514762D01*
G01X1215200Y512448D02*
X1214874Y512774D01*
G01X1215200Y510101D02*
Y512448D01*
G01X1216574Y508727D02*
X1215200Y510101D01*
G01X1216574Y481000D02*
Y508727D01*
G01X1217374Y480200D02*
X1216574Y481000D01*
G01X1218974Y480200D02*
X1217374D01*
G01X1211411Y464809D02*
X1213044D01*
G01X1168745Y525788D02*
X1169882Y526925D01*
G01X1168745Y524712D02*
Y525788D01*
G01X1169757Y523700D02*
X1168745Y524712D01*
G01X1169757Y522500D02*
Y523700D01*
G01X1168745Y521488D02*
X1169757Y522500D01*
G01X1168745Y520412D02*
Y521488D01*
G01X1169857Y519300D02*
X1168745Y520412D01*
G01X1169857Y516667D02*
Y519300D01*
G01X1169682Y516492D02*
X1169857Y516667D01*
G01X1169682Y514800D02*
Y516492D01*
G01X1171368Y513114D02*
X1169682Y514800D01*
G01X1171456Y513114D02*
X1171368D01*
G01X1172900Y511670D02*
X1171456Y513114D01*
G01X1172900Y502500D02*
Y511670D01*
G01X1172400Y502000D02*
X1172900Y502500D01*
G01X1172400Y491678D02*
Y502000D01*
G01X1172600Y491478D02*
X1172400Y491678D01*
G01X1172600Y487401D02*
Y491478D01*
G01X1162543Y477344D02*
X1172600Y487401D01*
G01X1198863Y525788D02*
X1200000Y526925D01*
G01X1198863Y524712D02*
Y525788D01*
G01X1199875Y523700D02*
X1198863Y524712D01*
G01X1199875Y522500D02*
Y523700D01*
G01X1198863Y521488D02*
X1199875Y522500D01*
G01X1198863Y520412D02*
Y521488D01*
G01X1199975Y519300D02*
X1198863Y520412D01*
G01X1199975Y516667D02*
Y519300D01*
G01X1199800Y516492D02*
X1199975Y516667D01*
G01X1199800Y514800D02*
Y516492D01*
G01X1201486Y513114D02*
X1199800Y514800D01*
G01X1201574Y513114D02*
X1201486D01*
G01X1202421Y512267D02*
X1201574Y513114D01*
G01X1202421Y506126D02*
Y512267D01*
G01X1203030Y505517D02*
X1202421Y506126D01*
G01X1204255Y505517D02*
X1203030D01*
G01X1204865Y504907D02*
X1204255Y505517D01*
G01X1204865Y503517D02*
Y504907D01*
G01X1204255Y502907D02*
X1204865Y503517D01*
G01X1203110Y502907D02*
X1204255D01*
G01X1202355Y502152D02*
X1203110Y502907D01*
G01X1202355Y494845D02*
Y502152D01*
G01X1203985Y493215D02*
X1202355Y494845D01*
G01X1203985Y489677D02*
Y493215D01*
G01X1201300Y486992D02*
X1203985Y489677D01*
G01X1201300Y469801D02*
Y486992D01*
G01X1205993Y528899D02*
X1204921D01*
G01X1206693Y528199D02*
X1205993Y528899D01*
G01X1206693Y526925D02*
Y528199D01*
G01X1196523Y530049D02*
X1201574Y535100D01*
G01X1176775Y534700D02*
X1177763D01*
G01X1173720Y531645D02*
X1176775Y534700D01*
G01X1173720Y530457D02*
Y531645D01*
G01X1173098Y529835D02*
X1173720Y530457D01*
G01X1203216Y530049D02*
X1208267Y535100D01*
G01X1162489Y528899D02*
X1161417D01*
G01X1163189Y528199D02*
X1162489Y528899D01*
G01X1163189Y526925D02*
Y528199D01*
G01X1182976Y534700D02*
X1184142D01*
G01X1179791Y531515D02*
X1182976Y534700D01*
G01X1213586D02*
X1214574D01*
G01X1210531Y531645D02*
X1213586Y534700D01*
G01X1210531Y530457D02*
Y531645D01*
G01X1209909Y529835D02*
X1210531Y530457D01*
G01X1219287Y528899D02*
X1218307D01*
G01X1159712Y530049D02*
X1164763Y535100D01*
G01X1175875Y528899D02*
X1174803D01*
G01X1176475Y528299D02*
X1175875Y528899D01*
G01X1176475Y527401D02*
Y528299D01*
G01X1166405Y530049D02*
X1171456Y535100D01*
G01X1182476Y528899D02*
X1181496D01*
G01X1183075Y528300D02*
X1182476Y528899D01*
G01X1183075Y527100D02*
Y528300D01*
G01X1216602Y531515D02*
X1219787Y534700D01*
G01X1212402Y528899D02*
X1211614D01*
G01X1213086Y528215D02*
X1212402Y528899D01*
G01X1213086Y527201D02*
Y528215D01*
G01X1169182Y528899D02*
X1168110D01*
G01X1169882Y528199D02*
X1169182Y528899D01*
G01X1169882Y526925D02*
Y528199D01*
G01X1199300Y528899D02*
X1198228D01*
G01X1200000Y528199D02*
X1199300Y528899D01*
G01X1200000Y526925D02*
Y528199D01*
G01X1220086Y72367D02*
X1220953Y71500D01*
G01X1220086Y74668D02*
Y72367D01*
G01X1219803Y79850D02*
Y78950D01*
G01X1220086Y85800D02*
Y83832D01*
G01X1241732Y147816D02*
Y92757D01*
G01X1243511Y73467D02*
X1245078Y71900D01*
G01X1243511Y74668D02*
Y73467D01*
G01X1242153Y76026D02*
X1243511Y74668D01*
G01X1242153Y77399D02*
Y76026D01*
G01X1243353Y78599D02*
X1242153Y77399D01*
G01X1243353Y79725D02*
Y78599D01*
G01X1242153Y80925D02*
X1243353Y79725D01*
G01X1242153Y82500D02*
Y80925D01*
G01X1243953Y84300D02*
X1242153Y82500D01*
G01X1243953Y85358D02*
Y84300D01*
G01X1240611Y88700D02*
X1243953Y85358D01*
G01X1240611Y91636D02*
Y88700D01*
G01X1241732Y92757D02*
X1240611Y91636D01*
G01X1239192Y93768D02*
Y127230D01*
G01X1236474Y91050D02*
X1239192Y93768D01*
G01X1236474Y89625D02*
Y91050D01*
G01X1238385Y87714D02*
X1236474Y89625D01*
G01X1239774Y86325D02*
X1238385Y87714D01*
G01X1239774Y73312D02*
Y86325D01*
G01X1240386Y72700D02*
X1239774Y73312D01*
G01X1240386Y71300D02*
Y72700D01*
G01X1238586Y69500D02*
X1240386Y71300D01*
G01X1237586Y69500D02*
X1238586D01*
G01X1235039Y66953D02*
X1237586Y69500D01*
G01X1235039Y65699D02*
Y66953D01*
G01X1221586Y69700D02*
X1220186D01*
G01X1223042Y71156D02*
X1221586Y69700D01*
G01X1223042Y72500D02*
Y71156D01*
G01X1222426Y73116D02*
X1223042Y72500D01*
G01X1222426Y86241D02*
Y73116D01*
G01X1220953Y87714D02*
X1222426Y86241D01*
G01X1218974Y89693D02*
X1220953Y87714D01*
G01X1218974Y90874D02*
Y89693D01*
G01X1220374Y92274D02*
X1218974Y90874D01*
G01X1220374Y97439D02*
Y92274D01*
G01X1236911Y73374D02*
X1238385Y71900D01*
G01X1236911Y74468D02*
Y73374D01*
G01X1235478Y75901D02*
X1236911Y74468D01*
G01X1235478Y77124D02*
Y75901D01*
G01X1236978Y78624D02*
X1235478Y77124D01*
G01X1236978Y79976D02*
Y78624D01*
G01X1235478Y81476D02*
X1236978Y79976D01*
G01X1235478Y82599D02*
Y81476D01*
G01X1237153Y84274D02*
X1235478Y82599D01*
G01X1237153Y85659D02*
Y84274D01*
G01X1234111Y88701D02*
X1237153Y85659D01*
G01X1234111Y91829D02*
Y88701D01*
G01X1235039Y92757D02*
X1234111Y91829D01*
G01X1235039Y93861D02*
Y92757D01*
G01X1234092Y94808D02*
X1235039Y93861D01*
G01X1244300Y92200D02*
Y148848D01*
G01X1243300Y91200D02*
X1244300Y92200D01*
G01X1243300Y89492D02*
Y91200D01*
G01X1245078Y87714D02*
X1243300Y89492D01*
G01X1246467Y86325D02*
X1245078Y87714D01*
G01X1246467Y73312D02*
Y86325D01*
G01X1247079Y72700D02*
X1246467Y73312D01*
G01X1247079Y71300D02*
Y72700D01*
G01X1245279Y69500D02*
X1247079Y71300D01*
G01X1244279Y69500D02*
X1245279D01*
G01X1241732Y66953D02*
X1244279Y69500D01*
G01X1241732Y65699D02*
Y66953D01*
G01X1219174Y100546D02*
Y99673D01*
G01X1220700Y102072D02*
X1219174Y100546D01*
G01X1220700Y103346D02*
Y102072D01*
G01X1219174Y104872D02*
X1220700Y103346D01*
G01X1219174Y106146D02*
Y104872D01*
G01X1220700Y107672D02*
X1219174Y106146D01*
G01X1220700Y108946D02*
Y107672D01*
G01X1219174Y110472D02*
X1220700Y108946D01*
G01X1219174Y111746D02*
Y110472D01*
G01X1220700Y113272D02*
X1219174Y111746D01*
G01X1220700Y114546D02*
Y113272D01*
G01X1219174Y116072D02*
X1220700Y114546D01*
G01X1219174Y117346D02*
Y116072D01*
G01X1220700Y118872D02*
X1219174Y117346D01*
G01X1220700Y120146D02*
Y118872D01*
G01X1219174Y121672D02*
X1220700Y120146D01*
G01X1219174Y122946D02*
Y121672D01*
G01X1220700Y124472D02*
X1219174Y122946D01*
G01X1220700Y125746D02*
Y124472D01*
G01X1219174Y127272D02*
X1220700Y125746D01*
G01X1219174Y128546D02*
Y127272D01*
G01X1220700Y130072D02*
X1219174Y128546D01*
G01X1220700Y131346D02*
Y130072D01*
G01X1219174Y132872D02*
X1220700Y131346D01*
G01X1219174Y134146D02*
Y132872D01*
G01X1220700Y135672D02*
X1219174Y134146D01*
G01X1220700Y136946D02*
Y135672D01*
G01X1219174Y138472D02*
X1220700Y136946D01*
G01X1226674Y162874D02*
X1241732Y147816D01*
G01X1235900Y149848D02*
X1226324Y159424D01*
G01X1235900Y135230D02*
Y149848D01*
G01X1236700Y134430D02*
X1235900Y135230D01*
G01X1238392Y134430D02*
X1236700D01*
G01X1239000Y133822D02*
X1238392Y134430D01*
G01X1239000Y131838D02*
Y133822D01*
G01X1238392Y131230D02*
X1239000Y131838D01*
G01X1236700Y131230D02*
X1238392D01*
G01X1235900Y130430D02*
X1236700Y131230D01*
G01X1235900Y128830D02*
Y130430D01*
G01X1236700Y128030D02*
X1235900Y128830D01*
G01X1238392Y128030D02*
X1236700D01*
G01X1239192Y127230D02*
X1238392Y128030D01*
G01X1223200Y100265D02*
X1220374Y97439D01*
G01X1223200Y138301D02*
Y100265D01*
G01X1220201Y141300D02*
X1223200Y138301D01*
G01X1234092Y96059D02*
Y94808D01*
G01X1234892Y96859D02*
X1234092Y96059D01*
G01X1235792Y96859D02*
X1234892D01*
G01X1236592Y97659D02*
X1235792Y96859D01*
G01X1236592Y99200D02*
Y97659D01*
G01X1235792Y100000D02*
X1236592Y99200D01*
G01X1234951Y100000D02*
X1235792D01*
G01X1234092Y100859D02*
X1234951Y100000D01*
G01X1234092Y103159D02*
Y100859D01*
G01X1234992Y104059D02*
X1234092Y103159D01*
G01X1235892Y104059D02*
X1234992D01*
G01X1236592Y104759D02*
X1235892Y104059D01*
G01X1236592Y105659D02*
Y104759D01*
G01X1235792Y106459D02*
X1236592Y105659D01*
G01X1234200Y106459D02*
X1235792D01*
G01X1233400Y107259D02*
X1234200Y106459D01*
G01X1233400Y108867D02*
Y107259D01*
G01X1234200Y109667D02*
X1233400Y108867D01*
G01X1235800Y109667D02*
X1234200D01*
G01X1236600Y110467D02*
X1235800Y109667D01*
G01X1236600Y112067D02*
Y110467D01*
G01X1235800Y112867D02*
X1236600Y112067D01*
G01X1234200Y112867D02*
X1235800D01*
G01X1233400Y113667D02*
X1234200Y112867D01*
G01X1233400Y115267D02*
Y113667D01*
G01X1234200Y116067D02*
X1233400Y115267D01*
G01X1235800Y116067D02*
X1234200D01*
G01X1236600Y116867D02*
X1235800Y116067D01*
G01X1236600Y118467D02*
Y116867D01*
G01X1235800Y119267D02*
X1236600Y118467D01*
G01X1234200Y119267D02*
X1235800D01*
G01X1233400Y120067D02*
X1234200Y119267D01*
G01X1233400Y148300D02*
Y120067D01*
G01X1226126Y155574D02*
X1233400Y148300D01*
G01X1244300Y148848D02*
X1225824Y167324D01*
G01X1226844Y440700D02*
X1253700Y467556D01*
G01X1221383Y440700D02*
X1226844D01*
G01X1228977Y449904D02*
X1248700Y469627D01*
G01X1223515Y449904D02*
X1228977D01*
G01X1222920Y449309D02*
X1223515Y449904D01*
G01X1222920Y448447D02*
Y449309D01*
G01X1223952Y447416D02*
X1222920Y448447D01*
G01X1223952Y446554D02*
Y447416D01*
G01X1222551Y445153D02*
X1223952Y446554D01*
G01X1221689Y445153D02*
X1222551D01*
G01X1220657Y446184D02*
X1221689Y445153D01*
G01X1219795Y446184D02*
X1220657D01*
G01X1227941Y452404D02*
X1246200Y470663D01*
G01X1222403Y452404D02*
X1227941D01*
G01X1225308Y442700D02*
X1251200Y468592D01*
G01X1219847Y442700D02*
X1225308D01*
G01X1245078Y513166D02*
Y513114D01*
G01X1246374Y511870D02*
X1245078Y513166D01*
G01X1246374Y509426D02*
Y511870D01*
G01X1248480Y507320D02*
X1246374Y509426D01*
G01X1248480Y499205D02*
Y507320D01*
G01X1249090Y498595D02*
X1248480Y499205D01*
G01X1250480Y498595D02*
X1249090D01*
G01X1251090Y499205D02*
X1250480Y498595D01*
G01X1251090Y506172D02*
Y499205D01*
G01X1251700Y506782D02*
X1251090Y506172D01*
G01X1253090Y506782D02*
X1251700D01*
G01X1253700Y506172D02*
X1253090Y506782D01*
G01X1253700Y467556D02*
Y506172D01*
G01X1242367Y525788D02*
X1243504Y526925D01*
G01X1242367Y524712D02*
Y525788D01*
G01X1243379Y523700D02*
X1242367Y524712D01*
G01X1243379Y522500D02*
Y523700D01*
G01X1242367Y521488D02*
X1243379Y522500D01*
G01X1242367Y520412D02*
Y521488D01*
G01X1243479Y519300D02*
X1242367Y520412D01*
G01X1243479Y516667D02*
Y519300D01*
G01X1243304Y516492D02*
X1243479Y516667D01*
G01X1243304Y514800D02*
Y516492D01*
G01X1244990Y513114D02*
X1243304Y514800D01*
G01X1245078Y513114D02*
X1244990D01*
G01X1239731Y511768D02*
X1238385Y513114D01*
G01X1239774Y511768D02*
X1239731D01*
G01X1239774Y509326D02*
Y511768D01*
G01X1242300Y506800D02*
X1239774Y509326D01*
G01X1242300Y489581D02*
Y506800D01*
G01X1243100Y488781D02*
X1242300Y489581D01*
G01X1246165Y488781D02*
X1243100D01*
G01X1246965Y487981D02*
X1246165Y488781D01*
G01X1246965Y486381D02*
Y487981D01*
G01X1246165Y485581D02*
X1246965Y486381D01*
G01X1242923Y485581D02*
X1246165D01*
G01X1242123Y484781D02*
X1242923Y485581D01*
G01X1242123Y482835D02*
Y484781D01*
G01X1242923Y482035D02*
X1242123Y482835D01*
G01X1247744Y482035D02*
X1242923D01*
G01X1248700Y481079D02*
X1247744Y482035D01*
G01X1248700Y469627D02*
Y481079D01*
G01X1235674Y525788D02*
X1236811Y526925D01*
G01X1235674Y524712D02*
Y525788D01*
G01X1236686Y523700D02*
X1235674Y524712D01*
G01X1236686Y522500D02*
Y523700D01*
G01X1235674Y521488D02*
X1236686Y522500D01*
G01X1235674Y520412D02*
Y521488D01*
G01X1236786Y519300D02*
X1235674Y520412D01*
G01X1236786Y516667D02*
Y519300D01*
G01X1236611Y516492D02*
X1236786Y516667D01*
G01X1236611Y514800D02*
Y516492D01*
G01X1238297Y513114D02*
X1236611Y514800D01*
G01X1238385Y513114D02*
X1238297D01*
G01X1218942Y526156D02*
X1219886Y527100D01*
G01X1218942Y524944D02*
Y526156D01*
G01X1219786Y524100D02*
X1218942Y524944D01*
G01X1219786Y522400D02*
Y524100D01*
G01X1218942Y521556D02*
X1219786Y522400D01*
G01X1218942Y520136D02*
Y521556D01*
G01X1220086Y518992D02*
X1218942Y520136D01*
G01X1220086Y517399D02*
Y518992D01*
G01X1219179Y516492D02*
X1220086Y517399D01*
G01X1219179Y514800D02*
Y516492D01*
G01X1220865Y513114D02*
X1219179Y514800D01*
G01X1220953Y513114D02*
X1220865D01*
G01X1220953Y512764D02*
Y513114D01*
G01X1222065Y511652D02*
X1220953Y512764D01*
G01X1222065Y505664D02*
Y511652D01*
G01X1222829Y504900D02*
X1222065Y505664D01*
G01X1225793Y504900D02*
X1222829D01*
G01X1226403Y504290D02*
X1225793Y504900D01*
G01X1226403Y502900D02*
Y504290D01*
G01X1225793Y502290D02*
X1226403Y502900D01*
G01X1222470Y502290D02*
X1225793D01*
G01X1221860Y501680D02*
X1222470Y502290D01*
G01X1221860Y499919D02*
Y501680D01*
G01X1222616Y499163D02*
X1221860Y499919D01*
G01X1227408Y499163D02*
X1222616D01*
G01X1228033Y498538D02*
X1227408Y499163D01*
G01X1228033Y496544D02*
Y498538D01*
G01X1227452Y495963D02*
X1228033Y496544D01*
G01X1222364Y495963D02*
X1227452D01*
G01X1221486Y495085D02*
X1222364Y495963D01*
G01X1221486Y493500D02*
Y495085D01*
G01X1222266Y492720D02*
X1221486Y493500D01*
G01X1226708Y492720D02*
X1222266D01*
G01X1227974Y491454D02*
X1226708Y492720D01*
G01X1227974Y478001D02*
Y491454D01*
G01X1229100Y476875D02*
X1227974Y478001D01*
G01X1229100Y474801D02*
Y476875D01*
G01X1227974Y473675D02*
X1229100Y474801D01*
G01X1227974Y472510D02*
Y473675D01*
G01X1225476Y470012D02*
X1227974Y472510D01*
G01X1225476Y468976D02*
Y470012D01*
G01X1223731Y467231D02*
X1225476Y468976D01*
G01X1222695Y467231D02*
X1223731D01*
G01X1233334Y519862D02*
Y530049D01*
G01X1235039Y518157D02*
X1233334Y519862D01*
G01X1234374Y517492D02*
X1235039Y518157D01*
G01X1234374Y513657D02*
Y517492D01*
G01X1237274Y510757D02*
X1234374Y513657D01*
G01X1237274Y508462D02*
Y510757D01*
G01X1239800Y505936D02*
X1237274Y508462D01*
G01X1239800Y473057D02*
Y505936D01*
G01X1240644Y472213D02*
X1239800Y473057D01*
G01X1242244Y472213D02*
X1240644D01*
G01X1243000Y472969D02*
X1242244Y472213D01*
G01X1243000Y478721D02*
Y472969D01*
G01X1243844Y479565D02*
X1243000Y478721D01*
G01X1245444Y479565D02*
X1243844D01*
G01X1246200Y478809D02*
X1245444Y479565D01*
G01X1246200Y470663D02*
Y478809D01*
G01X1220000Y509100D02*
Y511081D01*
G01X1219074Y508174D02*
X1220000Y509100D01*
G01X1219074Y488200D02*
Y508174D01*
G01X1219874Y487400D02*
X1219074Y488200D01*
G01X1221474Y487400D02*
X1219874D01*
G01X1222274Y488200D02*
X1221474Y487400D01*
G01X1222274Y489803D02*
Y488200D01*
G01X1223074Y490603D02*
X1222274Y489803D01*
G01X1224674Y490603D02*
X1223074D01*
G01X1225474Y489803D02*
X1224674Y490603D01*
G01X1225474Y473546D02*
Y489803D01*
G01X1219774Y481000D02*
X1218974Y480200D01*
G01X1219774Y484000D02*
Y481000D01*
G01X1220574Y484800D02*
X1219774Y484000D01*
G01X1222174Y484800D02*
X1220574D01*
G01X1222974Y484000D02*
X1222174Y484800D01*
G01X1222974Y474739D02*
Y484000D01*
G01X1241300Y517725D02*
X1241732Y518157D01*
G01X1241300Y513381D02*
Y517725D01*
G01X1243774Y510907D02*
X1241300Y513381D01*
G01X1243774Y508726D02*
Y510907D01*
G01X1244800Y507700D02*
X1243774Y508726D01*
G01X1244800Y492558D02*
Y507700D01*
G01X1245633Y491725D02*
X1244800Y492558D01*
G01X1247233Y491725D02*
X1245633D01*
G01X1248000Y492492D02*
X1247233Y491725D01*
G01X1248000Y495218D02*
Y492492D01*
G01X1248822Y496040D02*
X1248000Y495218D01*
G01X1250386Y496040D02*
X1248822D01*
G01X1251200Y495226D02*
X1250386Y496040D01*
G01X1251200Y468592D02*
Y495226D01*
G01X1240027Y519862D02*
Y530049D01*
G01X1241732Y518157D02*
X1240027Y519862D01*
G01X1242804Y528899D02*
X1241732D01*
G01X1243504Y528199D02*
X1242804Y528899D01*
G01X1243504Y526925D02*
Y528199D01*
G01X1236111Y528899D02*
X1235039D01*
G01X1236811Y528199D02*
X1236111Y528899D01*
G01X1236811Y526925D02*
Y528199D01*
G01X1219886Y528300D02*
X1219287Y528899D01*
G01X1219886Y527100D02*
Y528300D01*
G01X1233334Y530049D02*
X1238385Y535100D01*
G01X1219787Y534700D02*
X1220953D01*
G01X1240027Y530049D02*
X1245078Y535100D01*
M02*
